G04 ================== begin FILE IDENTIFICATION RECORD ==================*
G04 Layout Name:  D:/<user>/Wistron_project/16369-sd/gbr/16369-sd.brd*
G04 Film Name:    16369-sd_X_Y*
G04 File Format:  Gerber RS274X*
G04 File Origin:  Cadence Allegro 16.5-S056*
G04 Origin Date:  Wed Mar 29 13:12:40 2017*
G04 *
G04 Layer:  BOARD GEOMETRY/PANEL_DRAWING*
G04 *
G04 Offset:    (0.00 0.00)*
G04 Mirror:    No*
G04 Mode:      Positive*
G04 Rotation:  0*
G04 FullContactRelief:  No*
G04 UndefLineWidth:     6.00*
G04 ================== end FILE IDENTIFICATION RECORD ====================*
%FSLAX35Y35*MOIN*%
%IR0*IPPOS*OFA0.00000B0.00000*MIA0B0*SFA1.00000B1.00000*%
%ADD10C,.006*%
G75*
%LPD*%
G75*
G54D10*
G01X-220799Y-295211D02*
Y-288912D01*
X-217807D01*
G01X-218909Y-291956D02*
X-220799D01*
G01X-217728Y-58990D02*
X-220878D01*
Y-52691D01*
X-217728D01*
G01X-218988Y-55735D02*
X-220878D01*
G01X-221035Y177230D02*
Y183529D01*
X-219461D01*
X-218831Y183214D01*
X-218358Y182794D01*
X-217964Y182164D01*
X-217650Y181429D01*
X-217571Y180379D01*
X-217650Y179330D01*
X-217964Y178595D01*
X-218358Y177965D01*
X-218831Y177545D01*
X-219461Y177230D01*
X-221035D01*
G01X-217571Y419225D02*
X-218043Y419540D01*
X-218594Y419750D01*
X-219224D01*
X-219933Y419435D01*
X-220484Y418910D01*
X-220878Y418280D01*
X-221193Y417230D01*
X-221271Y416286D01*
X-221114Y415341D01*
X-220878Y414711D01*
X-220405Y414081D01*
X-219854Y413661D01*
X-219303Y413451D01*
X-218752D01*
X-218201Y413661D01*
X-217728Y413976D01*
X-217335Y414396D01*
G01X-218673Y653031D02*
X-218358Y653345D01*
X-218122Y653870D01*
X-217964Y654605D01*
X-218122Y655235D01*
X-218437Y655655D01*
X-218988Y655970D01*
X-221114D01*
Y649671D01*
X-218516D01*
X-217964Y650091D01*
X-217650Y650721D01*
X-217492Y651456D01*
X-217650Y652190D01*
X-218122Y652820D01*
X-218673Y653031D01*
X-221114D01*
G01X-221271Y885892D02*
X-219303Y892191D01*
X-217335Y885892D01*
G01X-218043Y888097D02*
X-220563D01*
G01X-141350Y-365289D02*
Y-358990D01*
X-142295Y-360250D01*
G01Y-365289D02*
X-140405D01*
G01X-109577Y-22340D02*
X-110365Y-22602D01*
X-110955Y-23259D01*
X-111349Y-24046D01*
X-111644Y-25096D01*
X-111743Y-26277D01*
X-111644Y-27458D01*
X-111349Y-28508D01*
X-110955Y-29296D01*
X-110365Y-29952D01*
X-109577Y-30214D01*
X-108790Y-29952D01*
X-108199Y-29296D01*
X-107805Y-28508D01*
X-107510Y-27458D01*
X-107411Y-26277D01*
X-107510Y-25096D01*
X-107805Y-24046D01*
X-108199Y-23259D01*
X-108790Y-22602D01*
X-109577Y-22340D01*
G01X-101702Y-30476D02*
X-101899Y-30345D01*
Y-30083D01*
X-101702Y-29952D01*
X-101505Y-30083D01*
Y-30345D01*
X-101702Y-30476D01*
G01X-93827Y-22340D02*
X-94615Y-22602D01*
X-95205Y-23259D01*
X-95599Y-24046D01*
X-95894Y-25096D01*
X-95993Y-26277D01*
X-95894Y-27458D01*
X-95599Y-28508D01*
X-95205Y-29296D01*
X-94615Y-29952D01*
X-93827Y-30214D01*
X-93040Y-29952D01*
X-92449Y-29296D01*
X-92055Y-28508D01*
X-91760Y-27458D01*
X-91661Y-26277D01*
X-91760Y-25096D01*
X-92055Y-24046D01*
X-92449Y-23259D01*
X-93040Y-22602D01*
X-93827Y-22340D01*
G01X-85952D02*
X-86740Y-22602D01*
X-87330Y-23259D01*
X-87724Y-24046D01*
X-88019Y-25096D01*
X-88118Y-26277D01*
X-88019Y-27458D01*
X-87724Y-28508D01*
X-87330Y-29296D01*
X-86740Y-29952D01*
X-85952Y-30214D01*
X-85165Y-29952D01*
X-84574Y-29296D01*
X-84180Y-28508D01*
X-83885Y-27458D01*
X-83786Y-26277D01*
X-83885Y-25096D01*
X-84180Y-24046D01*
X-84574Y-23259D01*
X-85165Y-22602D01*
X-85952Y-22340D01*
G01X-106288Y-10548D02*
Y-5548D01*
X-104134D01*
G01X-104928Y-7965D02*
X-106288D01*
G01X-101811Y-7215D02*
Y-10548D01*
G01Y-5881D02*
X-101924Y-5798D01*
Y-5631D01*
X-101811Y-5548D01*
X-101698Y-5631D01*
Y-5798D01*
X-101811Y-5881D01*
G01X-97391Y-5548D02*
Y-10548D01*
G01Y-9798D02*
X-97618Y-10215D01*
X-97958Y-10465D01*
X-98354Y-10548D01*
X-98808Y-10381D01*
X-99148Y-9965D01*
X-99374Y-9465D01*
X-99431Y-8881D01*
X-99374Y-8298D01*
X-99148Y-7798D01*
X-98808Y-7381D01*
X-98354Y-7215D01*
X-97958Y-7298D01*
X-97674Y-7465D01*
X-97391Y-7798D01*
G01X-95974Y-7215D02*
Y-9548D01*
X-95748Y-10131D01*
X-95408Y-10465D01*
X-95011Y-10548D01*
X-94614Y-10465D01*
X-94274Y-10131D01*
X-94048Y-9548D01*
G01Y-10548D02*
Y-7215D01*
G01X-90704Y-7631D02*
X-91101Y-7298D01*
X-91441Y-7215D01*
X-91894Y-7381D01*
X-92234Y-7715D01*
X-92461Y-8298D01*
X-92518Y-8881D01*
X-92461Y-9465D01*
X-92234Y-9965D01*
X-91894Y-10381D01*
X-91441Y-10548D01*
X-91044Y-10381D01*
X-90704Y-10048D01*
G01X-88211Y-7215D02*
Y-10548D01*
G01Y-5881D02*
X-88324Y-5798D01*
Y-5631D01*
X-88211Y-5548D01*
X-88098Y-5631D01*
Y-5798D01*
X-88211Y-5881D01*
G01X-83791Y-10548D02*
Y-7215D01*
G01Y-7798D02*
X-84018Y-7465D01*
X-84358Y-7298D01*
X-84754Y-7215D01*
X-85151Y-7381D01*
X-85491Y-7715D01*
X-85718Y-8215D01*
X-85831Y-8881D01*
X-85718Y-9548D01*
X-85491Y-10048D01*
X-85151Y-10381D01*
X-84754Y-10548D01*
X-84358Y-10465D01*
X-84018Y-10215D01*
X-83791Y-9881D01*
G01X-81411Y-10548D02*
Y-5548D01*
G01X-76084Y-10548D02*
Y-5548D01*
X-74611Y-9715D01*
X-73138Y-5548D01*
Y-10548D01*
G01X-70191D02*
Y-7215D01*
G01Y-7798D02*
X-70418Y-7465D01*
X-70758Y-7298D01*
X-71154Y-7215D01*
X-71551Y-7381D01*
X-71891Y-7715D01*
X-72118Y-8215D01*
X-72231Y-8881D01*
X-72118Y-9548D01*
X-71891Y-10048D01*
X-71551Y-10381D01*
X-71154Y-10548D01*
X-70758Y-10465D01*
X-70418Y-10215D01*
X-70191Y-9881D01*
G01X-68604Y-10548D02*
Y-7215D01*
G01Y-7881D02*
X-68321Y-7548D01*
X-68038Y-7298D01*
X-67641Y-7215D01*
X-67358Y-7298D01*
X-67018Y-7548D01*
G01X-65374Y-10548D02*
Y-5548D01*
G01X-63561Y-7215D02*
X-65374Y-9131D01*
G01X-64638Y-8381D02*
X-63448Y-10548D01*
G01X-58461Y-7215D02*
X-56761Y-10548D01*
G01Y-7215D02*
X-58461Y-10548D01*
G01X-52058Y-9548D02*
X-51718Y-10131D01*
X-51264Y-10465D01*
X-50754Y-10548D01*
X-50301Y-10465D01*
X-49848Y-10048D01*
X-49564Y-9548D01*
X-49508Y-9048D01*
X-49621Y-8465D01*
X-50018Y-8048D01*
X-50414Y-7881D01*
X-50924D01*
G01X-50414D02*
X-50074Y-7631D01*
X-49791Y-7215D01*
X-49678Y-6715D01*
X-49791Y-6215D01*
X-50074Y-5798D01*
X-50584Y-5548D01*
X-51094Y-5631D01*
X-51604Y-5965D01*
G01X-118238Y360801D02*
X-117549Y360145D01*
X-116762Y359883D01*
X-115974Y360145D01*
X-115285Y360933D01*
X-114793Y362114D01*
X-114596Y363295D01*
Y364739D01*
X-114793Y365920D01*
X-115285Y366970D01*
X-115876Y367495D01*
X-116565Y367757D01*
X-117353Y367495D01*
X-117943Y366970D01*
X-118337Y366182D01*
X-118534Y365132D01*
X-118337Y364214D01*
X-117845Y363295D01*
X-117254Y362770D01*
X-116565Y362639D01*
X-115778Y362901D01*
X-115187Y363557D01*
X-114596Y364739D01*
G01X-108690Y359883D02*
X-108001Y360014D01*
X-107214Y360408D01*
X-106721Y361064D01*
X-106524Y361983D01*
X-106721Y362901D01*
X-107312Y363689D01*
X-108198Y364083D01*
X-109182D01*
X-109773Y364345D01*
X-110265Y365001D01*
X-110462Y365920D01*
X-110166Y366838D01*
X-109478Y367495D01*
X-108690Y367757D01*
X-107903Y367495D01*
X-107214Y366838D01*
X-106918Y365920D01*
X-107115Y365001D01*
X-107607Y364345D01*
X-108198Y364083D01*
X-109182D01*
X-110068Y363689D01*
X-110659Y362901D01*
X-110856Y361983D01*
X-110659Y361064D01*
X-110166Y360408D01*
X-109379Y360014D01*
X-108690Y359883D01*
G01X-100815Y359621D02*
X-101012Y359752D01*
Y360014D01*
X-100815Y360145D01*
X-100618Y360014D01*
Y359752D01*
X-100815Y359621D01*
G01X-93137Y359883D02*
X-92940Y361589D01*
X-92645Y363032D01*
X-92251Y364345D01*
X-91759Y365788D01*
X-90971Y367757D01*
X-94909D01*
G01X-85065D02*
X-85853Y367495D01*
X-86443Y366838D01*
X-86837Y366051D01*
X-87132Y365001D01*
X-87231Y363820D01*
X-87132Y362639D01*
X-86837Y361589D01*
X-86443Y360801D01*
X-85853Y360145D01*
X-85065Y359883D01*
X-84278Y360145D01*
X-83687Y360801D01*
X-83293Y361589D01*
X-82998Y362639D01*
X-82899Y363820D01*
X-82998Y365001D01*
X-83293Y366051D01*
X-83687Y366838D01*
X-84278Y367495D01*
X-85065Y367757D01*
G01X-118238Y351686D02*
X-117549Y351030D01*
X-116762Y350768D01*
X-115974Y351030D01*
X-115285Y351818D01*
X-114793Y352999D01*
X-114596Y354180D01*
Y355624D01*
X-114793Y356805D01*
X-115285Y357855D01*
X-115876Y358380D01*
X-116565Y358642D01*
X-117353Y358380D01*
X-117943Y357855D01*
X-118337Y357067D01*
X-118534Y356017D01*
X-118337Y355099D01*
X-117845Y354180D01*
X-117254Y353655D01*
X-116565Y353524D01*
X-115778Y353786D01*
X-115187Y354442D01*
X-114596Y355624D01*
G01X-110560Y354049D02*
X-109871Y354968D01*
X-109281Y355492D01*
X-108493Y355755D01*
X-107804Y355492D01*
X-107312Y354968D01*
X-106918Y354180D01*
X-106820Y353261D01*
X-106918Y352474D01*
X-107312Y351686D01*
X-107903Y351030D01*
X-108591Y350768D01*
X-109379Y351030D01*
X-110068Y351818D01*
X-110462Y352999D01*
X-110560Y354311D01*
X-110363Y356017D01*
X-110068Y356936D01*
X-109576Y357855D01*
X-108887Y358511D01*
X-108198Y358642D01*
X-107509Y358380D01*
X-107017Y357723D01*
G01X-100815Y350506D02*
X-101012Y350637D01*
Y350899D01*
X-100815Y351030D01*
X-100618Y350899D01*
Y350637D01*
X-100815Y350506D01*
G01X-93137Y350768D02*
X-92940Y352474D01*
X-92645Y353917D01*
X-92251Y355230D01*
X-91759Y356673D01*
X-90971Y358642D01*
X-94909D01*
G01X-85065D02*
X-85853Y358380D01*
X-86443Y357723D01*
X-86837Y356936D01*
X-87132Y355886D01*
X-87231Y354705D01*
X-87132Y353524D01*
X-86837Y352474D01*
X-86443Y351686D01*
X-85853Y351030D01*
X-85065Y350768D01*
X-84278Y351030D01*
X-83687Y351686D01*
X-83293Y352474D01*
X-82998Y353524D01*
X-82899Y354705D01*
X-82998Y355886D01*
X-83293Y356936D01*
X-83687Y357723D01*
X-84278Y358380D01*
X-85065Y358642D01*
G01X-124562Y738656D02*
Y746530D01*
X-125743Y744955D01*
G01Y738656D02*
X-123381D01*
G01X-118360Y739574D02*
X-117671Y738918D01*
X-116884Y738656D01*
X-116096Y738918D01*
X-115407Y739706D01*
X-114915Y740887D01*
X-114718Y742068D01*
Y743512D01*
X-114915Y744693D01*
X-115407Y745743D01*
X-115998Y746268D01*
X-116687Y746530D01*
X-117475Y746268D01*
X-118065Y745743D01*
X-118459Y744955D01*
X-118656Y743905D01*
X-118459Y742987D01*
X-117967Y742068D01*
X-117376Y741543D01*
X-116687Y741412D01*
X-115900Y741674D01*
X-115309Y742330D01*
X-114718Y743512D01*
G01X-110978Y739837D02*
X-110387Y739181D01*
X-109698Y738787D01*
X-108812Y738656D01*
X-107926Y738918D01*
X-107237Y739443D01*
X-106745Y740362D01*
X-106646Y741412D01*
X-106843Y742462D01*
X-107336Y743118D01*
X-108025Y743643D01*
X-108713Y743774D01*
X-109403Y743643D01*
X-110288Y743118D01*
X-109993Y746530D01*
X-107336D01*
G01X-100937Y738394D02*
X-101134Y738525D01*
Y738787D01*
X-100937Y738918D01*
X-100740Y738787D01*
Y738525D01*
X-100937Y738394D01*
G01X-91881Y738656D02*
Y746530D01*
X-95523Y740887D01*
X-90601D01*
G01X-85187Y746530D02*
X-85975Y746268D01*
X-86565Y745611D01*
X-86959Y744824D01*
X-87254Y743774D01*
X-87353Y742593D01*
X-87254Y741412D01*
X-86959Y740362D01*
X-86565Y739574D01*
X-85975Y738918D01*
X-85187Y738656D01*
X-84400Y738918D01*
X-83809Y739574D01*
X-83415Y740362D01*
X-83120Y741412D01*
X-83021Y742593D01*
X-83120Y743774D01*
X-83415Y744824D01*
X-83809Y745611D01*
X-84400Y746268D01*
X-85187Y746530D01*
G01X-141350Y995341D02*
Y1001640D01*
X-142295Y1000380D01*
G01Y995341D02*
X-140405D01*
G01X-9055Y784179D02*
X-8399Y784770D01*
X-8005Y785459D01*
X-7874Y786345D01*
X-8136Y787231D01*
X-8661Y787920D01*
X-9580Y788412D01*
X-10630Y788511D01*
X-11680Y788314D01*
X-12336Y787821D01*
X-12861Y787132D01*
X-12992Y786444D01*
X-12861Y785754D01*
X-12336Y784869D01*
X-15748Y785164D01*
Y787821D01*
G01X-7612Y794220D02*
X-7743Y794023D01*
X-8005D01*
X-8136Y794220D01*
X-8005Y794417D01*
X-7743D01*
X-7612Y794220D01*
G01X-15748Y802095D02*
X-15486Y801307D01*
X-14829Y800717D01*
X-14042Y800323D01*
X-12992Y800028D01*
X-11811Y799929D01*
X-10630Y800028D01*
X-9580Y800323D01*
X-8792Y800717D01*
X-8136Y801307D01*
X-7874Y802095D01*
X-8136Y802882D01*
X-8792Y803473D01*
X-9580Y803867D01*
X-10630Y804162D01*
X-11811Y804261D01*
X-12992Y804162D01*
X-14042Y803867D01*
X-14829Y803473D01*
X-15486Y802882D01*
X-15748Y802095D01*
G01Y809970D02*
X-15486Y809182D01*
X-14829Y808592D01*
X-14042Y808198D01*
X-12992Y807903D01*
X-11811Y807804D01*
X-10630Y807903D01*
X-9580Y808198D01*
X-8792Y808592D01*
X-8136Y809182D01*
X-7874Y809970D01*
X-8136Y810757D01*
X-8792Y811348D01*
X-9580Y811742D01*
X-10630Y812037D01*
X-11811Y812136D01*
X-12992Y812037D01*
X-14042Y811742D01*
X-14829Y811348D01*
X-15486Y810757D01*
X-15748Y809970D01*
G01X-35433Y786345D02*
X-35171Y785557D01*
X-34514Y784967D01*
X-33727Y784573D01*
X-32677Y784278D01*
X-31496Y784179D01*
X-30315Y784278D01*
X-29265Y784573D01*
X-28477Y784967D01*
X-27821Y785557D01*
X-27559Y786345D01*
X-27821Y787132D01*
X-28477Y787723D01*
X-29265Y788117D01*
X-30315Y788412D01*
X-31496Y788511D01*
X-32677Y788412D01*
X-33727Y788117D01*
X-34514Y787723D01*
X-35171Y787132D01*
X-35433Y786345D01*
G01X-27297Y794220D02*
X-27428Y794023D01*
X-27690D01*
X-27821Y794220D01*
X-27690Y794417D01*
X-27428D01*
X-27297Y794220D01*
G01X-35433Y802095D02*
X-35171Y801307D01*
X-34514Y800717D01*
X-33727Y800323D01*
X-32677Y800028D01*
X-31496Y799929D01*
X-30315Y800028D01*
X-29265Y800323D01*
X-28477Y800717D01*
X-27821Y801307D01*
X-27559Y802095D01*
X-27821Y802882D01*
X-28477Y803473D01*
X-29265Y803867D01*
X-30315Y804162D01*
X-31496Y804261D01*
X-32677Y804162D01*
X-33727Y803867D01*
X-34514Y803473D01*
X-35171Y802882D01*
X-35433Y802095D01*
G01Y809970D02*
X-35171Y809182D01*
X-34514Y808592D01*
X-33727Y808198D01*
X-32677Y807903D01*
X-31496Y807804D01*
X-30315Y807903D01*
X-29265Y808198D01*
X-28477Y808592D01*
X-27821Y809182D01*
X-27559Y809970D01*
X-27821Y810757D01*
X-28477Y811348D01*
X-29265Y811742D01*
X-30315Y812037D01*
X-31496Y812136D01*
X-32677Y812037D01*
X-33727Y811742D01*
X-34514Y811348D01*
X-35171Y810757D01*
X-35433Y809970D01*
G01X40382Y-360040D02*
X40854Y-359410D01*
X41406Y-359095D01*
X42036Y-358990D01*
X42823Y-359200D01*
X43374Y-359725D01*
X43531Y-360355D01*
X43453Y-360985D01*
X43138Y-361510D01*
X41563Y-362559D01*
X40854Y-363294D01*
X40382Y-364344D01*
X40225Y-365289D01*
X43531D01*
G01X40382Y1000590D02*
X40854Y1001220D01*
X41406Y1001535D01*
X42036Y1001640D01*
X42823Y1001430D01*
X43374Y1000905D01*
X43531Y1000275D01*
X43453Y999645D01*
X43138Y999120D01*
X41563Y998071D01*
X40854Y997336D01*
X40382Y996286D01*
X40225Y995341D01*
X43531D01*
G01X114546Y41881D02*
Y30070D01*
G01X111150Y41881D02*
X117942D01*
G01X114546Y430464D02*
Y418653D01*
G01X111150Y430464D02*
X117942D01*
G01X213374Y-364029D02*
X213846Y-364764D01*
X214476Y-365184D01*
X215185Y-365289D01*
X215815Y-365184D01*
X216445Y-364659D01*
X216838Y-364029D01*
X216917Y-363399D01*
X216759Y-362665D01*
X216208Y-362140D01*
X215657Y-361929D01*
X214948D01*
G01X215657D02*
X216130Y-361615D01*
X216523Y-361090D01*
X216681Y-360460D01*
X216523Y-359830D01*
X216130Y-359305D01*
X215421Y-358990D01*
X214712Y-359095D01*
X214004Y-359515D01*
G01X213374Y996601D02*
X213846Y995866D01*
X214476Y995446D01*
X215185Y995341D01*
X215815Y995446D01*
X216445Y995971D01*
X216838Y996601D01*
X216917Y997231D01*
X216759Y997965D01*
X216208Y998490D01*
X215657Y998701D01*
X214948D01*
G01X215657D02*
X216130Y999015D01*
X216523Y999540D01*
X216681Y1000170D01*
X216523Y1000800D01*
X216130Y1001325D01*
X215421Y1001640D01*
X214712Y1001535D01*
X214004Y1001115D01*
G01X241207Y784475D02*
X240288Y785164D01*
X239764Y785754D01*
X239501Y786542D01*
X239764Y787231D01*
X240288Y787723D01*
X241076Y788117D01*
X241995Y788215D01*
X242782Y788117D01*
X243570Y787723D01*
X244226Y787132D01*
X244488Y786444D01*
X244226Y785656D01*
X243438Y784967D01*
X242257Y784573D01*
X240945Y784475D01*
X239239Y784672D01*
X238320Y784967D01*
X237401Y785459D01*
X236745Y786148D01*
X236614Y786837D01*
X236876Y787526D01*
X237533Y788018D01*
G01X243570Y792547D02*
X244226Y793236D01*
X244488Y794023D01*
X244226Y794811D01*
X243438Y795500D01*
X242257Y795992D01*
X241076Y796189D01*
X239632D01*
X238451Y795992D01*
X237401Y795500D01*
X236876Y794909D01*
X236614Y794220D01*
X236876Y793432D01*
X237401Y792842D01*
X238189Y792448D01*
X239239Y792251D01*
X240157Y792448D01*
X241076Y792940D01*
X241601Y793531D01*
X241732Y794220D01*
X241470Y795007D01*
X240814Y795598D01*
X239632Y796189D01*
G01X244750Y802095D02*
X244619Y801898D01*
X244357D01*
X244226Y802095D01*
X244357Y802292D01*
X244619D01*
X244750Y802095D01*
G01X244488Y809970D02*
X236614D01*
X238189Y808789D01*
G01X244488D02*
Y811151D01*
G01X236614Y817845D02*
X236876Y817057D01*
X237533Y816467D01*
X238320Y816073D01*
X239370Y815778D01*
X240551Y815679D01*
X241732Y815778D01*
X242782Y816073D01*
X243570Y816467D01*
X244226Y817057D01*
X244488Y817845D01*
X244226Y818632D01*
X243570Y819223D01*
X242782Y819617D01*
X241732Y819912D01*
X240551Y820011D01*
X239370Y819912D01*
X238320Y819617D01*
X237533Y819223D01*
X236876Y818632D01*
X236614Y817845D01*
G01X300739Y-35624D02*
X301526Y-36280D01*
X302412Y-36674D01*
X303200D01*
X303987Y-36280D01*
X304578Y-35624D01*
X304873Y-34705D01*
X304676Y-33787D01*
X304184Y-33000D01*
X303298Y-32474D01*
X302117Y-32212D01*
X301428Y-31687D01*
X301133Y-30769D01*
X301330Y-29850D01*
X301822Y-29194D01*
X302511Y-28800D01*
X303200D01*
X303889Y-29062D01*
X304479Y-29719D01*
G01X309205Y-33131D02*
X312354D01*
X312059Y-32212D01*
X311567Y-31687D01*
X310878Y-31425D01*
X310189Y-31556D01*
X309598Y-31950D01*
X309205Y-32868D01*
X309008Y-33656D01*
Y-34443D01*
X309205Y-35231D01*
X309697Y-36018D01*
X310287Y-36543D01*
X310976Y-36674D01*
X311665Y-36412D01*
X312354Y-35624D01*
G01X317178Y-36674D02*
Y-31425D01*
G01Y-32474D02*
X317670Y-31950D01*
X318162Y-31556D01*
X318851Y-31425D01*
X319343Y-31556D01*
X319934Y-31950D01*
G01X326431Y-31425D02*
Y-36674D01*
G01Y-29325D02*
X326234Y-29194D01*
Y-28931D01*
X326431Y-28800D01*
X326628Y-28931D01*
Y-29194D01*
X326431Y-29325D01*
G01X332830Y-33131D02*
X335979D01*
X335684Y-32212D01*
X335192Y-31687D01*
X334503Y-31425D01*
X333814Y-31556D01*
X333223Y-31950D01*
X332830Y-32868D01*
X332633Y-33656D01*
Y-34443D01*
X332830Y-35231D01*
X333322Y-36018D01*
X333912Y-36543D01*
X334601Y-36674D01*
X335290Y-36412D01*
X335979Y-35624D01*
G01X340705Y-35756D02*
X341197Y-36280D01*
X341886Y-36674D01*
X342476D01*
X343067Y-36412D01*
X343461Y-36018D01*
X343657Y-35493D01*
X343559Y-34705D01*
X343165Y-34312D01*
X341393Y-33525D01*
X341000Y-32606D01*
X341197Y-31950D01*
X341590Y-31556D01*
X342181Y-31425D01*
X342772Y-31556D01*
X343362Y-31950D01*
G01X356258Y-36674D02*
Y-31425D01*
G01Y-32737D02*
X356651Y-32081D01*
X357242Y-31556D01*
X358030Y-31425D01*
X358718Y-31556D01*
X359309Y-32081D01*
X359604Y-33000D01*
Y-36674D01*
G01X364133Y-31425D02*
Y-35099D01*
X364526Y-36018D01*
X365117Y-36543D01*
X365806Y-36674D01*
X366495Y-36543D01*
X367086Y-36018D01*
X367479Y-35099D01*
G01Y-36674D02*
Y-31425D01*
G01X370728Y-36674D02*
Y-31425D01*
G01Y-32868D02*
X371023Y-32212D01*
X371515Y-31687D01*
X372205Y-31425D01*
X372893Y-31687D01*
X373386Y-32212D01*
X373681Y-32868D01*
Y-36674D01*
G01Y-32868D02*
X373976Y-32212D01*
X374468Y-31687D01*
X375157Y-31425D01*
X375847Y-31687D01*
X376339Y-32212D01*
X376634Y-33000D01*
Y-36674D01*
G01X379784D02*
Y-28800D01*
G01Y-32737D02*
X380276Y-31950D01*
X380867Y-31556D01*
X381457Y-31425D01*
X382343Y-31687D01*
X382934Y-32212D01*
X383328Y-33131D01*
Y-34181D01*
X383131Y-35231D01*
X382737Y-36018D01*
X382048Y-36543D01*
X381457Y-36674D01*
X380867Y-36543D01*
X380276Y-36149D01*
X379784Y-35493D01*
G01X387955Y-33131D02*
X391104D01*
X390809Y-32212D01*
X390317Y-31687D01*
X389628Y-31425D01*
X388939Y-31556D01*
X388348Y-31950D01*
X387955Y-32868D01*
X387758Y-33656D01*
Y-34443D01*
X387955Y-35231D01*
X388447Y-36018D01*
X389037Y-36543D01*
X389726Y-36674D01*
X390415Y-36412D01*
X391104Y-35624D01*
G01X395928Y-36674D02*
Y-31425D01*
G01Y-32474D02*
X396420Y-31950D01*
X396912Y-31556D01*
X397601Y-31425D01*
X398093Y-31556D01*
X398684Y-31950D01*
G01X414828Y-36674D02*
Y-31425D01*
G01Y-32343D02*
X414434Y-31818D01*
X413843Y-31556D01*
X413155Y-31425D01*
X412465Y-31687D01*
X411875Y-32212D01*
X411481Y-33000D01*
X411284Y-34049D01*
X411481Y-35099D01*
X411875Y-35887D01*
X412465Y-36412D01*
X413155Y-36674D01*
X413843Y-36543D01*
X414434Y-36149D01*
X414828Y-35624D01*
G01X419258Y-36674D02*
Y-31425D01*
G01Y-32737D02*
X419651Y-32081D01*
X420242Y-31556D01*
X421030Y-31425D01*
X421718Y-31556D01*
X422309Y-32081D01*
X422604Y-33000D01*
Y-36674D01*
G01X430578Y-28800D02*
Y-36674D01*
G01Y-35493D02*
X430184Y-36149D01*
X429593Y-36543D01*
X428905Y-36674D01*
X428117Y-36412D01*
X427526Y-35756D01*
X427133Y-34968D01*
X427034Y-34049D01*
X427133Y-33131D01*
X427526Y-32343D01*
X428117Y-31687D01*
X428905Y-31425D01*
X429593Y-31556D01*
X430086Y-31818D01*
X430578Y-32343D01*
G01X443178Y-36674D02*
Y-31425D01*
G01Y-32474D02*
X443670Y-31950D01*
X444162Y-31556D01*
X444851Y-31425D01*
X445343Y-31556D01*
X445934Y-31950D01*
G01X450955Y-33131D02*
X454104D01*
X453809Y-32212D01*
X453317Y-31687D01*
X452628Y-31425D01*
X451939Y-31556D01*
X451348Y-31950D01*
X450955Y-32868D01*
X450758Y-33656D01*
Y-34443D01*
X450955Y-35231D01*
X451447Y-36018D01*
X452037Y-36543D01*
X452726Y-36674D01*
X453415Y-36412D01*
X454104Y-35624D01*
G01X459715Y-36674D02*
Y-29981D01*
X459912Y-29325D01*
X460306Y-28931D01*
X460897Y-28800D01*
X461487Y-29062D01*
X461782Y-29719D01*
G01X460601Y-31950D02*
X458633D01*
G01X466705Y-33131D02*
X469854D01*
X469559Y-32212D01*
X469067Y-31687D01*
X468378Y-31425D01*
X467689Y-31556D01*
X467098Y-31950D01*
X466705Y-32868D01*
X466508Y-33656D01*
Y-34443D01*
X466705Y-35231D01*
X467197Y-36018D01*
X467787Y-36543D01*
X468476Y-36674D01*
X469165Y-36412D01*
X469854Y-35624D01*
G01X474678Y-36674D02*
Y-31425D01*
G01Y-32474D02*
X475170Y-31950D01*
X475662Y-31556D01*
X476351Y-31425D01*
X476843Y-31556D01*
X477434Y-31950D01*
G01X482455Y-33131D02*
X485604D01*
X485309Y-32212D01*
X484817Y-31687D01*
X484128Y-31425D01*
X483439Y-31556D01*
X482848Y-31950D01*
X482455Y-32868D01*
X482258Y-33656D01*
Y-34443D01*
X482455Y-35231D01*
X482947Y-36018D01*
X483537Y-36543D01*
X484226Y-36674D01*
X484915Y-36412D01*
X485604Y-35624D01*
G01X490133Y-36674D02*
Y-31425D01*
G01Y-32737D02*
X490526Y-32081D01*
X491117Y-31556D01*
X491905Y-31425D01*
X492593Y-31556D01*
X493184Y-32081D01*
X493479Y-33000D01*
Y-36674D01*
G01X501256Y-32081D02*
X500567Y-31556D01*
X499976Y-31425D01*
X499189Y-31687D01*
X498598Y-32212D01*
X498205Y-33131D01*
X498106Y-34049D01*
X498205Y-34968D01*
X498598Y-35756D01*
X499189Y-36412D01*
X499976Y-36674D01*
X500665Y-36412D01*
X501256Y-35887D01*
G01X506080Y-33131D02*
X509229D01*
X508934Y-32212D01*
X508442Y-31687D01*
X507753Y-31425D01*
X507064Y-31556D01*
X506473Y-31950D01*
X506080Y-32868D01*
X505883Y-33656D01*
Y-34443D01*
X506080Y-35231D01*
X506572Y-36018D01*
X507162Y-36543D01*
X507851Y-36674D01*
X508540Y-36412D01*
X509229Y-35624D01*
G01X523306Y-36674D02*
X522715Y-36543D01*
X522125Y-36018D01*
X521731Y-35099D01*
X521534Y-34049D01*
X521731Y-33000D01*
X522125Y-32081D01*
X522715Y-31556D01*
X523306Y-31425D01*
X523897Y-31556D01*
X524487Y-32081D01*
X524881Y-33000D01*
X524979Y-34049D01*
X524881Y-35099D01*
X524487Y-36018D01*
X523897Y-36543D01*
X523306Y-36674D01*
G01X529508D02*
Y-31425D01*
G01Y-32737D02*
X529901Y-32081D01*
X530492Y-31556D01*
X531280Y-31425D01*
X531968Y-31556D01*
X532559Y-32081D01*
X532854Y-33000D01*
Y-36674D01*
G01X539056D02*
Y-28800D01*
G01X544864Y-39036D02*
X545455Y-39299D01*
X546242Y-39036D01*
X546734Y-38511D01*
X547128Y-37855D01*
X547718Y-35756D01*
X548998Y-31425D01*
G01X545848D02*
X547718Y-35756D01*
G01X554806Y-36936D02*
X554609Y-36805D01*
Y-36543D01*
X554806Y-36412D01*
X555003Y-36543D01*
Y-36805D01*
X554806Y-36936D01*
G01X366557Y286071D02*
Y297882D01*
G01X369953Y286071D02*
X363161D01*
G01X366557Y674654D02*
Y686465D01*
G01X369953Y674654D02*
X363161D01*
G01X389280Y-365289D02*
Y-358990D01*
X386367Y-363504D01*
X390303D01*
G01X389280Y995341D02*
Y1001640D01*
X386367Y997126D01*
X390303D01*
G01X516536Y785220D02*
X508662D01*
X510237Y784039D01*
G01X516536D02*
Y786401D01*
G01X514961Y790929D02*
X515880Y791520D01*
X516405Y792307D01*
X516536Y793194D01*
X516405Y793981D01*
X515749Y794768D01*
X514961Y795261D01*
X514174Y795359D01*
X513255Y795162D01*
X512599Y794473D01*
X512336Y793784D01*
Y792898D01*
G01Y793784D02*
X511943Y794375D01*
X511287Y794867D01*
X510499Y795064D01*
X509712Y794867D01*
X509056Y794375D01*
X508662Y793489D01*
X508793Y792603D01*
X509318Y791717D01*
G01X516536Y800970D02*
X516405Y801659D01*
X516011Y802446D01*
X515355Y802939D01*
X514436Y803136D01*
X513518Y802939D01*
X512730Y802348D01*
X512336Y801462D01*
Y800478D01*
X512074Y799887D01*
X511418Y799395D01*
X510499Y799198D01*
X509581Y799494D01*
X508924Y800182D01*
X508662Y800970D01*
X508924Y801757D01*
X509581Y802446D01*
X510499Y802742D01*
X511418Y802545D01*
X512074Y802053D01*
X512336Y801462D01*
Y800478D01*
X512730Y799592D01*
X513518Y799001D01*
X514436Y798804D01*
X515355Y799001D01*
X516011Y799494D01*
X516405Y800281D01*
X516536Y800970D01*
G01X516798Y808845D02*
X516667Y808648D01*
X516405D01*
X516274Y808845D01*
X516405Y809042D01*
X516667D01*
X516798Y808845D01*
G01X509974Y814850D02*
X509187Y815440D01*
X508793Y816129D01*
X508662Y816917D01*
X508924Y817901D01*
X509581Y818590D01*
X510368Y818787D01*
X511156Y818689D01*
X511812Y818295D01*
X513124Y816326D01*
X514043Y815440D01*
X515355Y814850D01*
X516536Y814653D01*
Y818787D01*
G01X508662Y824595D02*
X508924Y823807D01*
X509581Y823217D01*
X510368Y822823D01*
X511418Y822528D01*
X512599Y822429D01*
X513780Y822528D01*
X514830Y822823D01*
X515618Y823217D01*
X516274Y823807D01*
X516536Y824595D01*
X516274Y825382D01*
X515618Y825973D01*
X514830Y826367D01*
X513780Y826662D01*
X512599Y826761D01*
X511418Y826662D01*
X510368Y826367D01*
X509581Y825973D01*
X508924Y825382D01*
X508662Y824595D01*
G01X496851Y786345D02*
X488977D01*
X490552Y785164D01*
G01X496851D02*
Y787526D01*
G01X495276Y792054D02*
X496195Y792645D01*
X496720Y793432D01*
X496851Y794319D01*
X496720Y795106D01*
X496064Y795893D01*
X495276Y796386D01*
X494489Y796484D01*
X493570Y796287D01*
X492914Y795598D01*
X492651Y794909D01*
Y794023D01*
G01Y794909D02*
X492258Y795500D01*
X491602Y795992D01*
X490814Y796189D01*
X490027Y795992D01*
X489371Y795500D01*
X488977Y794614D01*
X489108Y793728D01*
X489633Y792842D01*
G01X495276Y799929D02*
X496195Y800520D01*
X496720Y801307D01*
X496851Y802194D01*
X496720Y802981D01*
X496064Y803768D01*
X495276Y804261D01*
X494489Y804359D01*
X493570Y804162D01*
X492914Y803473D01*
X492651Y802784D01*
Y801898D01*
G01Y802784D02*
X492258Y803375D01*
X491602Y803867D01*
X490814Y804064D01*
X490027Y803867D01*
X489371Y803375D01*
X488977Y802489D01*
X489108Y801603D01*
X489633Y800717D01*
G01X497113Y809970D02*
X496982Y809773D01*
X496720D01*
X496589Y809970D01*
X496720Y810167D01*
X496982D01*
X497113Y809970D01*
G01X490289Y815975D02*
X489502Y816565D01*
X489108Y817254D01*
X488977Y818042D01*
X489239Y819026D01*
X489896Y819715D01*
X490683Y819912D01*
X491471Y819814D01*
X492127Y819420D01*
X493439Y817451D01*
X494358Y816565D01*
X495670Y815975D01*
X496851Y815778D01*
Y819912D01*
G01X488977Y825720D02*
X489239Y824932D01*
X489896Y824342D01*
X490683Y823948D01*
X491733Y823653D01*
X492914Y823554D01*
X494095Y823653D01*
X495145Y823948D01*
X495933Y824342D01*
X496589Y824932D01*
X496851Y825720D01*
X496589Y826507D01*
X495933Y827098D01*
X495145Y827492D01*
X494095Y827787D01*
X492914Y827886D01*
X491733Y827787D01*
X490683Y827492D01*
X489896Y827098D01*
X489239Y826507D01*
X488977Y825720D01*
G01X559831Y-364344D02*
X560303Y-364869D01*
X560854Y-365184D01*
X561563Y-365289D01*
X562272Y-365079D01*
X562823Y-364659D01*
X563216Y-363924D01*
X563295Y-363084D01*
X563138Y-362245D01*
X562744Y-361720D01*
X562193Y-361300D01*
X561642Y-361195D01*
X561091Y-361300D01*
X560382Y-361720D01*
X560618Y-358990D01*
X562744D01*
G01X559831Y996286D02*
X560303Y995761D01*
X560854Y995446D01*
X561563Y995341D01*
X562272Y995551D01*
X562823Y995971D01*
X563216Y996706D01*
X563295Y997546D01*
X563138Y998385D01*
X562744Y998910D01*
X562193Y999330D01*
X561642Y999435D01*
X561091Y999330D01*
X560382Y998910D01*
X560618Y1001640D01*
X562744D01*
G01X674960Y-250810D02*
X673460Y-249810D01*
X671710Y-249143D01*
X669710D01*
X667460Y-250143D01*
X665710Y-251810D01*
X664460Y-253810D01*
X663460Y-257143D01*
X663210Y-260143D01*
X663710Y-263143D01*
X664460Y-265143D01*
X665960Y-267143D01*
X667710Y-268476D01*
X669460Y-269143D01*
X671210D01*
X672960Y-268476D01*
X674460Y-267477D01*
X675710Y-266144D01*
G01X685960Y-269143D02*
Y-255810D01*
G01Y-258476D02*
X687210Y-257143D01*
X688460Y-256143D01*
X690210Y-255810D01*
X691460Y-256143D01*
X692960Y-257143D01*
G01X705710Y-260143D02*
X713710D01*
X712960Y-257810D01*
X711710Y-256477D01*
X709960Y-255810D01*
X708210Y-256143D01*
X706710Y-257143D01*
X705710Y-259477D01*
X705210Y-261477D01*
Y-263476D01*
X705710Y-265477D01*
X706960Y-267477D01*
X708460Y-268810D01*
X710210Y-269143D01*
X711960Y-268476D01*
X713710Y-266477D01*
G01X733960Y-269143D02*
Y-255810D01*
G01Y-258143D02*
X732960Y-256810D01*
X731460Y-256143D01*
X729710Y-255810D01*
X727960Y-256477D01*
X726460Y-257810D01*
X725460Y-259810D01*
X724960Y-262477D01*
X725460Y-265143D01*
X726460Y-267143D01*
X727960Y-268476D01*
X729710Y-269143D01*
X731460Y-268810D01*
X732960Y-267810D01*
X733960Y-266477D01*
G01X749460Y-249143D02*
Y-269143D01*
G01X745960Y-255810D02*
X752960D01*
G01X765710Y-260143D02*
X773710D01*
X772960Y-257810D01*
X771710Y-256477D01*
X769960Y-255810D01*
X768210Y-256143D01*
X766710Y-257143D01*
X765710Y-259477D01*
X765210Y-261477D01*
Y-263476D01*
X765710Y-265477D01*
X766960Y-267477D01*
X768460Y-268810D01*
X770210Y-269143D01*
X771960Y-268476D01*
X773710Y-266477D01*
G01X793960Y-249143D02*
Y-269143D01*
G01Y-266144D02*
X792960Y-267810D01*
X791460Y-268810D01*
X789710Y-269143D01*
X787710Y-268476D01*
X786210Y-266810D01*
X785210Y-264810D01*
X784960Y-262477D01*
X785210Y-260143D01*
X786210Y-258143D01*
X787710Y-256477D01*
X789710Y-255810D01*
X791460Y-256143D01*
X792710Y-256810D01*
X793960Y-258143D01*
G01X660508Y-200235D02*
X666758Y-220235D01*
X673008Y-200235D01*
G01X683008Y-211235D02*
X691008D01*
X690258Y-208902D01*
X689008Y-207569D01*
X687258Y-206902D01*
X685508Y-207235D01*
X684008Y-208235D01*
X683008Y-210569D01*
X682508Y-212569D01*
Y-214568D01*
X683008Y-216569D01*
X684258Y-218569D01*
X685758Y-219902D01*
X687508Y-220235D01*
X689258Y-219568D01*
X691008Y-217569D01*
G01X703258Y-220235D02*
Y-206902D01*
G01Y-209568D02*
X704508Y-208235D01*
X705758Y-207235D01*
X707508Y-206902D01*
X708758Y-207235D01*
X710258Y-208235D01*
G01X723008Y-217902D02*
X724258Y-219235D01*
X726008Y-220235D01*
X727508D01*
X729008Y-219568D01*
X730008Y-218569D01*
X730508Y-217236D01*
X730258Y-215235D01*
X729258Y-214235D01*
X724758Y-212235D01*
X723758Y-209901D01*
X724258Y-208235D01*
X725258Y-207235D01*
X726758Y-206902D01*
X728258Y-207235D01*
X729758Y-208235D01*
G01X746758Y-206902D02*
Y-220235D01*
G01Y-201569D02*
X746258Y-201235D01*
Y-200568D01*
X746758Y-200235D01*
X747258Y-200568D01*
Y-201235D01*
X746758Y-201569D01*
G01X766758Y-220235D02*
X765258Y-219902D01*
X763758Y-218569D01*
X762758Y-216235D01*
X762258Y-213569D01*
X762758Y-210902D01*
X763758Y-208568D01*
X765258Y-207235D01*
X766758Y-206902D01*
X768258Y-207235D01*
X769758Y-208568D01*
X770758Y-210902D01*
X771008Y-213569D01*
X770758Y-216235D01*
X769758Y-218569D01*
X768258Y-219902D01*
X766758Y-220235D01*
G01X782508D02*
Y-206902D01*
G01Y-210235D02*
X783508Y-208568D01*
X785008Y-207235D01*
X787008Y-206902D01*
X788758Y-207235D01*
X790258Y-208568D01*
X791008Y-210902D01*
Y-220235D01*
G01X664460Y-176222D02*
Y-156222D01*
X670460D01*
X672460Y-157222D01*
X673960Y-159555D01*
X674460Y-162222D01*
X673960Y-164889D01*
X672710Y-166889D01*
X670460Y-167889D01*
X664460D01*
G01X694960Y-157889D02*
X693460Y-156889D01*
X691710Y-156222D01*
X689710D01*
X687460Y-157222D01*
X685710Y-158889D01*
X684460Y-160889D01*
X683460Y-164222D01*
X683210Y-167222D01*
X683710Y-170222D01*
X684460Y-172222D01*
X685960Y-174222D01*
X687710Y-175555D01*
X689460Y-176222D01*
X691210D01*
X692960Y-175555D01*
X694460Y-174556D01*
X695710Y-173223D01*
G01X711460Y-165555D02*
X712460Y-164555D01*
X713210Y-162889D01*
X713710Y-160555D01*
X713210Y-158555D01*
X712210Y-157222D01*
X710460Y-156222D01*
X703710D01*
Y-176222D01*
X711960D01*
X713710Y-174889D01*
X714710Y-172889D01*
X715210Y-170555D01*
X714710Y-168222D01*
X713210Y-166222D01*
X711460Y-165555D01*
X703710D01*
G01X743710Y-176222D02*
Y-156222D01*
X755210Y-176222D01*
Y-156222D01*
G01X769460Y-176222D02*
X767960Y-175889D01*
X766460Y-174556D01*
X765460Y-172222D01*
X764960Y-169556D01*
X765460Y-166889D01*
X766460Y-164555D01*
X767960Y-163222D01*
X769460Y-162889D01*
X770960Y-163222D01*
X772460Y-164555D01*
X773460Y-166889D01*
X773710Y-169556D01*
X773460Y-172222D01*
X772460Y-174556D01*
X770960Y-175889D01*
X769460Y-176222D01*
G01X789460Y-176889D02*
X788960Y-176555D01*
Y-175889D01*
X789460Y-175555D01*
X789960Y-175889D01*
Y-176555D01*
X789460Y-176889D01*
G01X672905Y-132009D02*
Y-107009D01*
X681095Y-127842D01*
X689285Y-107009D01*
Y-132009D01*
G01X706295D02*
X704405Y-131592D01*
X702515Y-129926D01*
X701255Y-127009D01*
X700625Y-123676D01*
X701255Y-120343D01*
X702515Y-117426D01*
X704405Y-115759D01*
X706295Y-115343D01*
X708185Y-115759D01*
X710075Y-117426D01*
X711335Y-120343D01*
X711650Y-123676D01*
X711335Y-127009D01*
X710075Y-129926D01*
X708185Y-131592D01*
X706295Y-132009D01*
G01X737165Y-107009D02*
Y-132009D01*
G01Y-128260D02*
X735905Y-130343D01*
X734015Y-131592D01*
X731810Y-132009D01*
X729290Y-131176D01*
X727400Y-129093D01*
X726140Y-126593D01*
X725825Y-123676D01*
X726140Y-120759D01*
X727400Y-118259D01*
X729290Y-116176D01*
X731810Y-115343D01*
X734015Y-115759D01*
X735590Y-116593D01*
X737165Y-118259D01*
G01X751970Y-120759D02*
X762050D01*
X761105Y-117842D01*
X759530Y-116176D01*
X757325Y-115343D01*
X755120Y-115759D01*
X753230Y-117009D01*
X751970Y-119926D01*
X751340Y-122426D01*
Y-124926D01*
X751970Y-127426D01*
X753545Y-129926D01*
X755435Y-131592D01*
X757640Y-132009D01*
X759845Y-131176D01*
X762050Y-128676D01*
G01X781895Y-132009D02*
Y-107009D01*
G01X733295Y-362665D02*
X733846Y-361929D01*
X734319Y-361510D01*
X734949Y-361300D01*
X735500Y-361510D01*
X735893Y-361929D01*
X736208Y-362559D01*
X736287Y-363294D01*
X736208Y-363924D01*
X735893Y-364554D01*
X735421Y-365079D01*
X734870Y-365289D01*
X734240Y-365079D01*
X733689Y-364449D01*
X733374Y-363504D01*
X733295Y-362454D01*
X733452Y-361090D01*
X733689Y-360355D01*
X734082Y-359620D01*
X734633Y-359095D01*
X735185Y-358990D01*
X735736Y-359200D01*
X736130Y-359725D01*
G01X733295Y997965D02*
X733846Y998701D01*
X734319Y999120D01*
X734949Y999330D01*
X735500Y999120D01*
X735893Y998701D01*
X736208Y998071D01*
X736287Y997336D01*
X736208Y996706D01*
X735893Y996076D01*
X735421Y995551D01*
X734870Y995341D01*
X734240Y995551D01*
X733689Y996181D01*
X733374Y997126D01*
X733295Y998176D01*
X733452Y999540D01*
X733689Y1000275D01*
X734082Y1001010D01*
X734633Y1001535D01*
X735185Y1001640D01*
X735736Y1001430D01*
X736130Y1000905D01*
G01X804787Y312383D02*
X814843Y315128D01*
X813108Y318662D01*
X804787Y312383D01*
G01X809500Y308828D02*
X799224Y307079D01*
X809416Y304892D01*
X809500Y308828D01*
G01X842639Y-300678D02*
X847049Y-325678D01*
X852089Y-300678D01*
X857129Y-325678D01*
X861539Y-300678D01*
G01X877289Y-309012D02*
Y-325678D01*
G01Y-302345D02*
X876659Y-301928D01*
Y-301095D01*
X877289Y-300678D01*
X877919Y-301095D01*
Y-301928D01*
X877289Y-302345D01*
G01X897764Y-322762D02*
X899339Y-324428D01*
X901544Y-325678D01*
X903434D01*
X905324Y-324845D01*
X906584Y-323595D01*
X907214Y-321929D01*
X906899Y-319428D01*
X905639Y-318178D01*
X899969Y-315679D01*
X898709Y-312761D01*
X899339Y-310678D01*
X900599Y-309428D01*
X902489Y-309012D01*
X904379Y-309428D01*
X906269Y-310678D01*
G01X927689Y-300678D02*
Y-325678D01*
G01X923279Y-309012D02*
X932099D01*
G01X948479Y-325678D02*
Y-309012D01*
G01Y-312344D02*
X950054Y-310678D01*
X951629Y-309428D01*
X953834Y-309012D01*
X955409Y-309428D01*
X957299Y-310678D01*
G01X978089Y-325678D02*
X976199Y-325261D01*
X974309Y-323595D01*
X973049Y-320678D01*
X972419Y-317345D01*
X973049Y-314012D01*
X974309Y-311095D01*
X976199Y-309428D01*
X978089Y-309012D01*
X979979Y-309428D01*
X981869Y-311095D01*
X983129Y-314012D01*
X983444Y-317345D01*
X983129Y-320678D01*
X981869Y-323595D01*
X979979Y-325261D01*
X978089Y-325678D01*
G01X997934D02*
Y-309012D01*
G01Y-313178D02*
X999194Y-311095D01*
X1001084Y-309428D01*
X1003604Y-309012D01*
X1005809Y-309428D01*
X1007699Y-311095D01*
X1008644Y-314012D01*
Y-325678D01*
G01X1060619Y-302762D02*
X1058729Y-301511D01*
X1056524Y-300678D01*
X1054004D01*
X1051169Y-301928D01*
X1048964Y-304011D01*
X1047389Y-306512D01*
X1046129Y-310678D01*
X1045814Y-314428D01*
X1046444Y-318178D01*
X1047389Y-320678D01*
X1049279Y-323179D01*
X1051484Y-324845D01*
X1053689Y-325678D01*
X1055894D01*
X1058099Y-324845D01*
X1059989Y-323595D01*
X1061564Y-321929D01*
G01X1078889Y-325678D02*
X1076999Y-325261D01*
X1075109Y-323595D01*
X1073849Y-320678D01*
X1073219Y-317345D01*
X1073849Y-314012D01*
X1075109Y-311095D01*
X1076999Y-309428D01*
X1078889Y-309012D01*
X1080779Y-309428D01*
X1082669Y-311095D01*
X1083929Y-314012D01*
X1084244Y-317345D01*
X1083929Y-320678D01*
X1082669Y-323595D01*
X1080779Y-325261D01*
X1078889Y-325678D01*
G01X1099679D02*
Y-309012D01*
G01Y-312344D02*
X1101254Y-310678D01*
X1102829Y-309428D01*
X1105034Y-309012D01*
X1106609Y-309428D01*
X1108499Y-310678D01*
G01X1123619Y-334011D02*
Y-309012D01*
G01Y-312761D02*
X1125194Y-310678D01*
X1126769Y-309428D01*
X1129289Y-309012D01*
X1131494Y-309428D01*
X1133699Y-311511D01*
X1134644Y-314428D01*
X1134959Y-317345D01*
X1134644Y-320262D01*
X1133699Y-323179D01*
X1131809Y-324845D01*
X1129289Y-325678D01*
X1127084Y-325261D01*
X1124879Y-324012D01*
X1123619Y-322345D01*
G01X1154489Y-325678D02*
X1152599Y-325261D01*
X1150709Y-323595D01*
X1149449Y-320678D01*
X1148819Y-317345D01*
X1149449Y-314012D01*
X1150709Y-311095D01*
X1152599Y-309428D01*
X1154489Y-309012D01*
X1156379Y-309428D01*
X1158269Y-311095D01*
X1159529Y-314012D01*
X1159844Y-317345D01*
X1159529Y-320678D01*
X1158269Y-323595D01*
X1156379Y-325261D01*
X1154489Y-325678D01*
G01X1175279D02*
Y-309012D01*
G01Y-312344D02*
X1176854Y-310678D01*
X1178429Y-309428D01*
X1180634Y-309012D01*
X1182209Y-309428D01*
X1184099Y-310678D01*
G01X1210559Y-325678D02*
Y-309012D01*
G01Y-311928D02*
X1209299Y-310262D01*
X1207409Y-309428D01*
X1205204Y-309012D01*
X1202999Y-309845D01*
X1201109Y-311511D01*
X1199849Y-314012D01*
X1199219Y-317345D01*
X1199849Y-320678D01*
X1201109Y-323179D01*
X1202999Y-324845D01*
X1205204Y-325678D01*
X1207409Y-325261D01*
X1209299Y-324012D01*
X1210559Y-322345D01*
G01X1230089Y-300678D02*
Y-325678D01*
G01X1225679Y-309012D02*
X1234499D01*
G01X1255289D02*
Y-325678D01*
G01Y-302345D02*
X1254659Y-301928D01*
Y-301095D01*
X1255289Y-300678D01*
X1255919Y-301095D01*
Y-301928D01*
X1255289Y-302345D01*
G01X1280489Y-325678D02*
X1278599Y-325261D01*
X1276709Y-323595D01*
X1275449Y-320678D01*
X1274819Y-317345D01*
X1275449Y-314012D01*
X1276709Y-311095D01*
X1278599Y-309428D01*
X1280489Y-309012D01*
X1282379Y-309428D01*
X1284269Y-311095D01*
X1285529Y-314012D01*
X1285844Y-317345D01*
X1285529Y-320678D01*
X1284269Y-323595D01*
X1282379Y-325261D01*
X1280489Y-325678D01*
G01X1300334D02*
Y-309012D01*
G01Y-313178D02*
X1301594Y-311095D01*
X1303484Y-309428D01*
X1306004Y-309012D01*
X1308209Y-309428D01*
X1310099Y-311095D01*
X1311044Y-314012D01*
Y-325678D01*
G01X886442Y-222463D02*
X888442Y-224129D01*
X890692Y-225129D01*
X892692D01*
X894692Y-224129D01*
X896192Y-222463D01*
X896942Y-220129D01*
X896442Y-217796D01*
X895192Y-215796D01*
X892942Y-214462D01*
X889942Y-213796D01*
X888192Y-212463D01*
X887442Y-210129D01*
X887942Y-207796D01*
X889192Y-206129D01*
X890942Y-205129D01*
X892692D01*
X894442Y-205796D01*
X895942Y-207462D01*
G01X917192Y-206796D02*
X915692Y-205796D01*
X913942Y-205129D01*
X911942D01*
X909692Y-206129D01*
X907942Y-207796D01*
X906692Y-209796D01*
X905692Y-213129D01*
X905442Y-216129D01*
X905942Y-219129D01*
X906692Y-221129D01*
X908192Y-223129D01*
X909942Y-224462D01*
X911692Y-225129D01*
X913442D01*
X915192Y-224462D01*
X916692Y-223463D01*
X917942Y-222130D01*
G01X865664Y-247168D02*
X871914Y-267168D01*
X878164Y-247168D01*
G01X891914Y-253835D02*
Y-267168D01*
G01Y-248502D02*
X891414Y-248168D01*
Y-247501D01*
X891914Y-247168D01*
X892414Y-247501D01*
Y-248168D01*
X891914Y-248502D01*
G01X911914Y-267168D02*
Y-247168D01*
G01X928164Y-258168D02*
X936164D01*
X935414Y-255835D01*
X934164Y-254502D01*
X932414Y-253835D01*
X930664Y-254168D01*
X929164Y-255168D01*
X928164Y-257502D01*
X927664Y-259502D01*
Y-261501D01*
X928164Y-263502D01*
X929414Y-265502D01*
X930914Y-266835D01*
X932664Y-267168D01*
X934414Y-266501D01*
X936164Y-264502D01*
G01X956414Y-267168D02*
Y-253835D01*
G01Y-256168D02*
X955414Y-254835D01*
X953914Y-254168D01*
X952164Y-253835D01*
X950414Y-254502D01*
X948914Y-255835D01*
X947914Y-257835D01*
X947414Y-260502D01*
X947914Y-263168D01*
X948914Y-265168D01*
X950414Y-266501D01*
X952164Y-267168D01*
X953914Y-266835D01*
X955414Y-265835D01*
X956414Y-264502D01*
G01X967664Y-267168D02*
Y-253835D01*
G01Y-257168D02*
X968664Y-255501D01*
X970164Y-254168D01*
X972164Y-253835D01*
X973914Y-254168D01*
X975414Y-255501D01*
X976164Y-257835D01*
Y-267168D01*
G01X1006914Y-247168D02*
Y-267168D01*
X1016914D01*
G01X1031914Y-253835D02*
Y-267168D01*
G01Y-248502D02*
X1031414Y-248168D01*
Y-247501D01*
X1031914Y-247168D01*
X1032414Y-247501D01*
Y-248168D01*
X1031914Y-248502D01*
G01X877662Y-174247D02*
Y-154247D01*
X874662Y-158247D01*
G01Y-174247D02*
X880662D01*
G01X892912Y-165914D02*
X894662Y-163580D01*
X896162Y-162247D01*
X898162Y-161581D01*
X899912Y-162247D01*
X901162Y-163580D01*
X902162Y-165580D01*
X902412Y-167914D01*
X902162Y-169914D01*
X901162Y-171914D01*
X899662Y-173580D01*
X897912Y-174247D01*
X895912Y-173580D01*
X894162Y-171581D01*
X893162Y-168580D01*
X892912Y-165247D01*
X893412Y-160914D01*
X894162Y-158580D01*
X895412Y-156247D01*
X897162Y-154580D01*
X898912Y-154247D01*
X900662Y-154914D01*
X901912Y-156580D01*
G01X912162Y-170247D02*
X913662Y-172581D01*
X915662Y-173914D01*
X917912Y-174247D01*
X919912Y-173914D01*
X921912Y-172247D01*
X923162Y-170247D01*
X923412Y-168247D01*
X922912Y-165914D01*
X921162Y-164247D01*
X919412Y-163580D01*
X917162D01*
G01X919412D02*
X920912Y-162580D01*
X922162Y-160914D01*
X922662Y-158914D01*
X922162Y-156914D01*
X920912Y-155247D01*
X918662Y-154247D01*
X916412Y-154580D01*
X914162Y-155914D01*
G01X932912Y-165914D02*
X934662Y-163580D01*
X936162Y-162247D01*
X938162Y-161581D01*
X939912Y-162247D01*
X941162Y-163580D01*
X942162Y-165580D01*
X942412Y-167914D01*
X942162Y-169914D01*
X941162Y-171914D01*
X939662Y-173580D01*
X937912Y-174247D01*
X935912Y-173580D01*
X934162Y-171581D01*
X933162Y-168580D01*
X932912Y-165247D01*
X933412Y-160914D01*
X934162Y-158580D01*
X935412Y-156247D01*
X937162Y-154580D01*
X938912Y-154247D01*
X940662Y-154914D01*
X941912Y-156580D01*
G01X953412Y-171914D02*
X955162Y-173580D01*
X957162Y-174247D01*
X959162Y-173580D01*
X960912Y-171581D01*
X962162Y-168580D01*
X962662Y-165580D01*
Y-161914D01*
X962162Y-158914D01*
X960912Y-156247D01*
X959412Y-154914D01*
X957662Y-154247D01*
X955662Y-154914D01*
X954162Y-156247D01*
X953162Y-158247D01*
X952662Y-160914D01*
X953162Y-163247D01*
X954412Y-165580D01*
X955912Y-166914D01*
X957662Y-167247D01*
X959662Y-166581D01*
X961162Y-164914D01*
X962662Y-161914D01*
G01X857114Y-113994D02*
X858374Y-112745D01*
X859319Y-110662D01*
X859949Y-107744D01*
X859319Y-105245D01*
X858059Y-103578D01*
X855854Y-102328D01*
X847349D01*
Y-127328D01*
X857744D01*
X859949Y-125662D01*
X861209Y-123161D01*
X861839Y-120245D01*
X861209Y-117329D01*
X859319Y-114828D01*
X857114Y-113994D01*
X847349D01*
G01X875384Y-127328D02*
Y-110662D01*
G01Y-113994D02*
X876959Y-112328D01*
X878534Y-111078D01*
X880739Y-110662D01*
X882314Y-111078D01*
X884204Y-112328D01*
G01X898379Y-134828D02*
X900269Y-135661D01*
X902789Y-134828D01*
X904364Y-133162D01*
X905624Y-131078D01*
X907514Y-124412D01*
X911609Y-110662D01*
G01X901529D02*
X907514Y-124412D01*
G01X935234Y-112745D02*
X933029Y-111078D01*
X931139Y-110662D01*
X928619Y-111495D01*
X926729Y-113161D01*
X925469Y-116078D01*
X925154Y-118995D01*
X925469Y-121912D01*
X926729Y-124412D01*
X928619Y-126495D01*
X931139Y-127328D01*
X933344Y-126495D01*
X935234Y-124829D01*
G01X950669Y-116078D02*
X960749D01*
X959804Y-113161D01*
X958229Y-111495D01*
X956024Y-110662D01*
X953819Y-111078D01*
X951929Y-112328D01*
X950669Y-115245D01*
X950039Y-117745D01*
Y-120245D01*
X950669Y-122745D01*
X952244Y-125245D01*
X954134Y-126911D01*
X956339Y-127328D01*
X958544Y-126495D01*
X960749Y-123995D01*
G01X1012724Y-104412D02*
X1010834Y-103161D01*
X1008629Y-102328D01*
X1006109D01*
X1003274Y-103578D01*
X1001069Y-105661D01*
X999494Y-108162D01*
X998234Y-112328D01*
X997919Y-116078D01*
X998549Y-119828D01*
X999494Y-122328D01*
X1001384Y-124829D01*
X1003589Y-126495D01*
X1005794Y-127328D01*
X1007999D01*
X1010204Y-126495D01*
X1012094Y-125245D01*
X1013669Y-123579D01*
G01X1036664Y-127328D02*
Y-110662D01*
G01Y-113578D02*
X1035404Y-111912D01*
X1033514Y-111078D01*
X1031309Y-110662D01*
X1029104Y-111495D01*
X1027214Y-113161D01*
X1025954Y-115662D01*
X1025324Y-118995D01*
X1025954Y-122328D01*
X1027214Y-124829D01*
X1029104Y-126495D01*
X1031309Y-127328D01*
X1033514Y-126911D01*
X1035404Y-125662D01*
X1036664Y-123995D01*
G01X1050839Y-127328D02*
Y-110662D01*
G01Y-114828D02*
X1052099Y-112745D01*
X1053989Y-111078D01*
X1056509Y-110662D01*
X1058714Y-111078D01*
X1060604Y-112745D01*
X1061549Y-115662D01*
Y-127328D01*
G01X1074779Y-134828D02*
X1076669Y-135661D01*
X1079189Y-134828D01*
X1080764Y-133162D01*
X1082024Y-131078D01*
X1083914Y-124412D01*
X1088009Y-110662D01*
G01X1077929D02*
X1083914Y-124412D01*
G01X1106594Y-127328D02*
X1104704Y-126911D01*
X1102814Y-125245D01*
X1101554Y-122328D01*
X1100924Y-118995D01*
X1101554Y-115662D01*
X1102814Y-112745D01*
X1104704Y-111078D01*
X1106594Y-110662D01*
X1108484Y-111078D01*
X1110374Y-112745D01*
X1111634Y-115662D01*
X1111949Y-118995D01*
X1111634Y-122328D01*
X1110374Y-125245D01*
X1108484Y-126911D01*
X1106594Y-127328D01*
G01X1126439D02*
Y-110662D01*
G01Y-114828D02*
X1127699Y-112745D01*
X1129589Y-111078D01*
X1132109Y-110662D01*
X1134314Y-111078D01*
X1136204Y-112745D01*
X1137149Y-115662D01*
Y-127328D01*
G01X1176209D02*
Y-102328D01*
X1188179D01*
G01X1183769Y-114411D02*
X1176209D01*
G01X1202984Y-127328D02*
Y-110662D01*
G01Y-113994D02*
X1204559Y-112328D01*
X1206134Y-111078D01*
X1208339Y-110662D01*
X1209914Y-111078D01*
X1211804Y-112328D01*
G01X1232594Y-127328D02*
X1230704Y-126911D01*
X1228814Y-125245D01*
X1227554Y-122328D01*
X1226924Y-118995D01*
X1227554Y-115662D01*
X1228814Y-112745D01*
X1230704Y-111078D01*
X1232594Y-110662D01*
X1234484Y-111078D01*
X1236374Y-112745D01*
X1237634Y-115662D01*
X1237949Y-118995D01*
X1237634Y-122328D01*
X1236374Y-125245D01*
X1234484Y-126911D01*
X1232594Y-127328D01*
G01X1252439D02*
Y-110662D01*
G01Y-114828D02*
X1253699Y-112745D01*
X1255589Y-111078D01*
X1258109Y-110662D01*
X1260314Y-111078D01*
X1262204Y-112745D01*
X1263149Y-115662D01*
Y-127328D01*
G01X1282994Y-102328D02*
Y-127328D01*
G01X1278584Y-110662D02*
X1287404D01*
G01X1327094Y-127328D02*
Y-102328D01*
X1334654D01*
X1337174Y-103578D01*
X1339064Y-106495D01*
X1339694Y-109828D01*
X1339064Y-113161D01*
X1337489Y-115662D01*
X1334654Y-116912D01*
X1327094D01*
G01X1364264Y-127328D02*
Y-110662D01*
G01Y-113578D02*
X1363004Y-111912D01*
X1361114Y-111078D01*
X1358909Y-110662D01*
X1356704Y-111495D01*
X1354814Y-113161D01*
X1353554Y-115662D01*
X1352924Y-118995D01*
X1353554Y-122328D01*
X1354814Y-124829D01*
X1356704Y-126495D01*
X1358909Y-127328D01*
X1361114Y-126911D01*
X1363004Y-125662D01*
X1364264Y-123995D01*
G01X1378439Y-127328D02*
Y-110662D01*
G01Y-114828D02*
X1379699Y-112745D01*
X1381589Y-111078D01*
X1384109Y-110662D01*
X1386314Y-111078D01*
X1388204Y-112745D01*
X1389149Y-115662D01*
Y-127328D01*
G01X1404269Y-116078D02*
X1414349D01*
X1413404Y-113161D01*
X1411829Y-111495D01*
X1409624Y-110662D01*
X1407419Y-111078D01*
X1405529Y-112328D01*
X1404269Y-115245D01*
X1403639Y-117745D01*
Y-120245D01*
X1404269Y-122745D01*
X1405844Y-125245D01*
X1407734Y-126911D01*
X1409939Y-127328D01*
X1412144Y-126495D01*
X1414349Y-123995D01*
G01X1434194Y-127328D02*
Y-102328D01*
G01X1487114Y-113994D02*
X1488374Y-112745D01*
X1489319Y-110662D01*
X1489949Y-107744D01*
X1489319Y-105245D01*
X1488059Y-103578D01*
X1485854Y-102328D01*
X1477349D01*
Y-127328D01*
X1487744D01*
X1489949Y-125662D01*
X1491209Y-123161D01*
X1491839Y-120245D01*
X1491209Y-117329D01*
X1489319Y-114828D01*
X1487114Y-113994D01*
X1477349D01*
G01X1509794Y-127328D02*
X1507904Y-126911D01*
X1506014Y-125245D01*
X1504754Y-122328D01*
X1504124Y-118995D01*
X1504754Y-115662D01*
X1506014Y-112745D01*
X1507904Y-111078D01*
X1509794Y-110662D01*
X1511684Y-111078D01*
X1513574Y-112745D01*
X1514834Y-115662D01*
X1515149Y-118995D01*
X1514834Y-122328D01*
X1513574Y-125245D01*
X1511684Y-126911D01*
X1509794Y-127328D01*
G01X1540664D02*
Y-110662D01*
G01Y-113578D02*
X1539404Y-111912D01*
X1537514Y-111078D01*
X1535309Y-110662D01*
X1533104Y-111495D01*
X1531214Y-113161D01*
X1529954Y-115662D01*
X1529324Y-118995D01*
X1529954Y-122328D01*
X1531214Y-124829D01*
X1533104Y-126495D01*
X1535309Y-127328D01*
X1537514Y-126911D01*
X1539404Y-125662D01*
X1540664Y-123995D01*
G01X1555784Y-127328D02*
Y-110662D01*
G01Y-113994D02*
X1557359Y-112328D01*
X1558934Y-111078D01*
X1561139Y-110662D01*
X1562714Y-111078D01*
X1564604Y-112328D01*
G01X1591064Y-102328D02*
Y-127328D01*
G01Y-123579D02*
X1589804Y-125662D01*
X1587914Y-126911D01*
X1585709Y-127328D01*
X1583189Y-126495D01*
X1581299Y-124412D01*
X1580039Y-121912D01*
X1579724Y-118995D01*
X1580039Y-116078D01*
X1581299Y-113578D01*
X1583189Y-111495D01*
X1585709Y-110662D01*
X1587914Y-111078D01*
X1589489Y-111912D01*
X1591064Y-113578D01*
G01X907862Y-365289D02*
X908020Y-363924D01*
X908256Y-362770D01*
X908571Y-361720D01*
X908965Y-360565D01*
X909595Y-358990D01*
X906445D01*
G01X907862Y995341D02*
X908020Y996706D01*
X908256Y997860D01*
X908571Y998910D01*
X908965Y1000065D01*
X909595Y1001640D01*
X906445D01*
G01X1081248Y-365289D02*
X1081799Y-365184D01*
X1082429Y-364869D01*
X1082823Y-364344D01*
X1082980Y-363609D01*
X1082823Y-362875D01*
X1082350Y-362245D01*
X1081642Y-361929D01*
X1080854D01*
X1080382Y-361720D01*
X1079988Y-361195D01*
X1079831Y-360460D01*
X1080067Y-359725D01*
X1080618Y-359200D01*
X1081248Y-358990D01*
X1081878Y-359200D01*
X1082429Y-359725D01*
X1082665Y-360460D01*
X1082508Y-361195D01*
X1082114Y-361720D01*
X1081642Y-361929D01*
X1080854D01*
X1080146Y-362245D01*
X1079673Y-362875D01*
X1079516Y-363609D01*
X1079673Y-364344D01*
X1080067Y-364869D01*
X1080697Y-365184D01*
X1081248Y-365289D01*
G01Y995341D02*
X1081799Y995446D01*
X1082429Y995761D01*
X1082823Y996286D01*
X1082980Y997021D01*
X1082823Y997755D01*
X1082350Y998385D01*
X1081642Y998701D01*
X1080854D01*
X1080382Y998910D01*
X1079988Y999435D01*
X1079831Y1000170D01*
X1080067Y1000905D01*
X1080618Y1001430D01*
X1081248Y1001640D01*
X1081878Y1001430D01*
X1082429Y1000905D01*
X1082665Y1000170D01*
X1082508Y999435D01*
X1082114Y998910D01*
X1081642Y998701D01*
X1080854D01*
X1080146Y998385D01*
X1079673Y997755D01*
X1079516Y997021D01*
X1079673Y996286D01*
X1080067Y995761D01*
X1080697Y995446D01*
X1081248Y995341D01*
G01X1182295Y-199854D02*
Y-219854D01*
G01X1176545Y-199854D02*
X1188045D01*
G01X1198045Y-219854D02*
Y-199854D01*
G01Y-209520D02*
X1199295Y-207854D01*
X1200545Y-206854D01*
X1202545Y-206521D01*
X1204045Y-206854D01*
X1205795Y-208187D01*
X1206545Y-210188D01*
Y-219854D01*
G01X1222295Y-206521D02*
Y-219854D01*
G01Y-201188D02*
X1221795Y-200854D01*
Y-200187D01*
X1222295Y-199854D01*
X1222795Y-200187D01*
Y-200854D01*
X1222295Y-201188D01*
G01X1246295Y-208187D02*
X1244545Y-206854D01*
X1243045Y-206521D01*
X1241045Y-207188D01*
X1239545Y-208521D01*
X1238545Y-210854D01*
X1238295Y-213188D01*
X1238545Y-215521D01*
X1239545Y-217521D01*
X1241045Y-219187D01*
X1243045Y-219854D01*
X1244795Y-219187D01*
X1246295Y-217854D01*
G01X1258045Y-219854D02*
Y-199854D01*
G01X1266045Y-206521D02*
X1258045Y-214187D01*
G01X1261295Y-211187D02*
X1266545Y-219854D01*
G01X1278045D02*
Y-206521D01*
G01Y-209854D02*
X1279045Y-208187D01*
X1280545Y-206854D01*
X1282545Y-206521D01*
X1284295Y-206854D01*
X1285795Y-208187D01*
X1286545Y-210521D01*
Y-219854D01*
G01X1298545Y-210854D02*
X1306545D01*
X1305795Y-208521D01*
X1304545Y-207188D01*
X1302795Y-206521D01*
X1301045Y-206854D01*
X1299545Y-207854D01*
X1298545Y-210188D01*
X1298045Y-212188D01*
Y-214187D01*
X1298545Y-216188D01*
X1299795Y-218188D01*
X1301295Y-219521D01*
X1303045Y-219854D01*
X1304795Y-219187D01*
X1306545Y-217188D01*
G01X1318545Y-217521D02*
X1319795Y-218854D01*
X1321545Y-219854D01*
X1323045D01*
X1324545Y-219187D01*
X1325545Y-218188D01*
X1326045Y-216855D01*
X1325795Y-214854D01*
X1324795Y-213854D01*
X1320295Y-211854D01*
X1319295Y-209520D01*
X1319795Y-207854D01*
X1320795Y-206854D01*
X1322295Y-206521D01*
X1323795Y-206854D01*
X1325295Y-207854D01*
G01X1338545Y-217521D02*
X1339795Y-218854D01*
X1341545Y-219854D01*
X1343045D01*
X1344545Y-219187D01*
X1345545Y-218188D01*
X1346045Y-216855D01*
X1345795Y-214854D01*
X1344795Y-213854D01*
X1340295Y-211854D01*
X1339295Y-209520D01*
X1339795Y-207854D01*
X1340795Y-206854D01*
X1342295Y-206521D01*
X1343795Y-206854D01*
X1345295Y-207854D01*
G01X1253138Y-364554D02*
X1253690Y-365079D01*
X1254319Y-365289D01*
X1254949Y-365079D01*
X1255501Y-364449D01*
X1255894Y-363504D01*
X1256052Y-362559D01*
Y-361405D01*
X1255894Y-360460D01*
X1255501Y-359620D01*
X1255028Y-359200D01*
X1254477Y-358990D01*
X1253847Y-359200D01*
X1253375Y-359620D01*
X1253060Y-360250D01*
X1252902Y-361090D01*
X1253060Y-361825D01*
X1253453Y-362559D01*
X1253926Y-362979D01*
X1254477Y-363084D01*
X1255107Y-362875D01*
X1255579Y-362350D01*
X1256052Y-361405D01*
G01X1227198Y-269143D02*
Y-249143D01*
X1232198D01*
X1234198Y-250143D01*
X1235698Y-251476D01*
X1236948Y-253476D01*
X1237948Y-255810D01*
X1238198Y-259143D01*
X1237948Y-262477D01*
X1236948Y-264810D01*
X1235698Y-266810D01*
X1234198Y-268143D01*
X1232198Y-269143D01*
X1227198D01*
G01X1257198D02*
Y-255810D01*
G01Y-258143D02*
X1256198Y-256810D01*
X1254698Y-256143D01*
X1252948Y-255810D01*
X1251198Y-256477D01*
X1249698Y-257810D01*
X1248698Y-259810D01*
X1248198Y-262477D01*
X1248698Y-265143D01*
X1249698Y-267143D01*
X1251198Y-268476D01*
X1252948Y-269143D01*
X1254698Y-268810D01*
X1256198Y-267810D01*
X1257198Y-266477D01*
G01X1272698Y-249143D02*
Y-269143D01*
G01X1269198Y-255810D02*
X1276198D01*
G01X1288948Y-260143D02*
X1296948D01*
X1296198Y-257810D01*
X1294948Y-256477D01*
X1293198Y-255810D01*
X1291448Y-256143D01*
X1289948Y-257143D01*
X1288948Y-259477D01*
X1288448Y-261477D01*
Y-263476D01*
X1288948Y-265477D01*
X1290198Y-267477D01*
X1291698Y-268810D01*
X1293448Y-269143D01*
X1295198Y-268476D01*
X1296948Y-266477D01*
G01X1264300Y247186D02*
X1256138Y253670D01*
X1254315Y250180D01*
X1264300Y247186D01*
G01X1253138Y996076D02*
X1253690Y995551D01*
X1254319Y995341D01*
X1254949Y995551D01*
X1255501Y996181D01*
X1255894Y997126D01*
X1256052Y998071D01*
Y999225D01*
X1255894Y1000170D01*
X1255501Y1001010D01*
X1255028Y1001430D01*
X1254477Y1001640D01*
X1253847Y1001430D01*
X1253375Y1001010D01*
X1253060Y1000380D01*
X1252902Y999540D01*
X1253060Y998805D01*
X1253453Y998071D01*
X1253926Y997651D01*
X1254477Y997546D01*
X1255107Y997755D01*
X1255579Y998280D01*
X1256052Y999225D01*
G01X1358591Y324840D02*
X1368958Y325931D01*
X1367814Y329698D01*
X1358591Y324840D01*
G01X1352069Y317404D02*
X1361716Y313455D01*
X1362493Y317315D01*
X1352069Y317404D01*
G01X1427705Y-365289D02*
Y-358990D01*
X1426760Y-360250D01*
G01Y-365289D02*
X1428650D01*
G01X1434004Y-358990D02*
X1433374Y-359200D01*
X1432902Y-359725D01*
X1432587Y-360355D01*
X1432351Y-361195D01*
X1432272Y-362140D01*
X1432351Y-363084D01*
X1432587Y-363924D01*
X1432902Y-364554D01*
X1433374Y-365079D01*
X1434004Y-365289D01*
X1434634Y-365079D01*
X1435106Y-364554D01*
X1435421Y-363924D01*
X1435657Y-363084D01*
X1435736Y-362140D01*
X1435657Y-361195D01*
X1435421Y-360355D01*
X1435106Y-359725D01*
X1434634Y-359200D01*
X1434004Y-358990D01*
G01X1395366Y-250501D02*
X1396866Y-248502D01*
X1398616Y-247501D01*
X1400616Y-247168D01*
X1403116Y-247835D01*
X1404866Y-249501D01*
X1405366Y-251501D01*
X1405116Y-253502D01*
X1404116Y-255168D01*
X1399116Y-258501D01*
X1396866Y-260835D01*
X1395366Y-264169D01*
X1394866Y-267168D01*
X1405366D01*
G01X1420116Y-247168D02*
X1418116Y-247835D01*
X1416616Y-249501D01*
X1415616Y-251501D01*
X1414866Y-254168D01*
X1414616Y-257168D01*
X1414866Y-260168D01*
X1415616Y-262835D01*
X1416616Y-264835D01*
X1418116Y-266501D01*
X1420116Y-267168D01*
X1422116Y-266501D01*
X1423616Y-264835D01*
X1424616Y-262835D01*
X1425366Y-260168D01*
X1425616Y-257168D01*
X1425366Y-254168D01*
X1424616Y-251501D01*
X1423616Y-249501D01*
X1422116Y-247835D01*
X1420116Y-247168D01*
G01X1440116Y-267168D02*
Y-247168D01*
X1437116Y-251168D01*
G01Y-267168D02*
X1443116D01*
G01X1459616D02*
X1460116Y-262835D01*
X1460866Y-259168D01*
X1461866Y-255835D01*
X1463116Y-252168D01*
X1465116Y-247168D01*
X1455116D01*
G01X1476866Y-260502D02*
X1483366D01*
G01X1500116Y-247168D02*
X1498116Y-247835D01*
X1496616Y-249501D01*
X1495616Y-251501D01*
X1494866Y-254168D01*
X1494616Y-257168D01*
X1494866Y-260168D01*
X1495616Y-262835D01*
X1496616Y-264835D01*
X1498116Y-266501D01*
X1500116Y-267168D01*
X1502116Y-266501D01*
X1503616Y-264835D01*
X1504616Y-262835D01*
X1505366Y-260168D01*
X1505616Y-257168D01*
X1505366Y-254168D01*
X1504616Y-251501D01*
X1503616Y-249501D01*
X1502116Y-247835D01*
X1500116Y-247168D01*
G01X1515366Y-250501D02*
X1516866Y-248502D01*
X1518616Y-247501D01*
X1520616Y-247168D01*
X1523116Y-247835D01*
X1524866Y-249501D01*
X1525366Y-251501D01*
X1525116Y-253502D01*
X1524116Y-255168D01*
X1519116Y-258501D01*
X1516866Y-260835D01*
X1515366Y-264169D01*
X1514866Y-267168D01*
X1525366D01*
G01X1536866Y-260502D02*
X1543366D01*
G01X1555366Y-250501D02*
X1556866Y-248502D01*
X1558616Y-247501D01*
X1560616Y-247168D01*
X1563116Y-247835D01*
X1564866Y-249501D01*
X1565366Y-251501D01*
X1565116Y-253502D01*
X1564116Y-255168D01*
X1559116Y-258501D01*
X1556866Y-260835D01*
X1555366Y-264169D01*
X1554866Y-267168D01*
X1565366D01*
G01X1580116D02*
Y-247168D01*
X1577116Y-251168D01*
G01Y-267168D02*
X1583116D01*
G01X1408010Y-218460D02*
Y-198460D01*
X1405010Y-202460D01*
G01Y-218460D02*
X1411010D01*
G01X1428010Y-219127D02*
X1427510Y-218793D01*
Y-218127D01*
X1428010Y-217793D01*
X1428510Y-218127D01*
Y-218793D01*
X1428010Y-219127D01*
G01X1443260Y-210127D02*
X1445010Y-207793D01*
X1446510Y-206460D01*
X1448510Y-205794D01*
X1450260Y-206460D01*
X1451510Y-207793D01*
X1452510Y-209793D01*
X1452760Y-212127D01*
X1452510Y-214127D01*
X1451510Y-216127D01*
X1450010Y-217793D01*
X1448260Y-218460D01*
X1446260Y-217793D01*
X1444510Y-215794D01*
X1443510Y-212793D01*
X1443260Y-209460D01*
X1443760Y-205127D01*
X1444510Y-202793D01*
X1445760Y-200460D01*
X1447510Y-198793D01*
X1449260Y-198460D01*
X1451010Y-199127D01*
X1452260Y-200793D01*
G01X1460510Y-218460D02*
Y-205127D01*
G01Y-208794D02*
X1461260Y-207127D01*
X1462510Y-205794D01*
X1464260Y-205127D01*
X1466010Y-205794D01*
X1467260Y-207127D01*
X1468010Y-208794D01*
Y-218460D01*
G01Y-208794D02*
X1468760Y-207127D01*
X1470010Y-205794D01*
X1471760Y-205127D01*
X1473510Y-205794D01*
X1474760Y-207127D01*
X1475510Y-209127D01*
Y-218460D01*
G01X1480510D02*
Y-205127D01*
G01Y-208794D02*
X1481260Y-207127D01*
X1482510Y-205794D01*
X1484260Y-205127D01*
X1486010Y-205794D01*
X1487260Y-207127D01*
X1488010Y-208794D01*
Y-218460D01*
G01Y-208794D02*
X1488760Y-207127D01*
X1490010Y-205794D01*
X1491760Y-205127D01*
X1493510Y-205794D01*
X1494760Y-207127D01*
X1495510Y-209127D01*
Y-218460D01*
G01X1418067Y244463D02*
X1425431Y237086D01*
X1427642Y240343D01*
X1418067Y244463D01*
G01X1427705Y995341D02*
Y1001640D01*
X1426760Y1000380D01*
G01Y995341D02*
X1428650D01*
G01X1434004Y1001640D02*
X1433374Y1001430D01*
X1432902Y1000905D01*
X1432587Y1000275D01*
X1432351Y999435D01*
X1432272Y998490D01*
X1432351Y997546D01*
X1432587Y996706D01*
X1432902Y996076D01*
X1433374Y995551D01*
X1434004Y995341D01*
X1434634Y995551D01*
X1435106Y996076D01*
X1435421Y996706D01*
X1435657Y997546D01*
X1435736Y998490D01*
X1435657Y999435D01*
X1435421Y1000275D01*
X1435106Y1000905D01*
X1434634Y1001430D01*
X1434004Y1001640D01*
G01X1600933Y-365289D02*
Y-358990D01*
X1599988Y-360250D01*
G01Y-365289D02*
X1601878D01*
G01X1607232D02*
Y-358990D01*
X1606287Y-360250D01*
G01Y-365289D02*
X1608177D01*
G01X1600933Y995341D02*
Y1001640D01*
X1599988Y1000380D01*
G01Y995341D02*
X1601878D01*
G01X1607232D02*
Y1001640D01*
X1606287Y1000380D01*
G01Y995341D02*
X1608177D01*
G01X1730382Y-295211D02*
Y-288912D01*
X1733374D01*
G01X1732272Y-291956D02*
X1730382D01*
G01X1733453Y-58990D02*
X1730303D01*
Y-52691D01*
X1733453D01*
G01X1732193Y-55735D02*
X1730303D01*
G01X1730146Y177230D02*
Y183529D01*
X1731720D01*
X1732350Y183214D01*
X1732823Y182794D01*
X1733217Y182164D01*
X1733531Y181429D01*
X1733610Y180379D01*
X1733531Y179330D01*
X1733217Y178595D01*
X1732823Y177965D01*
X1732350Y177545D01*
X1731720Y177230D01*
X1730146D01*
G01X1733610Y419225D02*
X1733138Y419540D01*
X1732587Y419750D01*
X1731957D01*
X1731248Y419435D01*
X1730697Y418910D01*
X1730303Y418280D01*
X1729988Y417230D01*
X1729910Y416286D01*
X1730067Y415341D01*
X1730303Y414711D01*
X1730776Y414081D01*
X1731327Y413661D01*
X1731878Y413451D01*
X1732429D01*
X1732980Y413661D01*
X1733453Y413976D01*
X1733846Y414396D01*
G01X1732508Y653031D02*
X1732823Y653345D01*
X1733059Y653870D01*
X1733217Y654605D01*
X1733059Y655235D01*
X1732744Y655655D01*
X1732193Y655970D01*
X1730067D01*
Y649671D01*
X1732665D01*
X1733217Y650091D01*
X1733531Y650721D01*
X1733689Y651456D01*
X1733531Y652190D01*
X1733059Y652820D01*
X1732508Y653031D01*
X1730067D01*
G01X1729910Y885892D02*
X1731878Y892191D01*
X1733846Y885892D01*
G01X1733138Y888097D02*
X1730618D01*
G01X-208004Y-354220D02*
X1725855D01*
G01X-225326Y-371543D02*
X1743177D01*
G01X-208004Y989087D02*
Y-354220D01*
G01X-225326Y1006410D02*
Y-371543D01*
G01Y-174693D02*
X-208004D01*
G01X-225326Y61528D02*
X-208004D01*
G01X-225326Y297748D02*
X-208004D01*
G01X-225326Y533969D02*
X-208004D01*
G01X-225326Y770189D02*
X-208004D01*
G01Y989087D02*
X1725855D01*
G01X-225326Y1006410D02*
X1743177D01*
G01X0Y-26378D02*
X-81603D01*
G01X0Y354331D02*
X-81603D01*
G01X-61131Y363446D02*
X-81603D01*
G01X0Y742913D02*
X-81603D01*
G01X-52098Y-354220D02*
Y-371543D01*
G01X-7874Y-18504D02*
Y-22441D01*
G01X-11811Y-26378D02*
G03X-7874Y-22441I0J3937D01*
G01X-31496Y-11378D02*
G03X-16496Y-26378I15000J0D01*
G01X0Y-18504D02*
G03X-7874I-3937J0D01*
G01X-11811Y-26378D02*
X-16496D01*
G01X-31496Y727913D02*
Y-11378D01*
G01X-20846Y-13300D02*
X-57046D01*
G01X-5631Y1915D02*
X-20846Y-13300D01*
G01X-5631Y1915D02*
X-9166Y-5155D01*
G01D02*
X-12701Y-1620D01*
G01X-7874Y20866D02*
G03X0I3937J0D01*
G01X-7874Y175427D02*
Y20866D01*
G01X-14607Y16741D02*
G03I-4291J0D01*
G01X-1631Y5915D02*
G03I-4000J0D01*
G01X-3631D02*
G03I-2000J0D01*
G01X-12701Y-1620D02*
X-5631Y1915D01*
G01X-7874Y307086D02*
Y218273D01*
G01D02*
X-11609Y217029D01*
G01X-7874Y175427D02*
X-11609Y176672D01*
G01X-19685Y187877D02*
G03X-11608Y176672I11811J0D01*
G01Y217029D02*
G03X-19685Y205824I3734J-11205D01*
G01D02*
Y187877D01*
G01X-9118Y209559D02*
G03X-11811Y205824I1244J-3735D01*
G01Y187877D02*
G03X-9118Y184142I3937J0D01*
G01X-2692Y182000D02*
X-9119Y184142D01*
G01X-2692Y211701D02*
X-9119Y209559D01*
G01X-11811Y205824D02*
Y187877D01*
G01X-40658Y362205D02*
X-61131Y363446D01*
G01X0Y362205D02*
X-40658D01*
G01X-7874Y370079D02*
Y346456D01*
G01X0Y370079D02*
G03X-7874I-3937J0D01*
G01Y346456D02*
G03X0I3937J0D01*
G01Y307086D02*
G03X-7874I-3937J0D01*
G01Y409449D02*
G03X0I3937J0D01*
G01X-7874Y564010D02*
Y409449D01*
G01X-11811Y598343D02*
Y783037D01*
G01X-11608Y605612D02*
G03X-19685Y594406I3735J-11206D01*
G01D02*
Y576459D01*
G01X-7874Y564010D02*
X-11609Y565255D01*
G01X-19685Y576459D02*
G03X-11608Y565254I11811J0D01*
G01X-9118Y598141D02*
G03X-11811Y594406I1244J-3735D01*
G01Y576459D02*
G03X-9118Y572724I3937J0D01*
G01X-2692Y570582D02*
X-9119Y572725D01*
G01X-2692Y600284D02*
X-9119Y598141D01*
G01X-11811Y594406D02*
Y576459D01*
G01X-7874Y695669D02*
Y606856D01*
G01D02*
X-11609Y605611D01*
G01X-31496Y731850D02*
Y783037D01*
G01X-866Y709193D02*
G03I-4000J0D01*
G01X-2866D02*
G03I-2000J0D01*
G01X-13215Y723144D02*
G03I-4291J0D01*
G01X-7874Y738976D02*
G03X-11811Y742913I-3937J0D01*
G01X-16496D02*
G03X-31496Y727913I0J-15000D01*
G01X-7874Y735039D02*
G03X0I3937J0D01*
G01Y695669D02*
G03X-7874I-3937J0D01*
G01X-11811Y742913D02*
X-16496D01*
G01X-7874Y738976D02*
Y735039D01*
G01X-52098Y1006410D02*
Y989087D01*
G01X36520Y-7086D02*
X36555Y-7087D01*
G01X36484Y-7082D02*
X36520Y-7086D01*
G01X36449Y-7076D02*
X36484Y-7082D01*
G01X50532Y-8268D02*
G03X49351Y-7087I-1181J0D01*
G01X31673Y-3740D02*
G03X31437Y-3504I-236J0D01*
G01X31831Y-3740D02*
G03X31437Y-3347I-393J0D01*
G01Y-9095D02*
G03X31673Y-8858I0J236D01*
G01X31437Y-9252D02*
G03X31831Y-8858I0J394D01*
G01X29862Y-3504D02*
G03X29626Y-3740I0J-236D01*
G01X29862Y-3347D02*
G03X29469Y-3740I0J-393D01*
G01X19823Y-6496D02*
G03X20610Y-7284I788J0D01*
G01X21792Y-2559D02*
G03X24154I1181J0D01*
G01X29626Y-8858D02*
G03X29862Y-9095I237J0D01*
G01X29469Y-8858D02*
G03X29862Y-9252I394J0D01*
G01X22382Y-11418D02*
G03X23563Y-12599I1181J0D01*
G01X29075Y-26378D02*
G03X31044Y-24410I0J1969D01*
G01X0Y-22441D02*
G03X3937Y-26378I3937J0D01*
G01X35379Y-7076D02*
X35487Y-7015D01*
G01X43130Y-24331D02*
X41083Y-26378D01*
G01X43130Y-9134D02*
X45177Y-7087D01*
G01D02*
X43130Y-9134D01*
G01X26083Y-9646D02*
X25295Y-10433D01*
G01X35374Y-24332D02*
X34193Y-26378D01*
G01X36449Y-7076D02*
X39948Y394D01*
G01X38878D02*
X35374Y-7087D01*
G01X62402Y-4725D02*
X62540Y-788D01*
G01X59036Y-4725D02*
X59173Y-788D01*
G01X54173D02*
X54036Y-4725D01*
G01X64902Y-17126D02*
Y-788D01*
G01X64095D02*
Y-4725D01*
G01X61949D02*
Y-788D01*
G01X59095D02*
Y-4725D01*
G01X58583D02*
Y-788D01*
G01X63504D02*
X63642Y-4725D01*
G01X53583Y-788D02*
Y-4725D01*
G01X52225Y-788D02*
Y-4725D01*
G01X51122Y-788D02*
Y-4725D01*
G01X50532Y-8268D02*
Y-25197D01*
G01X48170Y394D02*
Y-7087D01*
G01X43130Y-9134D02*
Y-24331D01*
G01X58504Y-788D02*
X58642Y-4725D01*
G01X51634Y-788D02*
X51772Y-4725D01*
G01X50532Y-788D02*
X50669Y-4725D01*
G01X36555Y-26378D02*
Y-7087D01*
G01X35374D02*
Y-24332D01*
G01X32225Y9842D02*
Y-26378D01*
G01X31831Y-3740D02*
Y-8858D01*
G01X31680Y-3740D02*
Y-8858D01*
G01X31437Y-9101D02*
Y-9252D01*
G01X31044Y-24410D02*
Y-788D01*
G01X29862Y-9101D02*
Y-9252D01*
G01X29620Y-3740D02*
Y-8858D01*
G01X29469D02*
Y-3740D01*
G01X27894Y-10433D02*
Y6890D01*
G01X27107Y6102D02*
Y-9646D01*
G01X26122D02*
Y6102D01*
G01X26083Y-7992D02*
Y-9646D01*
G01X25532Y3740D02*
Y-7284D01*
G01X25295Y-10433D02*
Y-7992D01*
G01X22382D02*
Y-11418D01*
G01X19823Y2953D02*
Y-6496D01*
G01X0Y178265D02*
Y-22441D01*
G01X35487Y-7015D02*
X35722Y-6994D01*
G01X50532Y-25197D02*
X51713Y-26378D01*
G01X36520Y-7086D02*
X36484Y-7082D01*
G01X35722Y-6994D02*
X36055Y-7015D01*
G01X29620Y-3740D02*
X29469D01*
G01X31831D02*
X31680D01*
G01X50669Y-4725D02*
X62402D01*
G01X74036D02*
X63642D01*
G01X32225Y-7087D02*
X200453D01*
G01X27107Y-7284D02*
X20610D01*
G01X22382Y-7992D02*
X27107D01*
G01X26122Y-8071D02*
X27107D01*
G01X50532Y-8268D02*
X86792D01*
G01X26083Y-8386D02*
X27107D01*
G01X31680Y-8858D02*
X31831D01*
G01X26122D02*
X27107D01*
G01X29620D02*
X29469D01*
G01X29862Y-9101D02*
X31437D01*
G01X27107Y-9190D02*
X26122D01*
G01Y-9207D02*
X27107D01*
G01X31437Y-9252D02*
X29862D01*
G01X27107Y-9449D02*
X26122D01*
G01X27107Y-9544D02*
X26122D01*
G01X27107Y-9646D02*
X26083D01*
G01X25295Y-10433D02*
X27894D01*
G01X32225Y-10630D02*
X22382D01*
G01X23563Y-12599D02*
X32225D01*
G01X27107Y-9646D02*
X27894Y-10433D01*
G01X36055Y-7015D02*
X36449Y-7076D01*
G01X72776Y-17126D02*
X64902D01*
G01X36555Y-24332D02*
X43130D01*
G01D02*
X36555D01*
G01X35374D02*
X36555D01*
G01X87185Y-25197D02*
X50532D01*
G01X3937Y-26378D02*
X29075D01*
G01X41083D02*
X32225D01*
G01X180965D02*
X51713D01*
G01X59607Y2953D02*
G03X60000Y2559I394J0D01*
G01X62638D02*
G03X63032Y2953I0J394D01*
G01X64607D02*
G03X65000Y2559I394J0D01*
G01X67638D02*
G03X68032Y2953I0J394D01*
G01X69607D02*
G03X70000Y2559I394J0D01*
G01X60543Y-543D02*
G03X60738Y-105I-394J438D01*
G01X60294Y-768D02*
G03X60273Y-788I396J-437D01*
G01X62365D02*
G03X62345Y-768I-428J-408D01*
G01X61900Y-105D02*
G03X62095Y-543I589J0D01*
G01X65543D02*
G03X65738Y-105I-394J438D01*
G01X65294Y-768D02*
G03X65273Y-788I396J-437D01*
G01X67365D02*
G03X67345Y-768I-428J-408D01*
G01X66900Y-105D02*
G03X67095Y-543I589J0D01*
G01X70543D02*
G03X70738Y-105I-394J438D01*
G01X70294Y-768D02*
G03X70273Y-788I396J-437D01*
G01X71900Y-105D02*
G03X72095Y-543I589J0D01*
G01X52638Y2559D02*
G03X53032Y2953I0J394D01*
G01X54607D02*
G03X55000Y2559I394J0D01*
G01X57638D02*
G03X58032Y2953I0J394D01*
G01X51900Y-105D02*
G03X52095Y-543I589J0D01*
G01X55543D02*
G03X55738Y-105I-394J438D01*
G01X56900D02*
G03X57095Y-543I589J0D01*
G01X46595Y1181D02*
G03X47185Y1771I0J590D01*
G01X45020D02*
G03X45610Y1181I590J0D01*
G01Y7874D02*
G03X45020Y7283I0J-590D01*
G01X47185D02*
G03X46595Y7874I-591J0D01*
G01X52365Y-788D02*
G03X52345Y-768I-428J-408D01*
G01X55294D02*
G03X55273Y-788I396J-437D01*
G01X57365D02*
G03X57345Y-768I-428J-408D01*
G01X31437Y748D02*
G03X31673Y984I0J236D01*
G01Y6102D02*
G03X31437Y6338I-236J0D01*
G01X31831Y6102D02*
G03X31437Y6496I-394J0D01*
G01Y590D02*
G03X31831Y984I0J394D01*
G01X34784Y7874D02*
G03X34193Y7283I0J-591D01*
G01X38524D02*
G03X37933Y7874I-591J0D01*
G01Y1181D02*
G03X38524Y1771I0J591D01*
G01X34193D02*
G03X34784Y1181I590J0D01*
G01X43327Y5118D02*
G03I-1575J0D01*
G01X44114D02*
G03I-2362J0D01*
G01X44390D02*
G03I-2658J0D01*
G01X44705D02*
G03I-2953J0D01*
G01X33012Y1181D02*
G03X31044Y-788I0J-1968D01*
G01X29626Y984D02*
G03X29862Y748I236J0D01*
G01Y6338D02*
G03X29626Y6102I0J-236D01*
G01X29469Y984D02*
G03X29862Y590I394J0D01*
G01Y6496D02*
G03X29469Y6102I0J-393D01*
G01X20610Y3740D02*
G03X19823Y2953I0J-787D01*
G01X24154Y-984D02*
G03X21792I-1181J0D01*
G01X23563Y9055D02*
G03X22382Y7874I0J-1181D01*
G01X70543Y-543D02*
X70294Y-768D01*
G01X65543Y-543D02*
X65294Y-768D01*
G01X60543Y-543D02*
X60294Y-768D01*
G01X55543Y-543D02*
X55294Y-768D01*
G01X27894Y6890D02*
X27107Y6102D01*
G01X71900Y2559D02*
Y-105D01*
G01X70738Y2559D02*
Y-105D01*
G01X69607Y8472D02*
Y2953D01*
G01X68032Y8472D02*
Y2953D01*
G01X66900Y2559D02*
Y-105D01*
G01X65738Y2559D02*
Y-105D01*
G01X64607Y8472D02*
Y2953D01*
G01X63032Y8472D02*
Y2953D01*
G01X61900Y2559D02*
Y-105D01*
G01X60738Y2559D02*
Y-105D01*
G01X59607Y8472D02*
Y2953D01*
G01X58032Y8472D02*
Y2953D01*
G01X56900Y2559D02*
Y-105D01*
G01X55738Y2559D02*
Y-105D01*
G01X46192Y3937D02*
X46398Y9842D01*
G01X43642D02*
X43436Y3937D01*
G01X54607Y8472D02*
Y2953D01*
G01X53032Y8472D02*
Y2953D01*
G01X51900Y2559D02*
Y-105D01*
G01X49154Y9842D02*
Y-788D01*
G01X47185Y9842D02*
Y-788D01*
G01X45610Y3937D02*
Y9842D01*
G01X45020Y7283D02*
Y1771D01*
G01X44429Y3937D02*
Y9842D01*
G01X43051Y3937D02*
Y9842D01*
G01X40295D02*
Y3937D01*
G01X38918D02*
Y9842D01*
G01X38524Y7283D02*
Y1771D01*
G01X35374Y3937D02*
Y9842D01*
G01X34193Y-788D02*
Y9842D01*
G01X31831Y6102D02*
Y984D01*
G01X31680D02*
Y6102D01*
G01X31437Y6345D02*
Y6496D01*
G01Y-3347D02*
Y-3498D01*
G01Y742D02*
Y590D01*
G01X29862Y-3498D02*
Y-3347D01*
G01Y742D02*
Y590D01*
G01Y6496D02*
Y6345D01*
G01X29620Y6102D02*
Y984D01*
G01X29469D02*
Y6102D01*
G01X26083D02*
Y4449D01*
G01X25295D02*
Y6890D01*
G01X39705Y9842D02*
X39911Y3937D01*
G01X34793D02*
X34587Y9842D01*
G01X24154Y-984D02*
Y-2559D01*
G01X22382Y4449D02*
Y7874D01*
G01X21792Y-984D02*
Y-2559D01*
G01X72095Y-543D02*
X72345Y-768D01*
G01X67095Y-543D02*
X67345Y-768D01*
G01X62095Y-543D02*
X62345Y-768D01*
G01X57095Y-543D02*
X57345Y-768D01*
G01X52095Y-543D02*
X52345Y-768D01*
G01X49154Y9842D02*
X32225D01*
G01X23563Y9055D02*
X32225D01*
G01X54607Y8472D02*
X53032D01*
G01X59607D02*
X58032D01*
G01X64607D02*
X63032D01*
G01X69607D02*
X68032D01*
G01X37933Y7874D02*
X34784D01*
G01X46595D02*
X45610D01*
G01X32225Y7086D02*
X22382D01*
G01X25295Y6890D02*
X27894D01*
G01X29862Y6496D02*
X31437D01*
G01X29862Y6345D02*
X31437D01*
G01X54607Y6110D02*
X53032D01*
G01X59607D02*
X58032D01*
G01X64607D02*
X63032D01*
G01X69607D02*
X68032D01*
G01X31680Y6102D02*
X31831D01*
G01X29469D02*
X29620D01*
G01X27107D02*
X26083D01*
G01X26122Y5998D02*
X27107D01*
G01Y5905D02*
X26122D01*
G01X27107Y5663D02*
X26122D01*
G01X27107Y5647D02*
X26122D01*
G01X68032Y5365D02*
X69607D01*
G01X63032D02*
X64607D01*
G01X58032D02*
X59607D01*
G01X53032D02*
X54607D01*
G01X26122Y5315D02*
X27107D01*
G01Y4842D02*
X26083D01*
G01X54607Y4621D02*
X53032D01*
G01X59607D02*
X58032D01*
G01X64607D02*
X63032D01*
G01X69607D02*
X68032D01*
G01Y4547D02*
X69607D01*
G01X63032D02*
X64607D01*
G01X58032D02*
X59607D01*
G01X53032D02*
X54607D01*
G01X26122Y4527D02*
X27107D01*
G01Y4449D02*
X22382D01*
G01X34793Y3937D02*
X46192D01*
G01X54607Y3802D02*
X53032D01*
G01X59607D02*
X58032D01*
G01X64607D02*
X63032D01*
G01X69607D02*
X68032D01*
G01X20610Y3740D02*
X27107D01*
G01X54607Y3058D02*
X53032D01*
G01X59607D02*
X58032D01*
G01X64607D02*
X63032D01*
G01X69607D02*
X68032D01*
G01X52638Y2559D02*
X51900D01*
G01X55738D02*
X55000D01*
G01X57638D02*
X56900D01*
G01X60738D02*
X60000D01*
G01X62638D02*
X61900D01*
G01X65738D02*
X65000D01*
G01X67638D02*
X66900D01*
G01X70738D02*
X70000D01*
G01X72638D02*
X71900D01*
G01X33012Y1181D02*
X199666D01*
G01X31680Y984D02*
X31831D01*
G01X29620D02*
X29469D01*
G01X29862Y742D02*
X31437D01*
G01Y590D02*
X29862D01*
G01X48170Y394D02*
X38878D01*
G01X200453Y-788D02*
X32225D01*
G01X25295Y6890D02*
X26083Y6102D01*
G01X29862Y-3347D02*
X31437D01*
G01Y-3498D02*
X29862D01*
G01X71407Y128987D02*
G03X76975Y134555I2784J2784D01*
G01X23664Y128862D02*
X23819Y128838D01*
G01X23528Y128932D02*
X23664Y128862D01*
G01X23418Y129046D02*
X23528Y128932D01*
G01X23348Y129186D02*
X23418Y129046D01*
G01X23327Y129331D02*
X23348Y129186D01*
G01X23664Y145791D02*
X23819Y145768D01*
G01X23528Y145861D02*
X23664Y145791D01*
G01X23418Y145975D02*
X23528Y145861D01*
G01X23348Y146115D02*
X23418Y145975D01*
G01X23327Y146260D02*
X23348Y146115D01*
G01X24294Y146131D02*
X24274Y146069D01*
G01X24307Y146195D02*
X24294Y146131D01*
G01X24311Y146260D02*
X24307Y146195D01*
G01X24294Y129202D02*
X24274Y129139D01*
G01X24307Y129266D02*
X24294Y129202D01*
G01X24311Y129331D02*
X24307Y129266D01*
G01X24063Y145832D02*
X24006Y145803D01*
G01X24112Y145865D02*
X24063Y145832D01*
G01X24156Y145901D02*
X24112Y145865D01*
G01X24191Y145937D02*
X24156Y145901D01*
G01X24217Y145970D02*
X24191Y145937D01*
G01X24246Y146013D02*
X24217Y145970D01*
G01X24263Y146044D02*
X24246Y146013D01*
G01X24274Y146069D02*
X24263Y146044D01*
G01X40593Y128862D02*
X40748Y128838D01*
G01X40458Y128932D02*
X40593Y128862D01*
G01X40347Y129046D02*
X40458Y128932D01*
G01X40277Y129186D02*
X40347Y129046D01*
G01X40256Y129331D02*
X40277Y129186D01*
G01X40593Y145791D02*
X40748Y145768D01*
G01X40458Y145861D02*
X40593Y145791D01*
G01X40347Y145975D02*
X40458Y145861D01*
G01X40277Y146115D02*
X40347Y145975D01*
G01X40256Y146260D02*
X40277Y146115D01*
G01X41224Y146131D02*
X41203Y146069D01*
G01X41236Y146195D02*
X41224Y146131D01*
G01X41240Y146260D02*
X41236Y146195D01*
G01X41224Y129202D02*
X41203Y129139D01*
G01X41236Y129266D02*
X41224Y129202D01*
G01X41240Y129331D02*
X41236Y129266D01*
G01X24063Y128903D02*
X24006Y128874D01*
G01X24112Y128936D02*
X24063Y128903D01*
G01X24156Y128972D02*
X24112Y128936D01*
G01X24191Y129008D02*
X24156Y128972D01*
G01X24217Y129040D02*
X24191Y129008D01*
G01X24246Y129083D02*
X24217Y129040D01*
G01X24263Y129115D02*
X24246Y129083D01*
G01X24274Y129139D02*
X24263Y129115D01*
G01X40992Y145832D02*
X40935Y145803D01*
G01X41042Y145865D02*
X40992Y145832D01*
G01X41085Y145901D02*
X41042Y145865D01*
G01X41120Y145937D02*
X41085Y145901D01*
G01X41147Y145970D02*
X41120Y145937D01*
G01X41175Y146013D02*
X41147Y145970D01*
G01X41192Y146044D02*
X41175Y146013D01*
G01X41203Y146069D02*
X41192Y146044D01*
G01X23335Y129238D02*
X23327Y129331D01*
G01X23358Y129157D02*
X23335Y129238D01*
G01X23390Y129090D02*
X23358Y129157D01*
G01X23427Y129033D02*
X23390Y129090D01*
G01X23469Y128985D02*
X23427Y129033D01*
G01X23510Y128947D02*
X23469Y128985D01*
G01X23551Y128916D02*
X23510Y128947D01*
G01X23595Y128891D02*
X23551Y128916D01*
G01X23628Y128875D02*
X23595Y128891D01*
G01X40264Y129238D02*
X40256Y129331D01*
G01X40287Y129157D02*
X40264Y129238D01*
G01X40319Y129090D02*
X40287Y129157D01*
G01X40357Y129033D02*
X40319Y129090D01*
G01X40398Y128985D02*
X40357Y129033D01*
G01X40439Y128947D02*
X40398Y128985D01*
G01X40480Y128916D02*
X40439Y128947D01*
G01X40524Y128891D02*
X40480Y128916D01*
G01X40557Y128875D02*
X40524Y128891D01*
G01X40992Y128903D02*
X40935Y128874D01*
G01X41042Y128936D02*
X40992Y128903D01*
G01X41085Y128972D02*
X41042Y128936D01*
G01X41120Y129008D02*
X41085Y128972D01*
G01X41147Y129040D02*
X41120Y129008D01*
G01X41175Y129083D02*
X41147Y129040D01*
G01X41192Y129115D02*
X41175Y129083D01*
G01X41203Y129139D02*
X41192Y129115D01*
G01X23335Y146167D02*
X23327Y146260D01*
G01X23358Y146087D02*
X23335Y146167D01*
G01X23390Y146019D02*
X23358Y146087D01*
G01X23427Y145962D02*
X23390Y146019D01*
G01X23469Y145914D02*
X23427Y145962D01*
G01X23510Y145876D02*
X23469Y145914D01*
G01X23551Y145846D02*
X23510Y145876D01*
G01X23595Y145820D02*
X23551Y145846D01*
G01X23628Y145804D02*
X23595Y145820D01*
G01X40264Y146167D02*
X40256Y146260D01*
G01X40287Y146087D02*
X40264Y146167D01*
G01X40319Y146019D02*
X40287Y146087D01*
G01X40357Y145962D02*
X40319Y146019D01*
G01X40398Y145914D02*
X40357Y145962D01*
G01X40439Y145876D02*
X40398Y145914D01*
G01X40480Y145846D02*
X40439Y145876D01*
G01X40524Y145820D02*
X40480Y145846D01*
G01X40557Y145804D02*
X40524Y145820D01*
G01X23690Y128855D02*
X23628Y128875D01*
G01X23754Y128843D02*
X23690Y128855D01*
G01X23819Y128838D02*
X23754Y128843D01*
G01X40619Y128855D02*
X40557Y128875D01*
G01X40683Y128843D02*
X40619Y128855D01*
G01X40748Y128838D02*
X40683Y128843D01*
G01X23850Y145768D02*
X23819D01*
G01X23877Y145770D02*
X23850Y145768D01*
G01X23904Y145774D02*
X23877Y145770D01*
G01X23928Y145779D02*
X23904Y145774D01*
G01X23951Y145784D02*
X23928Y145779D01*
G01X23971Y145790D02*
X23951Y145784D01*
G01X23992Y145797D02*
X23971Y145790D01*
G01X24006Y145803D02*
X23992Y145797D01*
G01X41216Y129175D02*
X41240Y129331D01*
G01X41149Y129043D02*
X41216Y129175D01*
G01X41035Y128931D02*
X41149Y129043D01*
G01X40902Y128861D02*
X41035Y128931D01*
G01X40748Y128838D02*
X40902Y128861D01*
G01X24287Y129175D02*
X24311Y129331D01*
G01X24220Y129043D02*
X24287Y129175D01*
G01X24106Y128931D02*
X24220Y129043D01*
G01X23972Y128861D02*
X24106Y128931D01*
G01X23819Y128838D02*
X23972Y128861D01*
G01X23690Y145784D02*
X23628Y145804D01*
G01X23754Y145772D02*
X23690Y145784D01*
G01X23819Y145768D02*
X23754Y145772D01*
G01X40619Y145784D02*
X40557Y145804D01*
G01X40683Y145772D02*
X40619Y145784D01*
G01X40748Y145768D02*
X40683Y145772D01*
G01X40779Y145768D02*
X40748D01*
G01X40806Y145770D02*
X40779Y145768D01*
G01X40833Y145774D02*
X40806Y145770D01*
G01X40857Y145779D02*
X40833Y145774D01*
G01X40880Y145784D02*
X40857Y145779D01*
G01X40900Y145790D02*
X40880Y145784D01*
G01X40921Y145797D02*
X40900Y145790D01*
G01X40935Y145803D02*
X40921Y145797D01*
G01X23850Y128839D02*
X23819Y128838D01*
G01X23877Y128841D02*
X23850Y128839D01*
G01X23904Y128845D02*
X23877Y128841D01*
G01X23928Y128850D02*
X23904Y128845D01*
G01X23951Y128855D02*
X23928Y128850D01*
G01X23971Y128861D02*
X23951Y128855D01*
G01X23992Y128868D02*
X23971Y128861D01*
G01X24006Y128874D02*
X23992Y128868D01*
G01X41216Y146104D02*
X41240Y146260D01*
G01X41149Y145972D02*
X41216Y146104D01*
G01X41035Y145860D02*
X41149Y145972D01*
G01X40902Y145790D02*
X41035Y145860D01*
G01X40748Y145768D02*
X40902Y145790D01*
G01X24287Y146104D02*
X24311Y146260D01*
G01X24220Y145972D02*
X24287Y146104D01*
G01X24106Y145860D02*
X24220Y145972D01*
G01X23972Y145790D02*
X24106Y145860D01*
G01X23819Y145768D02*
X23972Y145790D01*
G01X40779Y128839D02*
X40748Y128838D01*
G01X40806Y128841D02*
X40779Y128839D01*
G01X40833Y128845D02*
X40806Y128841D01*
G01X40857Y128850D02*
X40833Y128845D01*
G01X40880Y128855D02*
X40857Y128850D01*
G01X40900Y128861D02*
X40880Y128855D01*
G01X40921Y128868D02*
X40900Y128861D01*
G01X40935Y128874D02*
X40921Y128868D01*
G01X64567Y137457D02*
G03X65720Y134673I3938J0D01*
G01X41221Y146260D02*
G03X40276I-472J0D01*
G01X42421D02*
G03I-1673J0D01*
G01X42520D02*
G03I-1772J0D01*
G01X38191Y137795D02*
G03I-5907J0D01*
G01X39173D02*
G03I-6889J0D01*
G01X39475D02*
G03I-7191J0D01*
G01X39567D02*
G03I-7283J0D01*
G01X36949Y128950D02*
G03X41129Y133130I-4665J8845D01*
G01Y142460D02*
G03X36949Y146640I-8845J-4665D01*
G01X27618D02*
G03X23439Y142460I4667J-8844D01*
G01Y133130D02*
G03X27618Y128950I8846J4664D01*
G01X42520Y137795D02*
G03I-10236J0D01*
G01X41221Y129331D02*
G03X40276I-472J0D01*
G01X42914Y125590D02*
G03X44488Y127165I0J1574D01*
G01X42421Y129331D02*
G03I-1673J0D01*
G01X42520D02*
G03I-1772J0D01*
G01X24292Y146260D02*
G03X23347I-473J0D01*
G01X25492D02*
G03I-1673J0D01*
G01X25591D02*
G03I-1772J0D01*
G01X24292Y129331D02*
G03X23347I-473J0D01*
G01X20079Y127165D02*
G03X21654Y125590I1575J0D01*
G01X25492Y129331D02*
G03I-1673J0D01*
G01X25591D02*
G03I-1772J0D01*
G01X13744Y146471D02*
X13662Y146454D01*
G01X51178Y147030D02*
X51293Y147047D01*
G01X51276Y146963D02*
X51194Y146947D01*
G01X50752Y146628D02*
X50670Y146611D01*
G01X43898Y143701D02*
X43307Y143542D01*
G01X20670Y131890D02*
X21260Y132048D01*
G01X50686Y146712D02*
X50735Y146729D01*
G01X51358Y147047D02*
X51457Y147030D01*
G01X51293Y147047D02*
X51358D01*
G01X50276D02*
X50670D01*
G01X50686Y146963D02*
X50374D01*
G01X51342D02*
X51276D01*
G01X14105Y146890D02*
X14203D01*
G01X13268D02*
X13662D01*
G01X51112Y146863D02*
X51030D01*
G01X13678Y146806D02*
X13366D01*
G01X50374Y146712D02*
X50686D01*
G01X50670Y146611D02*
X50374D01*
G01X13366Y146555D02*
X13678D01*
G01X13662Y146454D02*
X13366D01*
G01X51145Y146343D02*
X51605D01*
G01X50374Y146260D02*
X50276D01*
G01X51605D02*
X51014D01*
G01X13366Y146102D02*
X13268D01*
G01X14203D02*
X14105D01*
G01X50000Y145275D02*
X14567D01*
G01X23439Y142461D02*
X21654D01*
G01X42914D02*
X41129D01*
G01X13678Y146555D02*
X13727Y146571D01*
G01X51112Y146997D02*
X51178Y147030D01*
G01X51194Y146947D02*
X51145Y146913D01*
G01X50817Y146678D02*
X50752Y146628D01*
G01X50735Y146947D02*
X50686Y146963D01*
G01X51424Y146947D02*
X51342Y146963D01*
G01X50670Y147047D02*
X50752Y147030D01*
G01X13662Y146890D02*
X13744Y146873D01*
G01X41129Y133130D02*
X42914D01*
G01X21654D02*
X23439D01*
G01X50000Y130315D02*
X14567D01*
G01X50000Y127559D02*
X14567D01*
G01X27618Y127165D02*
X36949D01*
G01X38031Y126771D02*
X26536D01*
G01X26378Y126181D02*
X20670D01*
G01X43898D02*
X38189D01*
G01X42914Y125590D02*
X21654D01*
G01X51555Y146712D02*
X51145Y146343D01*
G01X51014D02*
X51473Y146762D01*
G01X51047Y146930D02*
X51112Y146997D01*
G01X50735Y146729D02*
X50768Y146762D01*
G01X50866Y146745D02*
X50817Y146678D01*
G01X51588Y146762D02*
X51555Y146712D01*
G01X51145Y146913D02*
X51112Y146863D01*
G01X51523Y146997D02*
X51588Y146930D01*
G01X50768Y146913D02*
X50735Y146947D01*
G01X65720Y134673D02*
X94910Y105484D01*
G01X50752Y147030D02*
X50817Y146980D01*
G01X51473Y146913D02*
X51424Y146947D01*
G01X51457Y147030D02*
X51523Y146997D01*
G01X13727Y146789D02*
X13678Y146806D01*
G01X21260Y143542D02*
X20670Y143701D01*
G01X43307Y132048D02*
X43898Y131890D01*
G01X13809Y146521D02*
X13744Y146471D01*
G01X51473Y146762D02*
X51506Y146829D01*
G01X50883Y146796D02*
X50866Y146745D01*
G01X50768Y146762D02*
X50784Y146813D01*
G01X51605Y146829D02*
X51588Y146762D01*
G01X51030Y146863D02*
X51047Y146930D01*
G01X64567Y137457D02*
Y249131D01*
G01X51588Y146930D02*
X51605Y146863D01*
G01X50866Y146913D02*
X50883Y146863D01*
G01X50784D02*
X50768Y146913D01*
G01X51506Y146863D02*
X51473Y146913D01*
G01X50817Y146980D02*
X50866Y146913D01*
G01X13727Y146571D02*
X13760Y146605D01*
G01X14105Y146756D02*
X14006Y146638D01*
G01Y146772D02*
X14105Y146890D01*
G01X13858Y146588D02*
X13809Y146521D01*
G01X51605Y146343D02*
Y146260D01*
G01Y146863D02*
Y146829D01*
G01X51506D02*
Y146863D01*
G01X51014Y146260D02*
Y146343D01*
G01X50883Y146863D02*
Y146796D01*
G01X50784Y146813D02*
Y146863D01*
G01X50374Y146963D02*
Y146712D01*
G01Y146611D02*
Y146260D01*
G01X50276D02*
Y147047D01*
G01X50000Y130315D02*
Y127559D01*
G01Y148031D02*
Y145275D01*
G01X47102Y130315D02*
Y127559D01*
G01Y148031D02*
Y145275D01*
G01X46330D02*
Y148031D01*
G01Y127559D02*
Y130315D01*
G01X45986Y145275D02*
Y148031D01*
G01Y127559D02*
Y130315D01*
G01X45172Y145275D02*
Y148031D01*
G01Y127559D02*
Y130315D01*
G01X44828Y145275D02*
Y148031D01*
G01Y127559D02*
Y130315D01*
G01X44488Y148425D02*
Y127165D01*
G01X44056Y130315D02*
Y127559D01*
G01Y148031D02*
Y145275D01*
G01X43898Y131890D02*
Y126181D01*
G01Y149409D02*
Y143701D01*
G01X43307Y143542D02*
Y132048D01*
G01X42914Y133130D02*
Y142461D01*
G01X38189Y126181D02*
X38031Y126771D01*
G01X13760Y146756D02*
X13727Y146789D01*
G01X13744Y146873D02*
X13809Y146823D01*
G01X26536Y126771D02*
X26378Y126181D01*
G01X36949Y146640D02*
Y148425D01*
G01Y127165D02*
Y128950D01*
G01X27618D02*
Y127165D01*
G01Y148425D02*
Y146640D01*
G01X13858Y146756D02*
X13875Y146705D01*
G01X13776D02*
X13760Y146756D01*
G01X13809Y146823D02*
X13858Y146756D01*
G01X13875Y146638D02*
X13858Y146588D01*
G01X13760Y146605D02*
X13776Y146655D01*
G01X21654Y142461D02*
Y133130D01*
G01X21260Y143542D02*
Y132048D01*
G01X20670Y131890D02*
Y126181D01*
G01Y149409D02*
Y143701D01*
G01X20321Y145275D02*
Y148031D01*
G01Y127559D02*
Y130315D01*
G01X20079Y127165D02*
Y148425D01*
G01X19573Y130315D02*
Y127559D01*
G01Y148031D02*
Y145275D01*
G01X18899Y130315D02*
Y127559D01*
G01Y148031D02*
Y145275D01*
G01X18452Y130315D02*
Y127559D01*
G01Y148031D02*
Y145275D01*
G01X17777Y130315D02*
Y127559D01*
G01Y148031D02*
Y145275D01*
G01X17029D02*
Y148031D01*
G01Y127559D02*
Y130315D01*
G01X14567Y145275D02*
Y148031D01*
G01Y130315D02*
Y127559D01*
G01X14203Y146890D02*
Y146102D01*
G01X14105D02*
Y146756D01*
G01X14006Y146638D02*
Y146772D01*
G01X13875Y146705D02*
Y146638D01*
G01X13776Y146655D02*
Y146705D01*
G01X13366Y146806D02*
Y146555D01*
G01Y146454D02*
Y146102D01*
G01X13268D02*
Y146890D01*
G01X21072Y221168D02*
X21131Y221180D01*
G01X21036Y221155D02*
X21072Y221168D01*
G01X21024Y221142D02*
X21036Y221155D01*
G01X31894Y221140D02*
X31735Y221070D01*
G01X32022Y221275D02*
X31894Y221140D01*
G01X32104Y221455D02*
X32022Y221275D01*
G01X32131Y221653D02*
X32104Y221455D01*
G01X34149Y211635D02*
X33919Y211614D01*
G01X34359Y211696D02*
X34149Y211635D01*
G01X34531Y211792D02*
X34359Y211696D01*
G01X34650Y211914D02*
X34531Y211792D01*
G01X34705Y212052D02*
X34650Y211914D01*
G01X42543Y221874D02*
X42448Y221827D01*
G01X42630Y221991D02*
X42543Y221874D01*
G01X42698Y222165D02*
X42630Y221991D01*
G01X42742Y222381D02*
X42698Y222165D01*
G01X42756Y222613D02*
X42742Y222381D01*
G01X31805Y223569D02*
X31909Y223702D01*
G01X31740Y223404D02*
X31805Y223569D01*
G01X31719Y223228D02*
X31740Y223404D01*
G01X34982Y212201D02*
X35008Y212192D01*
G01X34956Y212148D02*
X34982Y212201D01*
G01X34933Y212039D02*
X34956Y212148D01*
G01X38259Y173361D02*
X38189Y173614D01*
G01X38259Y173097D02*
Y173361D01*
G01X38189Y172842D02*
X38259Y173097D01*
G01X37566Y172285D02*
X37284Y172244D01*
G01X37826Y172407D02*
X37566Y172285D01*
G01X38040Y172598D02*
X37826Y172407D01*
G01X38189Y172842D02*
X38040Y172598D01*
G01X29612Y212147D02*
X29634Y212039D01*
G01X29586Y212201D02*
X29612Y212147D01*
G01X29560Y212192D02*
X29586Y212201D01*
G01X30331Y210703D02*
X30561Y210682D01*
G01X30121Y210764D02*
X30331Y210703D01*
G01X29950Y210860D02*
X30121Y210764D01*
G01X29831Y210982D02*
X29950Y210860D01*
G01X29775Y211120D02*
X29831Y210982D01*
G01X29599Y213376D02*
X29534Y213353D01*
G01X29664Y213243D02*
X29599Y213376D01*
G01X29721Y212971D02*
X29664Y213243D01*
G01X42346Y221151D02*
X42327Y221155D01*
G01X42358Y221146D02*
X42346Y221151D01*
G01X42362Y221142D02*
X42358Y221146D01*
G01X38040Y173858D02*
X38189Y173614D01*
G01X37827Y174049D02*
X38040Y173858D01*
G01X37567Y174171D02*
X37827Y174049D01*
G01X37284Y174212D02*
X37567Y174171D01*
G01X21826Y222381D02*
X21811Y222613D01*
G01X21869Y222166D02*
X21826Y222381D01*
G01X21937Y221991D02*
X21869Y222166D01*
G01X22024Y221875D02*
X21937Y221991D01*
G01X22120Y221827D02*
X22024Y221875D01*
G01X37586Y174165D02*
X37284Y174212D01*
G01X37860Y174026D02*
X37586Y174165D01*
G01X38079Y173808D02*
X37860Y174026D01*
G01X38219Y173534D02*
X38079Y173808D01*
G01X38268Y173229D02*
X38219Y173534D01*
G01X38220Y172925D02*
X38268Y173229D01*
G01X38081Y172650D02*
X38220Y172925D01*
G01X37863Y172432D02*
X38081Y172650D01*
G01X37587Y172292D02*
X37863Y172432D01*
G01X37284Y172244D02*
X37587Y172292D01*
G01X21038Y221797D02*
X21045Y221796D01*
G01X21031Y221799D02*
X21038Y221797D01*
G01X21024Y221801D02*
X21031Y221799D01*
G01X34903Y213243D02*
X34846Y212971D01*
G01X34968Y213376D02*
X34903Y213243D01*
G01X35033Y213353D02*
X34968Y213376D01*
G01X29917Y211914D02*
X29862Y212052D01*
G01X30036Y211792D02*
X29917Y211914D01*
G01X30208Y211696D02*
X30036Y211792D01*
G01X30418Y211635D02*
X30208Y211696D01*
G01X30648Y211614D02*
X30418Y211635D01*
G01X43532Y221155D02*
X43544Y221142D01*
G01X43496Y221168D02*
X43532Y221155D01*
G01X43437Y221180D02*
X43496Y221168D01*
G01X24138Y221404D02*
X23780Y221386D01*
G01X24404Y221427D02*
X24138Y221404D01*
G01X24547Y221455D02*
X24404Y221427D01*
G01X24552Y221484D02*
X24547Y221455D01*
G01X24425Y221512D02*
X24552Y221484D01*
G01X34738Y210984D02*
X34792Y211120D01*
G01X34619Y210860D02*
X34738Y210984D01*
G01X34446Y210764D02*
X34619Y210860D01*
G01X34233Y210702D02*
X34446Y210764D01*
G01X34006Y210682D02*
X34233Y210702D01*
G01X23385Y221473D02*
X23350Y221481D01*
G01X23367Y221464D02*
X23385Y221473D01*
G01X23297Y221455D02*
X23367Y221464D01*
G01X23189Y221450D02*
X23297Y221455D01*
G01X23532Y221374D02*
X23491Y221369D01*
G01X23591Y221378D02*
X23532Y221374D01*
G01X23664Y221382D02*
X23591Y221378D01*
G01X42024Y221414D02*
X42186Y221394D01*
G01X41786Y221432D02*
X42024Y221414D01*
G01X41494Y221446D02*
X41786Y221432D01*
G01X40015Y221484D02*
X40142Y221512D01*
G01X40020Y221455D02*
X40015Y221484D01*
G01X40163Y221428D02*
X40020Y221455D01*
G01X40429Y221404D02*
X40163Y221428D01*
G01X40787Y221386D02*
X40429Y221404D01*
G01X40976Y221378D02*
X40903Y221382D01*
G01X41036Y221374D02*
X40976Y221378D01*
G01X41077Y221369D02*
X41036Y221374D01*
G01X41270Y221455D02*
X41378Y221450D01*
G01X41200Y221463D02*
X41270Y221455D01*
G01X41182Y221473D02*
X41200Y221463D01*
G01X41217Y221481D02*
X41182Y221473D01*
G01X22209Y221146D02*
X22205Y221142D01*
G01X22221Y221151D02*
X22209Y221146D01*
G01X22241Y221155D02*
X22221Y221151D01*
G01X31697Y221475D02*
X31719Y221653D01*
G01X31632Y221312D02*
X31697Y221475D01*
G01X31529Y221180D02*
X31632Y221312D01*
G01X31397Y221093D02*
X31529Y221180D01*
G01X31247Y221063D02*
X31397Y221093D01*
G01X32153Y223403D02*
X32131Y223228D01*
G01X32218Y223568D02*
X32153Y223403D01*
G01X32321Y223702D02*
X32218Y223568D01*
G01X31686Y221064D02*
X31661Y221063D01*
G01X31711Y221066D02*
X31686Y221064D01*
G01X31735Y221070D02*
X31711Y221066D01*
G01X43536Y221799D02*
X43544Y221801D01*
G01X43529Y221797D02*
X43536Y221799D01*
G01X43522Y221796D02*
X43529Y221797D01*
G01X22782Y221432D02*
X23073Y221446D01*
G01X22544Y221414D02*
X22782Y221432D01*
G01X22381Y221394D02*
X22544Y221414D01*
G01X37008Y214370D02*
G03X39528Y216890I0J2520D01*
G01X40315Y212992D02*
G03X41103Y213779I0J788D01*
G01X38268Y173228D02*
G03I-984J0D01*
G01X41103Y211614D02*
G03X42362Y212874I0J1259D01*
G01X40315Y211811D02*
G03X42284Y213779I0J1969D01*
G01X37795Y207086D02*
G03X39764Y209055I0J1969D01*
G01X44882Y214173D02*
G03X46851Y216142I0J1969D01*
G01X41103Y210433D02*
G03X43544Y212874I0J2441D01*
G01X38189Y173228D02*
G03I-5905J0D01*
G01X40158D02*
G03I-7874J0D01*
G01X23465Y213779D02*
G03X24252Y212992I787J0D01*
G01X28268Y173228D02*
G03I-984J0D01*
G01X22205Y212874D02*
G03X23465Y211614I1260J0D01*
G01X22284Y213779D02*
G03X24252Y211811I1968J0D01*
G01X17717Y216142D02*
G03X19685Y214173I1969J0D01*
G01X24803Y209055D02*
G03X26772Y207086I1969J0D01*
G01X21024Y212874D02*
G03X23465Y210433I2441J0D01*
G01X-2692Y211701D02*
G03X0Y215436I-1245J3735D01*
G01Y178265D02*
G03X-2692Y182000I-3937J0D01*
G01X44488Y148425D02*
G03X42914Y150000I-1575J0D01*
G01X21654D02*
G03X20079Y148425I0J-1575D01*
G01X40142Y221512D02*
X42448Y221827D01*
G01X43522Y221796D02*
X41217Y221481D01*
G01X21131Y221180D02*
X22381Y221394D01*
G01X23491Y221369D02*
X22241Y221155D01*
G01X41378Y221450D02*
X41494Y221446D01*
G01X40903Y221382D02*
X40787Y221386D01*
G01X42448Y221827D02*
X43522Y221796D01*
G01X39528Y223523D02*
X33347D01*
G01X37264Y223504D02*
X38051D01*
G01X37264Y223425D02*
X38051D01*
G01Y223350D02*
X37264D01*
G01Y223327D02*
X38051D01*
G01Y223291D02*
X37264D01*
G01X31719Y223228D02*
X32131D01*
G01X28839D02*
X27855D01*
G01X38051Y223203D02*
X37264D01*
G01X38051Y223179D02*
X37264D01*
G01Y223149D02*
X38051D01*
G01X37264Y223031D02*
X38051D01*
G01X28839D02*
X27855D01*
G01X38150Y222953D02*
X33071D01*
G01X33386Y222933D02*
X38051D01*
G01X42756Y222602D02*
X43543D01*
G01X24173Y222441D02*
X21024D01*
G01X43544D02*
X40394D01*
G01X36418Y222244D02*
X38780D01*
G01X24410Y222047D02*
X22284D01*
G01X38583D02*
X37264D01*
G01X42284D02*
X40158D01*
G01X28839Y221850D02*
X27855D01*
G01X31719Y221653D02*
X32131D01*
G01X28839D02*
X27855D01*
G01X39528D02*
X34318D01*
G01X38583Y221260D02*
X37795D01*
G01Y221063D02*
X38583D01*
G01X33268D02*
X30118D01*
G01X22205Y220905D02*
X21024D01*
G01X43544D02*
X42362D01*
G01X32284Y220890D02*
X33268D01*
G01X42362Y220877D02*
X43544D01*
G01X21024D02*
X22205D01*
G01X42362Y220866D02*
X43544D01*
G01X22205D02*
X21024D01*
G01X27855Y220472D02*
X33268D01*
G01X26477Y220275D02*
X34744D01*
G01X22205Y220092D02*
X21024D01*
G01X43544D02*
X42362D01*
G01X33347Y220079D02*
X27756D01*
G01X33268Y219980D02*
X32284D01*
G01X37795Y219882D02*
X38583D01*
G01X33268D02*
X32284D01*
G01Y219811D02*
X33268D01*
G01Y219764D02*
X32284D01*
G01Y219714D02*
X33268D01*
G01X38583Y219685D02*
X37795D01*
G01X32284Y219622D02*
X33268D01*
G01X33347Y219449D02*
X32284D01*
G01X39528Y219291D02*
X34318D01*
G01X42362Y219094D02*
X43544D01*
G01X22205D02*
X21024D01*
G01X37264Y218897D02*
X38583D01*
G01X36418Y218701D02*
X38780D01*
G01X22205Y218307D02*
X21024D01*
G01X43544D02*
X42362D01*
G01X38051Y218012D02*
X33386D01*
G01X38150Y217992D02*
X33071D01*
G01X37264Y217913D02*
X38051D01*
G01Y217795D02*
X37264D01*
G01Y217766D02*
X38051D01*
G01X37264Y217742D02*
X38051D01*
G01X32284Y217716D02*
X28347D01*
G01X37264Y217654D02*
X38051D01*
G01Y217618D02*
X37264D01*
G01Y217594D02*
X38051D01*
G01Y217519D02*
X37264D01*
G01X38051Y217441D02*
X37264D01*
G01X38150Y217421D02*
X37166D01*
G01X22205Y216338D02*
X21024D01*
G01X40158D02*
X24410D01*
G01X43544D02*
X42362D01*
G01X43465Y216142D02*
X21103D01*
G01X22205Y215551D02*
X21024D01*
G01X31890D02*
X28740D01*
G01X43544D02*
X42362D01*
G01X22284Y214960D02*
X21103D01*
G01X32284D02*
X28347D01*
G01X43465D02*
X42284D01*
G01X37008Y214370D02*
X32284D01*
G01X42362Y214173D02*
X44882D01*
G01X22205D02*
X19685D01*
G01X41103Y213779D02*
X42284D01*
G01X22284D02*
X23465D01*
G01X42362Y213386D02*
X43544D01*
G01X21024D02*
X22205D01*
G01X34991D02*
X29577D01*
G01X35033Y213353D02*
X29534D01*
G01X40315Y212992D02*
X24252D01*
G01X29721Y212971D02*
X34846D01*
G01X34991Y212205D02*
X29577D01*
G01X35008Y212192D02*
X29560D01*
G01X29634Y212039D02*
X34933D01*
G01X43465Y211811D02*
X21103D01*
G01X21024Y222591D02*
X21811Y222613D01*
G01X21045Y221796D02*
X22120Y221827D01*
G01X23073Y221446D02*
X23189Y221450D01*
G01X23780Y221386D02*
X23664Y221382D01*
G01X42186Y221394D02*
X43437Y221180D01*
G01X42327Y221155D02*
X41077Y221369D01*
G01X22120Y221827D02*
X24425Y221512D01*
G01X23350Y221481D02*
X21045Y221796D01*
G01X19529Y211614D02*
X45039D01*
G01X34006Y210682D02*
X30561D01*
G01X19529Y210433D02*
X45039D01*
G01X39764Y209645D02*
X24803D01*
G01X37795Y207086D02*
X26772D01*
G01X45241Y173794D02*
X45414Y173819D01*
G01X27284Y174212D02*
X26980Y174164D01*
G01X37284Y174212D02*
X36980Y174164D01*
G01X27284Y172244D02*
X27587Y172292D01*
G01X19257Y173190D02*
X19134Y173165D01*
G01X41895Y173190D02*
X41772Y173165D01*
G01X45389Y173693D02*
X45266Y173668D01*
G01X46078Y173819D02*
X46226D01*
G01X46767D02*
X46964D01*
G01X45414D02*
X45512D01*
G01X42633D02*
X42855D01*
G01X43470D02*
X43617D01*
G01X42289D02*
X42436D01*
G01X41181D02*
X41772D01*
G01X23243D02*
X23440D01*
G01X22505D02*
X22653D01*
G01X20832D02*
X20980D01*
G01X19995D02*
X20217D01*
G01X19651D02*
X19798D01*
G01X18544D02*
X19134D01*
G01X19159Y173693D02*
X18691D01*
G01X41796D02*
X41329D01*
G01X45487D02*
X45389D01*
G01X45143Y173542D02*
X45020D01*
G01X41329Y173316D02*
X41796D01*
G01X18691D02*
X19159D01*
G01X19134Y173165D02*
X18691D01*
G01X41772D02*
X41329D01*
G01X23563Y173040D02*
X23120D01*
G01X23588Y172939D02*
X23096D01*
G01X45192Y172763D02*
X45881D01*
G01X18691Y172638D02*
X18544D01*
G01X20143D02*
X19995D01*
G01X19798D02*
X19651D01*
G01X20980D02*
X20758D01*
G01X23834D02*
X23686D01*
G01X22997D02*
X22850D01*
G01X22653D02*
X22505D01*
G01X41329D02*
X41181D01*
G01X42781D02*
X42633D01*
G01X43617D02*
X43396D01*
G01X42436D02*
X42289D01*
G01X45881D02*
X44995D01*
G01X46226D02*
X46078D01*
G01X46964D02*
X46767D01*
G01X45610Y173668D02*
X45487Y173693D01*
G01X41772Y173819D02*
X41895Y173794D01*
G01X19134Y173819D02*
X19257Y173794D01*
G01X45512Y173819D02*
X45660Y173794D01*
G01X27284Y174212D02*
X27587Y174164D01*
G01X37284Y172244D02*
X36980Y172292D01*
G01X27284Y172244D02*
X26980Y172292D01*
G01X39010Y215360D02*
X38032Y216338D01*
G01X45660Y173794D02*
X45758Y173743D01*
G01X36982Y172291D02*
X36705Y172432D01*
G01X41870Y173668D02*
X41796Y173693D01*
G01X19232Y173668D02*
X19159Y173693D01*
G01X21654Y150000D02*
X42914D01*
G01X26378Y149409D02*
X20670D01*
G01X43898D02*
X38189D01*
G01X34902Y149016D02*
X29666D01*
G01X29662Y148819D02*
X26536D01*
G01X38031D02*
X34905D01*
G01X36949Y148425D02*
X27618D01*
G01X14567Y148031D02*
X50000D01*
G01X36167Y211614D02*
X35033Y213353D01*
G01X35008Y212192D02*
X36154Y210433D01*
G01X33071Y222953D02*
X32284Y224055D01*
G01X45758Y173743D02*
X45857Y173643D01*
G01X41895Y173794D02*
X41993Y173718D01*
G01X45684Y173618D02*
X45610Y173668D01*
G01X27586Y174165D02*
X27863Y174024D01*
G01X26982Y172291D02*
X26705Y172432D01*
G01X41796Y173316D02*
X41870Y173341D01*
G01X19159Y173316D02*
X19232Y173341D01*
G01X45143Y173743D02*
X45241Y173794D01*
G01X43396Y172638D02*
X42781Y173668D01*
G01X42855Y173819D02*
X43470Y172814D01*
G01X46521Y173341D02*
X46964Y172638D01*
G01X46767D02*
X46398Y173216D01*
G01X45733Y173542D02*
X45684Y173618D01*
G01X41993Y173718D02*
X42067Y173618D01*
G01X41920D02*
X41870Y173668D01*
G01X36707Y172431D02*
X36487Y172650D01*
G01X27860Y174026D02*
X28081Y173806D01*
G01X26707Y172431D02*
X26487Y172650D01*
G01X19257Y173794D02*
X19356Y173718D01*
G01X36705Y174024D02*
X36982Y174165D01*
G01X27863Y172432D02*
X27586Y172291D01*
G01X26705Y174024D02*
X26982Y174165D01*
G01X45266Y173668D02*
X45192Y173618D01*
G01X41993Y173266D02*
X41895Y173190D01*
G01X45807Y173316D02*
X45192Y172763D01*
G01X44995D02*
X45684Y173391D01*
G01X46398Y173216D02*
X46226Y173040D01*
G01X45045Y173643D02*
X45143Y173743D01*
G01X41870Y173341D02*
X41920Y173391D01*
G01X46226Y173241D02*
X46767Y173819D01*
G01X46964D02*
X46521Y173341D01*
G01X45857Y173643D02*
X45881Y173542D01*
G01X42067Y173618D02*
X42092Y173542D01*
G01X41944D02*
X41920Y173618D01*
G01X36488Y172648D02*
X36347Y172925D01*
G01X28079Y173808D02*
X28220Y173531D01*
G01X19356Y173718D02*
X19429Y173618D01*
G01X19282D02*
X19232Y173668D01*
G01X19356Y173266D02*
X19257Y173190D01*
G01X36487Y173806D02*
X36707Y174026D01*
G01X28081Y172650D02*
X27860Y172431D01*
G01X26487Y173806D02*
X26707Y174026D01*
G01X42067Y173366D02*
X41993Y173266D01*
G01X45857Y173391D02*
X45807Y173316D01*
G01X45192Y173618D02*
X45143Y173542D01*
G01X36347Y173531D02*
X36488Y173808D01*
G01X45684Y173391D02*
X45733Y173492D01*
G01X42092Y173442D02*
X42067Y173366D01*
G01X41920Y173391D02*
X41944Y173467D01*
G01X38031Y148819D02*
X38189Y149409D01*
G01X45881Y173492D02*
X45857Y173391D01*
G01X45020Y173542D02*
X45045Y173643D01*
G01X46851Y256299D02*
Y216142D01*
G01X46226Y173819D02*
Y173241D01*
G01Y173040D02*
Y172638D01*
G01X46078D02*
Y173819D01*
G01X45881Y172763D02*
Y172638D01*
G01Y173542D02*
Y173492D01*
G01X45733D02*
Y173542D01*
G01X45040Y211614D02*
Y210433D01*
G01X45001D02*
Y211614D01*
G01X44995Y172638D02*
Y172763D01*
G01X44973Y211614D02*
Y210433D01*
G01X44331Y258268D02*
Y214173D01*
G01X43640Y210433D02*
Y211614D01*
G01X43617Y173819D02*
Y172638D01*
G01X43544Y212874D02*
Y259567D01*
G01Y211614D02*
Y210433D01*
G01X43470Y172814D02*
Y173819D01*
G01X43465Y211811D02*
Y216142D01*
G01X43437Y221180D02*
Y227639D01*
G01X43420Y222441D02*
Y226378D01*
G01X43241Y210433D02*
Y211614D01*
G01X42781Y173668D02*
Y172638D01*
G01X42756Y222602D02*
Y226206D01*
G01Y210433D02*
Y211614D01*
G01X42633Y172638D02*
Y173819D01*
G01X42436D02*
Y172638D01*
G01X42362Y212874D02*
Y259567D01*
G01X42327Y221155D02*
Y227664D01*
G01X42289Y172638D02*
Y173819D01*
G01X42284Y213779D02*
Y258661D01*
G01X42186Y227424D02*
Y221394D01*
G01X42092Y173542D02*
Y173442D01*
G01X41944Y173467D02*
Y173542D01*
G01X41733Y211614D02*
Y210433D01*
G01X41525Y226378D02*
Y222441D01*
G01X41494Y221446D02*
Y227373D01*
G01X41378Y221450D02*
Y227369D01*
G01X41339Y211614D02*
Y210433D01*
G01X41329Y173693D02*
Y173316D01*
G01Y173165D02*
Y172638D01*
G01X41217Y227337D02*
Y221481D01*
G01X41181Y210433D02*
Y211616D01*
G01Y172638D02*
Y173819D01*
G01Y227347D02*
Y221471D01*
G01X41103Y258661D02*
Y213779D01*
G01X41077Y227450D02*
Y221369D01*
G01X40903Y221382D02*
Y227437D01*
G01X40787Y221386D02*
Y227433D01*
G01X40551Y210433D02*
Y211614D01*
G01X40394D02*
Y210433D01*
G01Y226378D02*
Y222441D01*
G01X40315Y211811D02*
Y212992D01*
G01X29862Y212052D02*
X29721Y212971D01*
G01X29634Y212039D02*
X29775Y211120D01*
G01X36348Y172923D02*
X36299Y173229D01*
G01X28219Y173534D02*
X28268Y173227D01*
G01X26348Y172923D02*
X26299Y173229D01*
G01X26378Y149409D02*
X26536Y148819D01*
G01X23342Y173718D02*
X23563Y173040D01*
G01X23686Y172638D02*
X23588Y172939D01*
G01X19429Y173618D02*
X19454Y173542D01*
G01X19306D02*
X19282Y173618D01*
G01X23440Y173819D02*
X23834Y172638D01*
G01X26488Y172648D02*
X26347Y172925D01*
G01X20758Y172638D02*
X20143Y173668D01*
G01X20217Y173819D02*
X20832Y172814D01*
G01X19232Y173341D02*
X19282Y173391D01*
G01X22505Y173618D02*
X22357Y173442D01*
G01Y173643D02*
X22505Y173819D01*
G01X19429Y173366D02*
X19356Y173266D01*
G01X28220Y172925D02*
X28079Y172648D01*
G01X26347Y173531D02*
X26488Y173808D01*
G01X36299Y173227D02*
X36348Y173534D01*
G01X28268Y173229D02*
X28219Y172923D01*
G01X26299Y173227D02*
X26348Y173534D01*
G01X34792Y211120D02*
X34933Y212039D01*
G01X34846Y212971D02*
X34705Y212052D01*
G01X30561Y210682D02*
X30648Y211614D01*
G01X29775Y211120D02*
X29862Y212052D01*
G01X29666Y149016D02*
X29662Y148819D01*
G01X40158Y216338D02*
Y216142D01*
G01Y226771D02*
Y222047D01*
G01X40142Y227307D02*
Y221512D01*
G01X40000Y227348D02*
Y221471D01*
G01X39764Y211614D02*
Y209055D01*
G01X39528Y255551D02*
Y216890D01*
G01X39396Y221653D02*
Y219291D01*
G01X38976Y211614D02*
Y210433D01*
G01X38780Y222244D02*
Y218701D01*
G01X38583Y222047D02*
Y218897D01*
G01X38582Y210433D02*
Y211614D01*
G01X38319Y218897D02*
Y222047D01*
G01X38279Y218897D02*
Y222047D01*
G01X38189Y178436D02*
Y168020D01*
G01Y211614D02*
Y210433D01*
G01X38182Y211614D02*
Y210433D01*
G01X38150Y217421D02*
Y223523D01*
G01X38051D02*
Y217421D01*
G01X38032Y256102D02*
Y216338D01*
G01X37944Y218012D02*
Y222933D01*
G01X37795Y222047D02*
Y218897D01*
G01X37637D02*
Y222047D01*
G01X37599Y222244D02*
Y218701D01*
G01X37528Y218897D02*
Y222047D01*
G01X37264Y217421D02*
Y223523D01*
G01X37210Y218012D02*
Y222933D01*
G01X37166Y217992D02*
Y217421D01*
G01Y223523D02*
Y222953D01*
G01X37075Y211614D02*
Y210433D01*
G01X36772Y211614D02*
Y210433D01*
G01X36675Y211614D02*
Y210433D01*
G01X36614Y219291D02*
Y217992D01*
G01Y222953D02*
Y221653D01*
G01X36418Y218701D02*
Y222244D01*
G01X36304Y210433D02*
Y211614D01*
G01X36228Y210433D02*
Y211614D01*
G01X35984Y210433D02*
Y211614D01*
G01X35522D02*
Y210433D01*
G01X35342D02*
Y211614D01*
G01X35314D02*
Y210433D01*
G01X35276Y211614D02*
Y210433D01*
G01X35211Y218012D02*
Y222933D01*
G01X35158D02*
Y218012D01*
G01X34744Y224606D02*
Y220275D01*
G01X34478Y218012D02*
Y222933D01*
G01X34370D02*
Y218012D01*
G01X34318Y219291D02*
Y221653D01*
G01X34252Y222953D02*
Y217992D01*
G01X34173Y222933D02*
Y218012D01*
G01X34134Y222953D02*
Y217992D01*
G01X33977Y218012D02*
Y222933D01*
G01X33780Y216338D02*
Y256102D01*
G01X33563Y224606D02*
Y220275D01*
G01X33465Y225295D02*
Y223523D01*
G01X33386Y222953D02*
Y217992D01*
G01X33347Y223622D02*
Y219449D01*
G01X33268D02*
Y225433D01*
G01X33226Y221063D02*
Y225000D01*
G01X33071Y222953D02*
Y217992D01*
G01X32284Y214370D02*
Y258071D01*
G01X32256Y221063D02*
Y225000D01*
G01X32131Y223228D02*
Y221653D01*
G01X31890Y216338D02*
Y215551D01*
G01X31735Y225000D02*
Y221070D01*
G01X31719Y221653D02*
Y223228D01*
G01X31130Y221063D02*
Y225000D01*
G01X31103D02*
Y220472D01*
G01X30161Y221063D02*
Y225000D01*
G01X30118D02*
Y221063D01*
G01X30020Y224409D02*
Y220472D01*
G01X29823Y224606D02*
Y220275D01*
G01X29292Y211614D02*
Y210433D01*
G01X29253D02*
Y211614D01*
G01X29225D02*
Y210433D01*
G01X29046D02*
Y211614D01*
G01X29036Y224606D02*
Y220275D01*
G01X28839Y220472D02*
Y224409D01*
G01X28740Y215551D02*
Y216338D01*
G01X28583Y211614D02*
Y210433D01*
G01X28347Y217716D02*
Y214960D01*
G01X28340Y211614D02*
Y210433D01*
G01X28264Y211614D02*
Y210433D01*
G01X27892D02*
Y211614D01*
G01X27855Y224409D02*
Y220472D01*
G01X27795Y211614D02*
Y210433D01*
G01X27756Y225197D02*
Y220079D01*
G01X27658Y224606D02*
Y220275D01*
G01X27493Y210433D02*
Y211614D01*
G01X26477Y224606D02*
Y220275D01*
G01X26385Y210433D02*
Y211614D01*
G01X26378D02*
Y210433D01*
G01X25985Y211614D02*
Y210433D01*
G01X25591Y211614D02*
Y210433D01*
G01X34902Y149016D02*
X34905Y148819D01*
G01X34705Y212052D02*
X34792Y211120D01*
G01X33919Y211614D02*
X34006Y210682D01*
G01X33780Y216338D02*
X32284Y214842D01*
G01Y216890D02*
X33071Y217992D01*
G01X28414Y210433D02*
X29560Y212192D01*
G01X29534Y213353D02*
X28401Y211614D01*
G01X22850Y172638D02*
X23243Y173819D01*
G01X23096Y172939D02*
X22997Y172638D01*
G01X23120Y173040D02*
X23342Y173718D01*
G01X19454Y173442D02*
X19429Y173366D01*
G01X19282Y173391D02*
X19306Y173467D01*
G01X24803Y211614D02*
Y209055D01*
G01X24567Y227348D02*
Y221471D01*
G01X24425Y221512D02*
Y227307D01*
G01X24410Y222047D02*
Y226771D01*
G01Y216142D02*
Y216338D01*
G01X24252Y212992D02*
Y211811D01*
G01X24173Y222441D02*
Y226378D01*
G01Y210433D02*
Y211614D01*
G01X24016D02*
Y210433D01*
G01X23780Y227433D02*
Y221386D01*
G01X23664Y227437D02*
Y221382D01*
G01X23491Y221369D02*
Y227450D01*
G01X23465Y213779D02*
Y258661D01*
G01X23386Y210433D02*
Y211616D01*
G01Y227347D02*
Y221471D01*
G01X23350Y221481D02*
Y227337D01*
G01X23228Y211614D02*
Y210433D01*
G01X23189Y227369D02*
Y221450D01*
G01X23073Y227373D02*
Y221446D01*
G01X23042Y222441D02*
Y226378D01*
G01X22834Y210433D02*
Y211614D01*
G01X22653Y173819D02*
Y172638D01*
G01X22505D02*
Y173618D01*
G01X22381Y221394D02*
Y227424D01*
G01X22357Y173442D02*
Y173643D01*
G01X22284Y258661D02*
Y213779D01*
G01X22241Y227664D02*
Y221155D01*
G01X22205Y259567D02*
Y212874D01*
G01X21811Y211614D02*
Y210433D01*
G01Y226206D02*
Y222613D01*
G01X21327Y211614D02*
Y210433D01*
G01X21147Y226378D02*
Y222441D01*
G01X21131Y227639D02*
Y221180D01*
G01X21103Y211811D02*
Y216142D01*
G01X21024Y211614D02*
Y210433D01*
G01Y259567D02*
Y212874D01*
G01X20980Y173819D02*
Y172638D01*
G01X20927Y211614D02*
Y210433D01*
G01X20832Y172814D02*
Y173819D01*
G01X20236Y214173D02*
Y236201D01*
G01X20143Y173668D02*
Y172638D01*
G01X19995D02*
Y173819D01*
G01X19798D02*
Y172638D01*
G01X19651D02*
Y173819D01*
G01X19594Y210433D02*
Y211614D01*
G01X19566D02*
Y210433D01*
G01X19528Y211614D02*
Y210433D01*
G01X19454Y173542D02*
Y173442D01*
G01X19306Y173467D02*
Y173542D01*
G01X18691Y173693D02*
Y173316D01*
G01Y173165D02*
Y172638D01*
G01X18544D02*
Y173819D01*
G01X17717Y236201D02*
Y216142D01*
G01X0Y350394D02*
Y215436D01*
G01X21072Y244790D02*
X21131Y244802D01*
G01X21036Y244777D02*
X21072Y244790D01*
G01X21024Y244764D02*
X21036Y244777D01*
G01X30418Y260806D02*
X30648Y260827D01*
G01X30208Y260745D02*
X30418Y260806D01*
G01X30036Y260649D02*
X30208Y260745D01*
G01X29918Y260526D02*
X30036Y260649D01*
G01X29862Y260388D02*
X29918Y260526D01*
G01X43496Y251273D02*
X43437Y251261D01*
G01X43532Y251286D02*
X43496Y251273D01*
G01X43544Y251299D02*
X43532Y251286D01*
G01X42741Y246000D02*
X42756Y246235D01*
G01X42698Y245787D02*
X42741Y246000D01*
G01X42630Y245614D02*
X42698Y245787D01*
G01X42544Y245498D02*
X42630Y245614D01*
G01X42448Y245449D02*
X42544Y245498D01*
G01X21826Y250059D02*
X21811Y249828D01*
G01X21869Y250275D02*
X21826Y250059D01*
G01X21937Y250449D02*
X21869Y250275D01*
G01X22024Y250566D02*
X21937Y250449D01*
G01X22120Y250614D02*
X22024Y250566D01*
G01X34956Y260293D02*
X34933Y260402D01*
G01X34982Y260240D02*
X34956Y260293D01*
G01X35008Y260249D02*
X34982Y260240D01*
G01X22025Y226944D02*
X22120Y226992D01*
G01X21938Y226828D02*
X22025Y226944D01*
G01X21869Y226653D02*
X21938Y226828D01*
G01X21826Y226438D02*
X21869Y226653D01*
G01X21811Y226206D02*
X21826Y226438D01*
G01X32043Y239537D02*
X32190Y239567D01*
G01X31909Y239450D02*
X32043Y239537D01*
G01X31805Y239317D02*
X31909Y239450D01*
G01X31740Y239152D02*
X31805Y239317D01*
G01X31719Y238976D02*
X31740Y239152D01*
G01X32043Y231663D02*
X32190Y231693D01*
G01X31909Y231576D02*
X32043Y231663D01*
G01X31805Y231443D02*
X31909Y231576D01*
G01X31740Y231278D02*
X31805Y231443D01*
G01X31719Y231102D02*
X31740Y231278D01*
G01X31894Y238266D02*
X31735Y238196D01*
G01X32022Y238401D02*
X31894Y238266D01*
G01X32104Y238581D02*
X32022Y238401D01*
G01X32131Y238779D02*
X32104Y238581D01*
G01X31894Y230392D02*
X31735Y230322D01*
G01X32022Y230527D02*
X31894Y230392D01*
G01X32104Y230707D02*
X32022Y230527D01*
G01X32131Y230905D02*
X32104Y230707D01*
G01X29586Y260240D02*
X29560Y260249D01*
G01X29612Y260293D02*
X29586Y260240D01*
G01X29634Y260402D02*
X29612Y260293D01*
G01X42341Y239534D02*
X42315Y239526D01*
G01X42357Y239543D02*
X42341Y239534D01*
G01X42362Y239552D02*
X42357Y239543D01*
G01X43510Y239524D02*
X43468Y239510D01*
G01X43535Y239538D02*
X43510Y239524D01*
G01X43544Y239552D02*
X43535Y239538D01*
G01X43496Y227651D02*
X43437Y227639D01*
G01X43532Y227664D02*
X43496Y227651D01*
G01X43544Y227676D02*
X43532Y227664D01*
G01X42326Y234323D02*
X42336Y234555D01*
G01X42294Y234108D02*
X42326Y234323D01*
G01X42245Y233934D02*
X42294Y234108D01*
G01X42183Y233817D02*
X42245Y233934D01*
G01X42114Y233768D02*
X42183Y233817D01*
G01X40017Y238849D02*
X40091Y238828D01*
G01X40002Y238871D02*
X40017Y238849D01*
G01X40047Y238892D02*
X40002Y238871D01*
G01X31356Y234240D02*
X31266Y234252D01*
G01X31440Y234206D02*
X31356Y234240D01*
G01X31518Y234152D02*
X31440Y234206D01*
G01X31586Y234079D02*
X31518Y234152D01*
G01X31643Y233988D02*
X31586Y234079D01*
G01X31685Y233886D02*
X31643Y233988D01*
G01X31710Y233776D02*
X31685Y233886D01*
G01X31719Y233661D02*
X31710Y233776D01*
G01X31356Y242114D02*
X31266Y242126D01*
G01X31440Y242080D02*
X31356Y242114D01*
G01X31518Y242026D02*
X31440Y242080D01*
G01X31586Y241953D02*
X31518Y242026D01*
G01X31643Y241862D02*
X31586Y241953D01*
G01X31685Y241760D02*
X31643Y241862D01*
G01X31710Y241650D02*
X31685Y241760D01*
G01X31719Y241535D02*
X31710Y241650D01*
G01X32714Y232885D02*
X32804Y232874D01*
G01X32630Y232919D02*
X32714Y232885D01*
G01X32552Y232974D02*
X32630Y232919D01*
G01X32484Y233047D02*
X32552Y232974D01*
G01X32427Y233138D02*
X32484Y233047D01*
G01X32386Y233239D02*
X32427Y233138D01*
G01X32360Y233350D02*
X32386Y233239D01*
G01X32351Y233464D02*
X32360Y233350D01*
G01X32714Y240759D02*
X32804Y240748D01*
G01X32630Y240793D02*
X32714Y240759D01*
G01X32552Y240848D02*
X32630Y240793D01*
G01X32484Y240921D02*
X32552Y240848D01*
G01X32427Y241012D02*
X32484Y240921D01*
G01X32386Y241113D02*
X32427Y241012D01*
G01X32360Y241224D02*
X32386Y241113D01*
G01X32351Y241338D02*
X32360Y241224D01*
G01X31235Y251362D02*
X31116Y251378D01*
G01X31347Y251317D02*
X31235Y251362D01*
G01X31451Y251245D02*
X31347Y251317D01*
G01X31542Y251147D02*
X31451Y251245D01*
G01X31618Y251026D02*
X31542Y251147D01*
G01X31673Y250890D02*
X31618Y251026D01*
G01X31707Y250743D02*
X31673Y250890D01*
G01X31719Y250590D02*
X31707Y250743D01*
G01X32835Y248637D02*
X32955Y248622D01*
G01X32723Y248682D02*
X32835Y248637D01*
G01X32619Y248755D02*
X32723Y248682D01*
G01X32528Y248852D02*
X32619Y248755D01*
G01X32452Y248974D02*
X32528Y248852D01*
G01X32397Y249109D02*
X32452Y248974D01*
G01X32363Y249256D02*
X32397Y249109D01*
G01X32351Y249409D02*
X32363Y249256D01*
G01X22025Y245496D02*
X22120Y245449D01*
G01X21938Y245613D02*
X22025Y245496D01*
G01X21869Y245787D02*
X21938Y245613D01*
G01X21826Y246003D02*
X21869Y245787D01*
G01X21811Y246235D02*
X21826Y246003D01*
G01X41057Y233840D02*
X40987Y233790D01*
G01X41119Y233956D02*
X41057Y233840D01*
G01X41167Y234129D02*
X41119Y233956D01*
G01X41198Y234342D02*
X41167Y234129D01*
G01X41209Y234577D02*
X41198Y234342D01*
G01X32043Y223789D02*
X32190Y223819D01*
G01X31909Y223702D02*
X32043Y223789D01*
G01X42544Y226943D02*
X42448Y226992D01*
G01X42630Y226827D02*
X42544Y226943D01*
G01X42698Y226654D02*
X42630Y226827D01*
G01X42741Y226441D02*
X42698Y226654D01*
G01X42756Y226206D02*
X42741Y226441D01*
G01X42544Y250565D02*
X42448Y250614D01*
G01X42630Y250449D02*
X42544Y250565D01*
G01X42698Y250276D02*
X42630Y250449D01*
G01X42741Y250063D02*
X42698Y250276D01*
G01X42756Y249828D02*
X42741Y250063D01*
G01X42183Y238624D02*
X42114Y238672D01*
G01X42245Y238507D02*
X42183Y238624D01*
G01X42294Y238333D02*
X42245Y238507D01*
G01X42326Y238118D02*
X42294Y238333D01*
G01X42336Y237886D02*
X42326Y238118D01*
G01X34968Y259064D02*
X35033Y259087D01*
G01X34903Y259197D02*
X34968Y259064D01*
G01X34846Y259470D02*
X34903Y259197D01*
G01X34236Y261738D02*
X34006Y261759D01*
G01X34446Y261677D02*
X34236Y261738D01*
G01X34618Y261581D02*
X34446Y261677D01*
G01X34736Y261459D02*
X34618Y261581D01*
G01X34792Y261321D02*
X34736Y261459D01*
G01X21072Y227651D02*
X21131Y227639D01*
G01X21036Y227664D02*
X21072Y227651D01*
G01X21024Y227676D02*
X21036Y227664D01*
G01X22221Y227668D02*
X22241Y227664D01*
G01X22209Y227672D02*
X22221Y227668D01*
G01X22205Y227676D02*
X22209Y227672D01*
G01X22221Y251290D02*
X22241Y251286D01*
G01X22209Y251294D02*
X22221Y251290D01*
G01X22205Y251299D02*
X22209Y251294D01*
G01X42346Y244773D02*
X42327Y244777D01*
G01X42358Y244768D02*
X42346Y244773D01*
G01X42362Y244764D02*
X42358Y244768D01*
G01X41188Y233582D02*
X41217Y233590D01*
G01X41182Y233573D02*
X41188Y233582D01*
G01X41200Y233565D02*
X41182Y233573D01*
G01X41198Y238098D02*
X41209Y237875D01*
G01X41167Y238311D02*
X41198Y238098D01*
G01X41119Y238484D02*
X41167Y238311D01*
G01X41057Y238600D02*
X41119Y238484D01*
G01X40987Y238650D02*
X41057Y238600D01*
G01X40429Y227415D02*
X40787Y227433D01*
G01X40163Y227391D02*
X40429Y227415D01*
G01X40021Y227363D02*
X40163Y227391D01*
G01X40015Y227334D02*
X40021Y227363D01*
G01X40142Y227307D02*
X40015Y227334D01*
G01X43529Y227021D02*
X43522Y227023D01*
G01X43536Y227020D02*
X43529Y227021D01*
G01X43544Y227018D02*
X43536Y227020D01*
G01X42357Y232897D02*
X42362Y232888D01*
G01X42341Y232906D02*
X42357Y232897D01*
G01X42315Y232915D02*
X42341Y232906D01*
G01X43535Y232903D02*
X43544Y232888D01*
G01X43510Y232917D02*
X43535Y232903D01*
G01X43468Y232931D02*
X43510Y232917D01*
G01X24552Y227334D02*
X24425Y227307D01*
G01X24547Y227363D02*
X24552Y227334D01*
G01X24405Y227391D02*
X24547Y227363D01*
G01X24139Y227415D02*
X24405Y227391D01*
G01X23780Y227433D02*
X24139Y227415D01*
G01X22780Y227387D02*
X23073Y227373D01*
G01X22545Y227404D02*
X22780Y227387D01*
G01X22381Y227424D02*
X22545Y227404D01*
G01X23591Y227440D02*
X23664Y227437D01*
G01X23532Y227445D02*
X23591Y227440D01*
G01X23491Y227450D02*
X23532Y227445D01*
G01X31728Y233348D02*
X31719Y233464D01*
G01X31753Y233237D02*
X31728Y233348D01*
G01X31795Y233136D02*
X31753Y233237D01*
G01X31851Y233047D02*
X31795Y233136D01*
G01X31921Y232972D02*
X31851Y233047D01*
G01X31999Y232918D02*
X31921Y232972D01*
G01X32083Y232885D02*
X31999Y232918D01*
G01X32171Y232874D02*
X32083Y232885D01*
G01X32342Y233778D02*
X32351Y233661D01*
G01X32317Y233888D02*
X32342Y233778D01*
G01X32275Y233990D02*
X32317Y233888D01*
G01X32219Y234079D02*
X32275Y233990D01*
G01X32149Y234153D02*
X32219Y234079D01*
G01X32071Y234207D02*
X32149Y234153D01*
G01X31987Y234241D02*
X32071Y234207D01*
G01X31899Y234252D02*
X31987Y234241D01*
G01X41182Y238867D02*
X41200Y238876D01*
G01X41188Y238859D02*
X41182Y238867D01*
G01X41217Y238850D02*
X41188Y238859D01*
G01X29665Y259198D02*
X29721Y259470D01*
G01X29600Y259064D02*
X29665Y259198D01*
G01X29534Y259087D02*
X29600Y259064D01*
G01X42358Y227672D02*
X42362Y227676D01*
G01X42346Y227668D02*
X42358Y227672D01*
G01X42327Y227664D02*
X42346Y227668D01*
G01X32455Y223789D02*
X32321Y223702D01*
G01X32603Y223819D02*
X32455Y223789D01*
G01X21031Y227020D02*
X21024Y227018D01*
G01X21038Y227021D02*
X21031Y227020D01*
G01X21045Y227023D02*
X21038Y227021D01*
G01X41786Y227386D02*
X41494Y227373D01*
G01X42023Y227404D02*
X41786Y227386D01*
G01X42186Y227424D02*
X42023Y227404D01*
G01X41182Y227346D02*
X41217Y227337D01*
G01X41200Y227355D02*
X41182Y227346D01*
G01X41270Y227363D02*
X41200Y227355D01*
G01X41378Y227369D02*
X41270Y227363D01*
G01X41036Y227445D02*
X41077Y227450D01*
G01X40976Y227440D02*
X41036Y227445D01*
G01X40903Y227437D02*
X40976Y227440D01*
G01X42024Y245036D02*
X42186Y245016D01*
G01X41786Y245054D02*
X42024Y245036D01*
G01X41494Y245068D02*
X41786Y245054D01*
G01X40015Y245106D02*
X40142Y245134D01*
G01X40020Y245077D02*
X40015Y245106D01*
G01X40163Y245050D02*
X40020Y245077D01*
G01X40429Y245026D02*
X40163Y245050D01*
G01X40787Y245008D02*
X40429Y245026D01*
G01X40976Y245000D02*
X40903Y245004D01*
G01X41036Y244996D02*
X40976Y245000D01*
G01X41077Y244991D02*
X41036Y244996D01*
G01X23591Y251062D02*
X23664Y251059D01*
G01X23532Y251067D02*
X23591Y251062D01*
G01X23491Y251072D02*
X23532Y251067D01*
G01X31728Y241222D02*
X31719Y241338D01*
G01X31753Y241111D02*
X31728Y241222D01*
G01X31795Y241010D02*
X31753Y241111D01*
G01X31851Y240921D02*
X31795Y241010D01*
G01X31921Y240847D02*
X31851Y240921D01*
G01X31999Y240792D02*
X31921Y240847D01*
G01X32083Y240759D02*
X31999Y240792D01*
G01X32171Y240748D02*
X32083Y240759D01*
G01X32342Y241652D02*
X32351Y241535D01*
G01X32317Y241762D02*
X32342Y241652D01*
G01X32275Y241864D02*
X32317Y241762D01*
G01X32219Y241953D02*
X32275Y241864D01*
G01X32149Y242027D02*
X32219Y241953D01*
G01X32071Y242081D02*
X32149Y242027D01*
G01X31987Y242115D02*
X32071Y242081D01*
G01X31899Y242126D02*
X31987Y242115D01*
G01X31731Y249254D02*
X31719Y249409D01*
G01X31765Y249107D02*
X31731Y249254D01*
G01X31821Y248971D02*
X31765Y249107D01*
G01X31895Y248852D02*
X31821Y248971D01*
G01X31988Y248753D02*
X31895Y248852D01*
G01X32092Y248681D02*
X31988Y248753D01*
G01X32205Y248637D02*
X32092Y248681D01*
G01X32322Y248622D02*
X32205Y248637D01*
G01X32340Y250746D02*
X32351Y250590D01*
G01X32305Y250893D02*
X32340Y250746D01*
G01X32249Y251028D02*
X32305Y250893D01*
G01X32175Y251147D02*
X32249Y251028D01*
G01X32082Y251246D02*
X32175Y251147D01*
G01X31978Y251318D02*
X32082Y251246D01*
G01X31865Y251363D02*
X31978Y251318D01*
G01X31748Y251378D02*
X31865Y251363D01*
G01X21031Y245421D02*
X21024Y245423D01*
G01X21038Y245419D02*
X21031Y245421D01*
G01X21045Y245418D02*
X21038Y245419D01*
G01X43536Y250642D02*
X43544Y250640D01*
G01X43529Y250643D02*
X43536Y250642D01*
G01X43522Y250645D02*
X43529Y250643D01*
G01X43532Y244777D02*
X43544Y244764D01*
G01X43496Y244790D02*
X43532Y244777D01*
G01X43437Y244802D02*
X43496Y244790D01*
G01X21036Y251286D02*
X21024Y251299D01*
G01X21072Y251273D02*
X21036Y251286D01*
G01X21131Y251261D02*
X21072Y251273D01*
G01X40429Y251037D02*
X40787Y251055D01*
G01X40163Y251013D02*
X40429Y251037D01*
G01X40021Y250985D02*
X40163Y251013D01*
G01X40015Y250956D02*
X40021Y250985D01*
G01X40142Y250929D02*
X40015Y250956D01*
G01X40002Y233570D02*
X40047Y233549D01*
G01X40017Y233592D02*
X40002Y233570D01*
G01X40091Y233612D02*
X40017Y233592D01*
G01X23299Y227363D02*
X23189Y227369D01*
G01X23367Y227355D02*
X23299Y227363D01*
G01X23385Y227346D02*
X23367Y227355D01*
G01X23350Y227337D02*
X23385Y227346D01*
G01X31697Y230727D02*
X31719Y230905D01*
G01X31632Y230564D02*
X31697Y230727D01*
G01X31529Y230432D02*
X31632Y230564D01*
G01X31397Y230345D02*
X31529Y230432D01*
G01X31247Y230315D02*
X31397Y230345D01*
G01X31697Y238601D02*
X31719Y238779D01*
G01X31632Y238438D02*
X31697Y238601D01*
G01X31529Y238306D02*
X31632Y238438D01*
G01X31397Y238219D02*
X31529Y238306D01*
G01X31247Y238189D02*
X31397Y238219D01*
G01X32153Y231278D02*
X32131Y231102D01*
G01X32218Y231442D02*
X32153Y231278D01*
G01X32321Y231576D02*
X32218Y231442D01*
G01X32455Y231663D02*
X32321Y231576D01*
G01X32603Y231693D02*
X32455Y231663D01*
G01X32153Y239152D02*
X32131Y238976D01*
G01X32218Y239317D02*
X32153Y239152D01*
G01X32321Y239450D02*
X32218Y239317D01*
G01X32455Y239537D02*
X32321Y239450D01*
G01X32603Y239567D02*
X32455Y239537D01*
G01X31686Y230316D02*
X31661Y230315D01*
G01X31711Y230318D02*
X31686Y230316D01*
G01X31735Y230322D02*
X31711Y230318D01*
G01X31686Y238190D02*
X31661Y238189D01*
G01X31711Y238192D02*
X31686Y238190D01*
G01X31735Y238196D02*
X31711Y238192D01*
G01X22782Y245054D02*
X23073Y245068D01*
G01X22544Y245036D02*
X22782Y245054D01*
G01X22381Y245016D02*
X22544Y245036D01*
G01X23385Y245095D02*
X23350Y245103D01*
G01X23367Y245086D02*
X23385Y245095D01*
G01X23297Y245078D02*
X23367Y245086D01*
G01X23189Y245072D02*
X23297Y245078D01*
G01X41182Y250968D02*
X41217Y250959D01*
G01X41200Y250977D02*
X41182Y250968D01*
G01X41270Y250985D02*
X41200Y250977D01*
G01X41378Y250991D02*
X41270Y250985D01*
G01X24553Y245106D02*
X24425Y245134D01*
G01X24547Y245077D02*
X24553Y245106D01*
G01X24406Y245050D02*
X24547Y245077D01*
G01X24142Y245026D02*
X24406Y245050D01*
G01X23780Y245008D02*
X24142Y245026D01*
G01X23532Y244996D02*
X23491Y244991D01*
G01X23591Y245000D02*
X23532Y244996D01*
G01X23664Y245004D02*
X23591Y245000D01*
G01X41036Y251067D02*
X41077Y251072D01*
G01X40976Y251062D02*
X41036Y251067D01*
G01X40903Y251059D02*
X40976Y251062D01*
G01X22544Y251026D02*
X22381Y251046D01*
G01X22781Y251009D02*
X22544Y251026D01*
G01X23073Y250995D02*
X22781Y251009D01*
G01X24552Y250956D02*
X24425Y250929D01*
G01X24547Y250985D02*
X24552Y250956D01*
G01X24405Y251013D02*
X24547Y250985D01*
G01X24139Y251037D02*
X24405Y251013D01*
G01X23780Y251055D02*
X24139Y251037D01*
G01X34650Y260526D02*
X34705Y260388D01*
G01X34531Y260648D02*
X34650Y260526D01*
G01X34360Y260744D02*
X34531Y260648D01*
G01X34150Y260806D02*
X34360Y260744D01*
G01X33919Y260827D02*
X34150Y260806D01*
G01X43529Y245419D02*
X43522Y245418D01*
G01X43536Y245421D02*
X43529Y245419D01*
G01X43544Y245423D02*
X43536Y245421D01*
G01X21038Y250643D02*
X21045Y250645D01*
G01X21031Y250642D02*
X21038Y250643D01*
G01X21024Y250640D02*
X21031Y250642D01*
G01X41270Y245078D02*
X41378Y245072D01*
G01X41200Y245086D02*
X41270Y245078D01*
G01X41182Y245095D02*
X41200Y245086D01*
G01X41217Y245103D02*
X41182Y245095D01*
G01X23297Y250985D02*
X23189Y250991D01*
G01X23367Y250977D02*
X23297Y250985D01*
G01X23385Y250968D02*
X23367Y250977D01*
G01X23350Y250959D02*
X23385Y250968D01*
G01X22209Y244768D02*
X22205Y244764D01*
G01X22221Y244773D02*
X22209Y244768D01*
G01X22241Y244777D02*
X22221Y244773D01*
G01X42358Y251294D02*
X42362Y251299D01*
G01X42346Y251290D02*
X42358Y251294D01*
G01X42327Y251286D02*
X42346Y251290D01*
G01X41786Y251009D02*
X41494Y250995D01*
G01X42023Y251026D02*
X41786Y251009D01*
G01X42186Y251046D02*
X42023Y251026D01*
G01X29830Y261457D02*
X29775Y261321D01*
G01X29949Y261580D02*
X29830Y261457D01*
G01X30122Y261677D02*
X29949Y261580D01*
G01X30334Y261738D02*
X30122Y261677D01*
G01X30561Y261759D02*
X30334Y261738D01*
G01X64567Y286302D02*
G03X67259Y282567I3937J0D01*
G01X24409Y301207D02*
G03X40158I7874J11785D01*
G01X47047Y312992D02*
G03I-14763J0D01*
G01X47835D02*
G03I-15551J0D01*
G01X50278D02*
G03I-17994J0D01*
G01X51061D02*
G03I-18777J0D01*
G01X51969D02*
G03I-19685J0D01*
G01X39764Y263386D02*
G03X37795Y265354I-1968J0D01*
G01X67259Y252866D02*
G03X64567Y249131I1245J-3735D01*
G01X41103Y258661D02*
G03X40315Y259449I-788J0D01*
G01X42362Y259567D02*
G03X41103Y260827I-1260J0D01*
G01X42284Y258661D02*
G03X40315Y260630I-1969J0D01*
G01X46851Y256299D02*
G03X44882Y258268I-1969J0D01*
G01X43544Y259567D02*
G03X41103Y262008I-2441J0D01*
G01X39528Y255551D02*
G03X37008Y258071I-2520J0D01*
G01X26772Y265354D02*
G03X24803Y263386I0J-1969D01*
G01X24252Y259449D02*
G03X23465Y258661I0J-787D01*
G01Y260827D02*
G03X22205Y259567I0J-1260D01*
G01X24252Y260630D02*
G03X22284Y258661I0J-1968D01*
G01X19685Y258268D02*
G03X17717Y256299I0J-1968D01*
G01X23465Y262008D02*
G03X21024Y259567I0J-2441D01*
G01X15158Y298228D02*
X49410D01*
G01X14764Y297834D02*
X49803D01*
G01X14764Y295275D02*
X49803D01*
G01X73686Y280425D02*
X67259Y282567D01*
G01X37795Y265354D02*
X26772D01*
G01X24803Y262795D02*
X39764D01*
G01X19529Y262008D02*
X45039D01*
G01X30561Y261759D02*
X34006D01*
G01X19529Y260827D02*
X45039D01*
G01X43465Y260630D02*
X21103D01*
G01X34933Y260402D02*
X29634D01*
G01X29560Y260249D02*
X35008D01*
G01X34991Y260236D02*
X29577D01*
G01X34846Y259470D02*
X29721D01*
G01X24252Y259449D02*
X40315D01*
G01X29534Y259087D02*
X35033D01*
G01X22205Y259055D02*
X21024D01*
G01X34991D02*
X29577D01*
G01X43544D02*
X42362D01*
G01X23465Y258661D02*
X22284D01*
G01X42284D02*
X41103D01*
G01X22205Y258268D02*
X19685D01*
G01X44882D02*
X42362D01*
G01X32284Y258071D02*
X37008D01*
G01X42284Y257480D02*
X43465D01*
G01X21103D02*
X22284D01*
G01X32284D02*
X28347D01*
G01X21045Y250645D02*
X23350Y250959D01*
G01X24425Y250929D02*
X22120Y250614D01*
G01X41077Y251072D02*
X42327Y251286D01*
G01X43437Y251261D02*
X42186Y251046D01*
G01X21131Y244802D02*
X22381Y245016D01*
G01X23491Y244991D02*
X22241Y244777D01*
G01X23664Y251059D02*
X23780Y251055D01*
G01X23189Y250991D02*
X23073Y250995D01*
G01X41378Y245072D02*
X41494Y245068D01*
G01X40903Y245004D02*
X40787Y245008D01*
G01X22120Y250614D02*
X21045Y250645D01*
G01X21024Y249850D02*
X21811Y249828D01*
G01X43544Y246213D02*
X42756Y246235D01*
G01X42448Y245449D02*
X43522Y245418D01*
G01X42362Y256890D02*
X43544D01*
G01X21024D02*
X22205D01*
G01X31890D02*
X28740D01*
G01X21103Y256299D02*
X43465D01*
G01X24410Y256102D02*
X40158D01*
G01X22205D02*
X21024D01*
G01X43544D02*
X42362D01*
G01X38150Y255019D02*
X37166D01*
G01X37264Y255000D02*
X38051D01*
G01X37264Y254921D02*
X38051D01*
G01Y254846D02*
X37264D01*
G01Y254823D02*
X38051D01*
G01Y254787D02*
X37264D01*
G01X32284Y254724D02*
X28347D01*
G01X38051Y254699D02*
X37264D01*
G01X38051Y254675D02*
X37264D01*
G01Y254645D02*
X38051D01*
G01X37264Y254527D02*
X38051D01*
G01X33071Y254449D02*
X38150D01*
G01X33386Y254429D02*
X38051D01*
G01X25158Y254419D02*
X32284D01*
G01X42362Y254134D02*
X43544D01*
G01X21024D02*
X22205D01*
G01X36418Y253740D02*
X38780D01*
G01X38583Y253543D02*
X37264D01*
G01X32284Y253528D02*
X26371D01*
G01X22205Y253346D02*
X21024D01*
G01X43544D02*
X42362D01*
G01X39528Y253149D02*
X34318D01*
G01X33347Y252992D02*
X32284D01*
G01X33268Y252819D02*
X32284D01*
G01X38583Y252756D02*
X37795D01*
G01X33268Y252726D02*
X32284D01*
G01Y252677D02*
X33268D01*
G01X27432Y252638D02*
X26219D01*
G01X33268Y252630D02*
X32284D01*
G01X37795Y252559D02*
X38583D01*
G01X33268D02*
X32284D01*
G01X33268Y252460D02*
X32284D01*
G01X27756Y252362D02*
X33347D01*
G01X42362Y252349D02*
X43544D01*
G01X21024D02*
X22205D01*
G01X26477Y252165D02*
X34744D01*
G01X33268Y251968D02*
X27855D01*
G01X33268Y251608D02*
X32284D01*
G01X22205Y251575D02*
X21024D01*
G01X43544D02*
X42362D01*
G01X22205Y251563D02*
X21024D01*
G01X43544D02*
X42362D01*
G01Y251535D02*
X43544D01*
G01X21024D02*
X22205D01*
G01X37795Y251378D02*
X38583D01*
G01X30118D02*
X33268D01*
G01X38583Y251181D02*
X37795D01*
G01X28839Y250787D02*
X27855D01*
G01X39528D02*
X34318D01*
G01X27855Y250590D02*
X28839D01*
G01X32351D02*
X31719D01*
G01X37264Y250394D02*
X38583D01*
G01X24410D02*
X22284D01*
G01X42284D02*
X40158D01*
G01X36418Y250197D02*
X38780D01*
G01X40394Y250000D02*
X43544D01*
G01X24173D02*
X21024D01*
G01X38051Y249508D02*
X33386D01*
G01X38150Y249488D02*
X33071D01*
G01X37264Y249409D02*
X38051D01*
G01X27855D02*
X28839D01*
G01X32351D02*
X31719D01*
G01X38051Y249291D02*
X37264D01*
G01Y249262D02*
X38051D01*
G01X37264Y249238D02*
X38051D01*
G01X28839Y249212D02*
X27855D01*
G01X37264Y249150D02*
X38051D01*
G01Y249114D02*
X37264D01*
G01Y249090D02*
X38051D01*
G01Y249016D02*
X37264D01*
G01X38051Y248937D02*
X37264D01*
G01X39528Y248917D02*
X33347D01*
G01X35512Y248819D02*
X33347D01*
G01X35315Y248622D02*
X32322D01*
G01X27855Y248031D02*
X33268D01*
G01X26477Y247834D02*
X34744D01*
G01X33268Y247539D02*
X32284D01*
G01X35315Y247441D02*
X30118D01*
G01X32284Y247370D02*
X33268D01*
G01Y247323D02*
X32284D01*
G01Y247273D02*
X33268D01*
G01X35512Y247244D02*
X27756D01*
G01X32284Y247210D02*
X33268D01*
G01X32284Y247181D02*
X33268D01*
G01X39528Y247145D02*
X33465D01*
G01X37264Y247126D02*
X38051D01*
G01X37264Y247047D02*
X38051D01*
G01X33347Y247008D02*
X32284D01*
G01X38051Y246972D02*
X37264D01*
G01Y246949D02*
X38051D01*
G01Y246913D02*
X37264D01*
G01X38051Y246825D02*
X37264D01*
G01X38051Y246801D02*
X37264D01*
G01Y246771D02*
X38051D01*
G01X37264Y246653D02*
X38051D01*
G01X33071Y246575D02*
X38150D01*
G01X33386Y246555D02*
X38051D01*
G01X24173Y246063D02*
X21024D01*
G01X43544D02*
X40394D01*
G01X36418Y245866D02*
X38780D01*
G01X24410Y245669D02*
X22284D01*
G01X38583D02*
X37264D01*
G01X42284D02*
X40158D01*
G01X39528Y245275D02*
X34318D01*
G01X38583Y244882D02*
X37795D01*
G01Y244685D02*
X38583D01*
G01X22205Y244527D02*
X21024D01*
G01X43544D02*
X42362D01*
G01Y244499D02*
X43544D01*
G01X21024D02*
X22205D01*
G01X42362Y244488D02*
X43544D01*
G01X21024D02*
X22205D01*
G01Y243714D02*
X21024D01*
G01X43544D02*
X42362D01*
G01X37795Y243504D02*
X38583D01*
G01Y243307D02*
X37795D01*
G01X33347Y243149D02*
X32284D01*
G01X33268Y242976D02*
X32284D01*
G01X39528Y242913D02*
X34318D01*
G01X43544D02*
X42362D01*
G01X33268Y242884D02*
X32284D01*
G01Y242834D02*
X33268D01*
G01Y242787D02*
X32284D01*
G01X42362Y242716D02*
X43544D01*
G01X22205D02*
X21024D01*
G01X33268D02*
X32284D01*
G01X33268Y242618D02*
X32284D01*
G01X37264Y242519D02*
X38583D01*
G01X33347D02*
X27756D01*
G01X36418Y242323D02*
X38780D01*
G01X26477D02*
X34744D01*
G01X33268Y242299D02*
X32284D01*
G01X43522Y250645D02*
X42448Y250614D01*
G01X42756Y249828D02*
X43544Y249850D01*
G01X21811Y246235D02*
X21024Y246213D01*
G01X21045Y245418D02*
X22120Y245449D01*
G01X40787Y251055D02*
X40903Y251059D01*
G01X41494Y250995D02*
X41378Y250991D01*
G01X23073Y245068D02*
X23189Y245072D01*
G01X23780Y245008D02*
X23664Y245004D01*
G01X40142Y245134D02*
X42448Y245449D01*
G01X43522Y245418D02*
X41217Y245103D01*
G01X40987Y233790D02*
X40091Y233612D01*
G01X41217Y233590D02*
X42114Y233768D01*
G01X42315Y239526D02*
X40047Y238892D01*
G01X41200Y238876D02*
X43468Y239510D01*
G01X22241Y251286D02*
X23491Y251072D01*
G01X22381Y251046D02*
X21131Y251261D01*
G01X42186Y245016D02*
X43437Y244802D01*
G01X42327Y244777D02*
X41077Y244991D01*
G01X41217Y250959D02*
X43522Y250645D01*
G01X42448Y250614D02*
X40142Y250929D01*
G01X22120Y245449D02*
X24425Y245134D01*
G01X23350Y245103D02*
X21045Y245418D01*
G01X41209Y234577D02*
X42336Y234555D01*
G01X42114Y233768D02*
X40987Y233790D01*
G01X33268Y242126D02*
X27855D01*
G01X43544D02*
X42362D01*
G01X43465Y241929D02*
X42284D01*
G01X38051Y241634D02*
X33386D01*
G01X38150Y241614D02*
X33071D01*
G01X37264Y241535D02*
X38051D01*
G01X32351D02*
X31719D01*
G01X38051Y241417D02*
X37264D01*
G01Y241388D02*
X38051D01*
G01X37264Y241364D02*
X38051D01*
G01X32351Y241338D02*
X31719D01*
G01X43544D02*
X42362D01*
G01X37264Y241276D02*
X38051D01*
G01Y241240D02*
X37264D01*
G01Y241216D02*
X38051D01*
G01X42362Y241152D02*
X43544D01*
G01X42362Y241150D02*
X43544D01*
G01X38051Y241142D02*
X37264D01*
G01X38051Y241063D02*
X37264D01*
G01X33347Y241043D02*
X39528D01*
G01X28839Y240945D02*
X27855D01*
G01X35512D02*
X33347D01*
G01X32171Y240748D02*
X35315D01*
G01X28839D02*
X27855D01*
G01X43465D02*
X42284D01*
G01X43544Y240034D02*
X42362D01*
G01X43544Y239579D02*
X42362D01*
G01X28839Y239567D02*
X27855D01*
G01X35315D02*
X32190D01*
G01X28839Y239370D02*
X27855D01*
G01X35512D02*
X33347D01*
G01X39528Y239271D02*
X33347D01*
G01X37264Y239252D02*
X38051D01*
G01X42362Y239248D02*
X43544D01*
G01X37264Y239173D02*
X38051D01*
G01Y239098D02*
X37264D01*
G01Y239075D02*
X38051D01*
G01Y239039D02*
X37264D01*
G01X31719Y238976D02*
X32131D01*
G01X38051Y238951D02*
X37264D01*
G01X38051Y238927D02*
X37264D01*
G01Y238897D02*
X38051D01*
G01X37264Y238779D02*
X38051D01*
G01X31719D02*
X32131D01*
G01X33071Y238701D02*
X38150D01*
G01X33386Y238681D02*
X38051D01*
G01X27855Y238189D02*
X33268D01*
G01X32284Y238016D02*
X33268D01*
G01X36418Y237992D02*
X38780D01*
G01X26477D02*
X34744D01*
G01X41209Y237875D02*
X42336D01*
G01X33347Y237795D02*
X27756D01*
G01X38583D02*
X37264D01*
G01X33268Y237697D02*
X32284D01*
G01X33268Y237598D02*
X32284D01*
G01Y237527D02*
X33268D01*
G01Y237480D02*
X32284D01*
G01Y237431D02*
X33268D01*
G01X39528Y237401D02*
X34318D01*
G01X32284Y237338D02*
X33268D01*
G01X33347Y237165D02*
X32284D01*
G01X38583Y237008D02*
X37795D01*
G01Y236811D02*
X38583D01*
G01X22205Y236240D02*
X17717D01*
G01X22205Y236201D02*
X17717D01*
G01X37795Y235630D02*
X38583D01*
G01Y235433D02*
X37795D01*
G01X33347Y235275D02*
X32284D01*
G01X33268Y235102D02*
X32284D01*
G01X39528Y235039D02*
X34318D01*
G01X33268Y235010D02*
X32284D01*
G01Y234960D02*
X33268D01*
G01Y234913D02*
X32284D01*
G01X22205Y234855D02*
X21024D01*
G01X33268Y234842D02*
X32284D01*
G01X22205Y234829D02*
X21024D01*
G01X33268Y234744D02*
X32284D01*
G01X37264Y234645D02*
X38583D01*
G01X33347D02*
X27756D01*
G01X36418Y234449D02*
X38780D01*
G01X26477D02*
X34744D01*
G01X33268Y234425D02*
X32284D01*
G01X33268Y234252D02*
X27855D01*
G01X22205Y233806D02*
X21024D01*
G01X22205Y233779D02*
X21024D01*
G01X38051Y233760D02*
X33386D01*
G01X38150Y233740D02*
X33071D01*
G01X37264Y233661D02*
X38051D01*
G01X32351D02*
X31719D01*
G01X38051Y233543D02*
X37264D01*
G01Y233514D02*
X38051D01*
G01X37264Y233490D02*
X38051D01*
G01X32351Y233464D02*
X31719D01*
G01X37264Y233402D02*
X38051D01*
G01Y233366D02*
X37264D01*
G01Y233342D02*
X38051D01*
G01Y233268D02*
X37264D01*
G01X43544Y233193D02*
X42362D01*
G01X38051Y233189D02*
X37264D01*
G01X39528Y233169D02*
X33347D01*
G01X28839Y233071D02*
X27855D01*
G01X35512D02*
X33347D01*
G01X32171Y232874D02*
X35315D01*
G01X28839D02*
X27855D01*
G01X42362Y232856D02*
X43544D01*
G01X42362Y232407D02*
X43544D01*
G01X22205Y232303D02*
X21024D01*
G01X22205Y232264D02*
X21024D01*
G01X28839Y231693D02*
X27855D01*
G01X35315D02*
X32190D01*
G01X43465D02*
X42284D01*
G01X28839Y231496D02*
X27855D01*
G01X35512D02*
X33347D01*
G01X39528Y231397D02*
X33347D01*
G01X37264Y231378D02*
X38051D01*
G01X37264Y231299D02*
X38051D01*
G01X43544Y231284D02*
X42362D01*
G01Y231282D02*
X43544D01*
G01X38051Y231224D02*
X37264D01*
G01Y231201D02*
X38051D01*
G01Y231165D02*
X37264D01*
G01X42362Y231102D02*
X43544D01*
G01X31719D02*
X32131D01*
G01X38051Y231077D02*
X37264D01*
G01X38051Y231053D02*
X37264D01*
G01Y231023D02*
X38051D01*
G01X37264Y230905D02*
X38051D01*
G01X31719D02*
X32131D01*
G01X38150Y230827D02*
X33071D01*
G01X33386Y230807D02*
X38051D01*
G01X43465Y230512D02*
X42284D01*
G01X27855Y230315D02*
X33268D01*
G01X43544D02*
X42362D01*
G01X32284Y230142D02*
X33268D01*
G01X36418Y230118D02*
X38780D01*
G01X26477D02*
X34744D01*
G01X33347Y229921D02*
X27756D01*
G01X38583D02*
X37264D01*
G01X33268Y229823D02*
X32284D01*
G01X22205Y229724D02*
X21024D01*
G01X33268D02*
X32284D01*
G01X43544D02*
X42362D01*
G01X32284Y229653D02*
X33268D01*
G01Y229606D02*
X32284D01*
G01Y229557D02*
X33268D01*
G01X42362Y229527D02*
X43544D01*
G01X39528D02*
X34318D01*
G01X32284Y229464D02*
X33268D01*
G01X33347Y229291D02*
X32284D01*
G01X38583Y229134D02*
X37795D01*
G01Y228937D02*
X38583D01*
G01X42362Y228727D02*
X43544D01*
G01X21024D02*
X22205D01*
G01Y227953D02*
X21024D01*
G01X43544D02*
X42362D01*
G01X22205Y227941D02*
X21024D01*
G01X43544D02*
X42362D01*
G01X22205Y227913D02*
X21024D01*
G01X43544D02*
X42362D01*
G01X37795Y227756D02*
X38583D01*
G01Y227559D02*
X37795D01*
G01X39528Y227165D02*
X34318D01*
G01X40987Y238650D02*
X42114Y238672D01*
G01X43522Y227023D02*
X42448Y226992D01*
G01X43544Y226228D02*
X42756Y226206D01*
G01X40787Y227433D02*
X40903Y227437D01*
G01X41494Y227373D02*
X41378Y227369D01*
G01X23350Y227337D02*
X21045Y227023D01*
G01X22120Y226992D02*
X24425Y227307D01*
G01X41077Y227450D02*
X42327Y227664D01*
G01X43437Y227639D02*
X42186Y227424D01*
G01X42114Y238672D02*
X41217Y238850D01*
G01X40091Y238828D02*
X40987Y238650D01*
G01X41217Y227337D02*
X43522Y227023D01*
G01X42448Y226992D02*
X40142Y227307D01*
G01X23664Y227437D02*
X23780Y227433D01*
G01X23189Y227369D02*
X23073Y227373D01*
G01X22120Y226992D02*
X21045Y227023D01*
G01X21811Y226206D02*
X21024Y226228D01*
G01X37264Y226771D02*
X38583D01*
G01X24410D02*
X22284D01*
G01X42284D02*
X40158D01*
G01X36418Y226575D02*
X38780D01*
G01X40394Y226378D02*
X43544D01*
G01X24173D02*
X21024D01*
G01X38051Y225886D02*
X33386D01*
G01X38150Y225866D02*
X33071D01*
G01X37264Y225787D02*
X38051D01*
G01Y225669D02*
X37264D01*
G01Y225640D02*
X38051D01*
G01X37264Y225616D02*
X38051D01*
G01X37264Y225528D02*
X38051D01*
G01Y225492D02*
X37264D01*
G01Y225468D02*
X38051D01*
G01X33347Y225433D02*
X32284D01*
G01X38051Y225394D02*
X37264D01*
G01X38051Y225315D02*
X37264D01*
G01X39528Y225295D02*
X33465D01*
G01X33268Y225260D02*
X32284D01*
G01X27756Y225197D02*
X35512D01*
G01X33268Y225173D02*
X32284D01*
G01X33268Y225167D02*
X32284D01*
G01Y225118D02*
X33268D01*
G01Y225071D02*
X32284D01*
G01X30118Y225000D02*
X35315D01*
G01X33268Y224901D02*
X32284D01*
G01X26477Y224606D02*
X34744D01*
G01X33268Y224409D02*
X27855D01*
G01X35315Y223819D02*
X32190D01*
G01X35512Y223622D02*
X33347D01*
G01X43468Y232931D02*
X41200Y233565D01*
G01X40047Y233549D02*
X42315Y232915D01*
G01X22241Y227664D02*
X23491Y227450D01*
G01X21131Y227639D02*
X22381Y227424D01*
G01X33780Y256102D02*
X32284Y257598D01*
G01X26371Y253528D02*
X27432Y252638D01*
G01X26219D02*
X25158Y253528D01*
G01X29560Y260249D02*
X28414Y262008D01*
G01X28401Y260827D02*
X29534Y259087D01*
G01X32284Y255551D02*
X33071Y254449D01*
G01Y246575D02*
X32284Y247677D01*
G01X33071Y238701D02*
X32284Y239803D01*
G01X33071Y230827D02*
X32284Y231929D01*
G01X64567Y286302D02*
Y350394D01*
G01X34933Y260402D02*
X34792Y261321D01*
G01X34705Y260388D02*
X34846Y259470D01*
G01X49803Y295275D02*
Y330708D01*
G01X49410Y304035D02*
Y298228D01*
G01X47047Y295275D02*
Y330708D01*
G01X45040Y260827D02*
Y262008D01*
G01X45001Y260827D02*
Y262008D01*
G01X44973D02*
Y260827D01*
G01X44685Y310039D02*
Y298228D01*
G01X43898Y300590D02*
Y298228D01*
G01X43640Y260827D02*
Y262008D01*
G01X43544D02*
Y260827D01*
G01X43468Y239510D02*
Y232931D01*
G01X43465Y256299D02*
Y260630D01*
G01Y241929D02*
Y230512D01*
G01X43437Y244802D02*
Y251261D01*
G01X43420Y246063D02*
Y250000D01*
G01X43241Y260827D02*
Y262008D01*
G01X42756Y260827D02*
Y262008D01*
G01Y249828D02*
Y246235D01*
G01X42336Y237875D02*
Y234555D01*
G01X42327Y244777D02*
Y251286D01*
G01X42315Y239526D02*
Y232915D01*
G01X42186Y251046D02*
Y245016D01*
G01X41733Y262008D02*
Y260827D01*
G01X41525Y250000D02*
Y246063D01*
G01X41494Y245068D02*
Y250995D01*
G01X41378Y245072D02*
Y250991D01*
G01X41339Y262008D02*
Y260827D01*
G01X41217Y233590D02*
Y238850D01*
G01Y250959D02*
Y245103D01*
G01X41209Y237864D02*
Y234577D01*
G01X41200Y238876D02*
Y233565D01*
G01X41181Y260824D02*
Y262008D01*
G01Y238865D02*
Y233576D01*
G01Y250970D02*
Y245093D01*
G01X41077Y251072D02*
Y244991D01*
G01X40903Y245004D02*
Y251059D01*
G01X40787Y245008D02*
Y251055D01*
G01X40551Y260827D02*
Y262008D01*
G01X40394Y250000D02*
Y246063D01*
G01Y262008D02*
Y260827D01*
G01X40315Y259449D02*
Y260630D01*
G01X34792Y261321D02*
X34705Y260388D01*
G01X34006Y261759D02*
X33919Y260827D01*
G01X40158Y250394D02*
Y245669D01*
G01Y256299D02*
Y256102D01*
G01X40142Y250929D02*
Y245134D01*
G01X40091Y233612D02*
Y238828D01*
G01X40047Y238892D02*
Y233549D01*
G01X40000Y238865D02*
Y233576D01*
G01Y250970D02*
Y245093D01*
G01X39764Y263386D02*
Y260827D01*
G01X39396Y229527D02*
Y227165D01*
G01Y237401D02*
Y235039D01*
G01Y245275D02*
Y242913D01*
G01Y253149D02*
Y250787D01*
G01X38976Y262008D02*
Y260827D01*
G01X38780Y230118D02*
Y226575D01*
G01Y237992D02*
Y234449D01*
G01Y245866D02*
Y242323D01*
G01Y253740D02*
Y250197D01*
G01X38583Y229921D02*
Y226771D01*
G01Y237795D02*
Y234645D01*
G01Y245669D02*
Y242519D01*
G01Y253543D02*
Y250394D01*
G01X38582Y260827D02*
Y262008D01*
G01X38319Y250394D02*
Y253543D01*
G01Y242519D02*
Y245669D01*
G01Y234645D02*
Y237795D01*
G01Y226771D02*
Y229921D01*
G01X38279Y250394D02*
Y253543D01*
G01Y242519D02*
Y245669D01*
G01Y234645D02*
Y237795D01*
G01Y226771D02*
Y229921D01*
G01X38189Y262008D02*
Y260827D01*
G01X38182Y262008D02*
Y260827D01*
G01X38150Y248917D02*
Y255019D01*
G01Y241043D02*
Y247145D01*
G01Y233169D02*
Y239271D01*
G01Y225295D02*
Y231397D01*
G01X38051D02*
Y225295D01*
G01Y239271D02*
Y233169D01*
G01Y247145D02*
Y241043D01*
G01Y255019D02*
Y248917D01*
G01X37944Y249508D02*
Y254429D01*
G01Y241634D02*
Y246555D01*
G01Y233760D02*
Y238681D01*
G01Y225886D02*
Y230807D01*
G01X37795Y229921D02*
Y226771D01*
G01Y237795D02*
Y234645D01*
G01Y245669D02*
Y242519D01*
G01Y253543D02*
Y250394D01*
G01X37637D02*
Y253543D01*
G01Y242519D02*
Y245669D01*
G01Y234645D02*
Y237795D01*
G01Y226771D02*
Y229921D01*
G01X37599Y230118D02*
Y226575D01*
G01Y237992D02*
Y234449D01*
G01Y245866D02*
Y242323D01*
G01Y253740D02*
Y250197D01*
G01X37528Y250394D02*
Y253543D01*
G01Y242519D02*
Y245669D01*
G01Y234645D02*
Y237795D01*
G01Y226771D02*
Y229921D01*
G01X37264Y248917D02*
Y255019D01*
G01Y241043D02*
Y247145D01*
G01Y233169D02*
Y239271D01*
G01Y225295D02*
Y231397D01*
G01X37210Y249508D02*
Y254429D01*
G01Y241634D02*
Y246555D01*
G01Y233760D02*
Y238681D01*
G01Y225886D02*
Y230807D01*
G01X37166Y225866D02*
Y225295D01*
G01Y231397D02*
Y230827D01*
G01Y233740D02*
Y233169D01*
G01Y239271D02*
Y238701D01*
G01Y241614D02*
Y241043D01*
G01Y247145D02*
Y246575D01*
G01Y249488D02*
Y248917D01*
G01Y255019D02*
Y254449D01*
G01X37075Y262008D02*
Y260827D01*
G01X36772Y262008D02*
Y260827D01*
G01X36675Y262008D02*
Y260827D01*
G01X36614Y227165D02*
Y225866D01*
G01Y230827D02*
Y229527D01*
G01Y235039D02*
Y233740D01*
G01Y238701D02*
Y237401D01*
G01Y242913D02*
Y241614D01*
G01Y246575D02*
Y245275D01*
G01Y250787D02*
Y249488D01*
G01Y254449D02*
Y253149D01*
G01X36418Y250197D02*
Y253740D01*
G01Y242323D02*
Y245866D01*
G01Y234449D02*
Y237992D01*
G01Y226575D02*
Y230118D01*
G01X36304Y260827D02*
Y262008D01*
G01X36228Y260827D02*
Y262008D01*
G01X35984Y260827D02*
Y262008D01*
G01X35522D02*
Y260827D01*
G01X35512Y225197D02*
Y223622D01*
G01Y233071D02*
Y231496D01*
G01Y240945D02*
Y239370D01*
G01Y248819D02*
Y247244D01*
G01X35342Y260827D02*
Y262008D01*
G01X35315Y225000D02*
Y223819D01*
G01Y232874D02*
Y231693D01*
G01Y240748D02*
Y239567D01*
G01Y248622D02*
Y247441D01*
G01X35314Y262008D02*
Y260827D01*
G01X35276D02*
Y262008D01*
G01X35211Y249508D02*
Y254429D01*
G01Y241634D02*
Y246555D01*
G01Y233760D02*
Y238681D01*
G01Y225886D02*
Y230807D01*
G01X35158D02*
Y225886D01*
G01Y238681D02*
Y233760D01*
G01Y246555D02*
Y241634D01*
G01Y254429D02*
Y249508D01*
G01X34744Y234449D02*
Y230118D01*
G01Y242323D02*
Y237992D01*
G01Y252165D02*
Y247834D01*
G01X34682Y225000D02*
Y223819D01*
G01Y232874D02*
Y231693D01*
G01Y240748D02*
Y239567D01*
G01Y248622D02*
Y247441D01*
G01X34478Y249508D02*
Y254429D01*
G01Y241634D02*
Y246555D01*
G01Y233760D02*
Y238681D01*
G01Y225886D02*
Y230807D01*
G01X34370D02*
Y225886D01*
G01Y238681D02*
Y233760D01*
G01Y246555D02*
Y241634D01*
G01Y254429D02*
Y249508D01*
G01X34331Y225000D02*
Y223819D01*
G01Y232874D02*
Y231693D01*
G01Y240748D02*
Y239567D01*
G01Y248622D02*
Y247441D01*
G01X34318Y250787D02*
Y253149D01*
G01Y242913D02*
Y245275D01*
G01Y235039D02*
Y237401D01*
G01Y227165D02*
Y229527D01*
G01X34252Y230827D02*
Y225866D01*
G01Y238701D02*
Y233740D01*
G01Y246575D02*
Y241614D01*
G01Y254449D02*
Y249488D01*
G01X34173Y230807D02*
Y225886D01*
G01Y238681D02*
Y233760D01*
G01Y246555D02*
Y241634D01*
G01Y254429D02*
Y249508D01*
G01X34134Y230827D02*
Y225866D01*
G01Y238701D02*
Y233740D01*
G01Y246575D02*
Y241614D01*
G01Y254449D02*
Y249488D01*
G01X34050Y225000D02*
Y223819D01*
G01Y232874D02*
Y231693D01*
G01Y240748D02*
Y239567D01*
G01Y248622D02*
Y247441D01*
G01X33977Y249508D02*
Y254429D01*
G01Y241634D02*
Y246555D01*
G01Y233760D02*
Y238681D01*
G01Y225886D02*
Y230807D01*
G01X33563Y234449D02*
Y230118D01*
G01Y242323D02*
Y237992D01*
G01Y252165D02*
Y247834D01*
G01X33465Y233169D02*
Y231397D01*
G01Y241043D02*
Y239271D01*
G01Y248917D02*
Y247145D01*
G01X33386Y230827D02*
Y225866D01*
G01Y238701D02*
Y233740D01*
G01Y246575D02*
Y241614D01*
G01Y254449D02*
Y249488D01*
G01X33347Y225433D02*
Y225197D01*
G01Y231496D02*
Y229291D01*
G01Y235275D02*
Y233071D01*
G01Y239370D02*
Y237165D01*
G01Y243149D02*
Y240945D01*
G01Y247244D02*
Y247008D01*
G01Y252992D02*
Y248819D01*
G01X33268Y247008D02*
Y252992D01*
G01Y237165D02*
Y243149D01*
G01Y229291D02*
Y235275D01*
G01X33226Y247441D02*
Y251378D01*
G01Y238189D02*
Y242126D01*
G01Y230315D02*
Y234252D01*
G01X33071Y233740D02*
Y238701D01*
G01Y230827D02*
Y225866D01*
G01Y246575D02*
Y241614D01*
G01Y254449D02*
Y249488D01*
G01X32351Y233661D02*
Y233464D01*
G01Y241535D02*
Y241338D01*
G01Y250590D02*
Y249409D01*
G01X32284Y254419D02*
Y253528D01*
G01X32256Y247441D02*
Y251378D01*
G01Y238189D02*
Y242126D01*
G01Y230315D02*
Y234252D01*
G01X32131Y231102D02*
Y230905D01*
G01Y238976D02*
Y238779D01*
G01X31890Y256890D02*
Y256102D01*
G01X31735Y234252D02*
Y230322D01*
G01Y242126D02*
Y238196D01*
G01Y251378D02*
Y247441D01*
G01X31719Y249409D02*
Y250590D01*
G01Y241338D02*
Y241535D01*
G01Y238779D02*
Y238976D01*
G01Y233464D02*
Y233661D01*
G01Y230905D02*
Y231102D01*
G01X31130Y247441D02*
Y251378D01*
G01Y238189D02*
Y242126D01*
G01Y230315D02*
Y234252D01*
G01X31103D02*
Y230315D01*
G01Y242126D02*
Y238189D01*
G01Y251968D02*
Y247441D01*
G01X30161D02*
Y251378D01*
G01Y238189D02*
Y242126D01*
G01Y230315D02*
Y234252D01*
G01X30118D02*
Y230315D01*
G01Y242126D02*
Y238189D01*
G01Y251378D02*
Y247441D01*
G01X30020Y234252D02*
Y230315D01*
G01Y242126D02*
Y238189D01*
G01Y251968D02*
Y248031D01*
G01X29823Y247834D02*
Y252165D01*
G01Y234449D02*
Y230118D01*
G01Y242323D02*
Y237992D01*
G01X29292Y260827D02*
Y262008D01*
G01X29253Y260827D02*
Y262008D01*
G01X29225D02*
Y260827D01*
G01X29046D02*
Y262008D01*
G01X29036Y234449D02*
Y230118D01*
G01Y242323D02*
Y237992D01*
G01Y252165D02*
Y247834D01*
G01X28839Y248031D02*
Y251968D01*
G01Y238189D02*
Y242126D01*
G01Y230315D02*
Y234252D01*
G01X28740Y256102D02*
Y256890D01*
G01X28583Y262008D02*
Y260827D01*
G01X28347Y257480D02*
Y254724D01*
G01X28340Y262008D02*
Y260827D01*
G01X28264Y262008D02*
Y260827D01*
G01X27892D02*
Y262008D01*
G01X27855Y234252D02*
Y230315D01*
G01Y242126D02*
Y238189D01*
G01Y251968D02*
Y248031D01*
G01X27795Y262008D02*
Y260827D01*
G01X27756Y234645D02*
Y229921D01*
G01Y242519D02*
Y237795D01*
G01Y252362D02*
Y247244D01*
G01X27658Y234449D02*
Y230118D01*
G01Y242323D02*
Y237992D01*
G01Y252165D02*
Y247834D01*
G01X27493Y260827D02*
Y262008D01*
G01X26477Y234449D02*
Y230118D01*
G01Y242323D02*
Y237992D01*
G01Y252165D02*
Y247834D01*
G01X26385Y260827D02*
Y262008D01*
G01X26378D02*
Y260827D01*
G01X25985Y262008D02*
Y260827D01*
G01X25591Y262008D02*
Y260827D01*
G01X25158Y253528D02*
Y254419D01*
G01X30648Y260827D02*
X30561Y261759D01*
G01X29862Y260388D02*
X29775Y261321D01*
G01X73686Y255008D02*
X67259Y252866D01*
G01X32284Y224764D02*
X33071Y225866D01*
G01X29721Y259470D02*
X29862Y260388D01*
G01X29775Y261321D02*
X29634Y260402D01*
G01X24803Y263386D02*
Y260827D01*
G01X24567Y250970D02*
Y245093D01*
G01X24425Y245134D02*
Y250929D01*
G01X24410Y256102D02*
Y256299D01*
G01Y245669D02*
Y250394D01*
G01X24252Y260630D02*
Y259449D01*
G01X24173Y260827D02*
Y262008D01*
G01Y246063D02*
Y250000D01*
G01X24016Y262008D02*
Y260827D01*
G01X23780Y251055D02*
Y245008D01*
G01X23664Y251059D02*
Y245004D01*
G01X23491Y244991D02*
Y251072D01*
G01X23386Y260824D02*
Y262008D01*
G01Y250970D02*
Y245093D01*
G01X23350Y245103D02*
Y250959D01*
G01X23228Y262008D02*
Y260827D01*
G01X23189Y250991D02*
Y245072D01*
G01X23073Y250995D02*
Y245068D01*
G01X23042Y250000D02*
Y246063D01*
G01X22834Y260827D02*
Y262008D01*
G01X22381Y245016D02*
Y251046D01*
G01X22241Y251286D02*
Y244777D01*
G01X21811Y246235D02*
Y249828D01*
G01Y262008D02*
Y260827D01*
G01X21327Y262008D02*
Y260827D01*
G01X21147Y250000D02*
Y246063D01*
G01X21131Y251261D02*
Y244802D01*
G01X21103Y256299D02*
Y260630D01*
G01X21024Y262008D02*
Y260827D01*
G01X20927Y262008D02*
Y260827D01*
G01X20670Y300590D02*
Y298228D01*
G01X20236Y236240D02*
Y258268D01*
G01X19882Y298228D02*
Y310039D01*
G01X19594Y260827D02*
Y262008D01*
G01X19566D02*
Y260827D01*
G01X19528D02*
Y262008D01*
G01X17717Y256299D02*
Y236240D01*
G01X17520Y295275D02*
Y330708D01*
G01X15158Y327756D02*
Y298228D01*
G01X14764Y330708D02*
Y295275D01*
G01X38032Y256102D02*
X39010Y257081D01*
G01X33071Y233740D02*
X32284Y232638D01*
G01Y240512D02*
X33071Y241614D01*
G01X32284Y248386D02*
X33071Y249488D01*
G01X35033Y259087D02*
X36167Y260827D01*
G01X36154Y262008D02*
X35008Y260249D01*
G01X47047Y298228D02*
X49410Y304134D01*
G01X64567Y346456D02*
G03X72441I3937J0D01*
G01Y321260D02*
G03X64567I-3937J0D01*
G01X29075Y362205D02*
G03X31044Y364173I0J1969D01*
G01X0Y366142D02*
G03X3937Y362205I3937J0D01*
G01X31044Y364173D02*
Y387795D01*
G01X0Y566847D02*
Y366142D01*
G01X3937Y362205D02*
X29075D01*
G01X16689Y320886D02*
X16339Y320866D01*
G01X17013Y320947D02*
X16689Y320886D01*
G01X17280Y321046D02*
X17013Y320947D01*
G01X17457Y321174D02*
X17280Y321046D01*
G01X17520Y321320D02*
X17457Y321174D01*
G01X47878Y306082D02*
X48229Y306102D01*
G01X47554Y306021D02*
X47878Y306082D01*
G01X47287Y305922D02*
X47554Y306021D01*
G01X47110Y305794D02*
X47287Y305922D01*
G01X47047Y305648D02*
X47110Y305794D01*
G01X17457Y304809D02*
X17520Y304664D01*
G01X17281Y304938D02*
X17457Y304809D01*
G01X17014Y305036D02*
X17281Y304938D01*
G01X16690Y305097D02*
X17014Y305036D01*
G01X16339Y305118D02*
X16690Y305097D01*
G01X47110Y320190D02*
X47047Y320336D01*
G01X47287Y320062D02*
X47110Y320190D01*
G01X47553Y319963D02*
X47287Y320062D01*
G01X47878Y319902D02*
X47553Y319963D01*
G01X48229Y319882D02*
X47878Y319902D01*
G01X64567Y350394D02*
G03X60630Y354331I-3937J0D01*
G01X37098Y319123D02*
G03X36612Y319291I-486J-619D01*
G01X37533Y318861D02*
G03X36221Y317394I-656J-733D01*
G01X36612Y306693D02*
G03X37098Y306861I0J787D01*
G01X33268Y321260D02*
G03X31299I-985J0D01*
G01Y312795D02*
G03X33268I984J0D01*
G01X28347Y317394D02*
G03X36221I3937J-4402D01*
G01X37098Y306861D02*
G03X39712Y310630I-4815J6130D01*
G01X24855D02*
G03X27469Y306861I7429J2361D01*
G01X39712Y315354D02*
G03X37098Y319123I-7429J-2361D01*
G01X27468Y319122D02*
G03X24855Y315354I4816J-6130D01*
G01X27034Y318861D02*
G03X37533I5250J-5869D01*
G01X23624Y310629D02*
G03X27037Y305709I8660J2363D01*
G01X37531D02*
G03X40944Y310629I-5247J7283D01*
G01X27037Y320275D02*
G03X23624Y315355I5247J-7283D01*
G01X40944D02*
G03X37531Y320275I-8660J-2363D01*
G01X23245Y309857D02*
G03X26065Y305722I9039J3135D01*
G01X38502D02*
G03X41322Y309857I-6218J7270D01*
G01Y316127D02*
G03X38502Y320262I-9038J-3135D01*
G01X26065D02*
G03X23245Y316127I6219J-7270D01*
G01X23243Y309744D02*
G03X26007Y305720I9040J3248D01*
G01X38561D02*
G03X41324Y309744I-6278J7271D01*
G01Y316240D02*
G03X38561Y320264I-9041J-3247D01*
G01X26007D02*
G03X23243Y316240I6276J-7272D01*
G01X45079Y312992D02*
G03I-12795J0D01*
G01X45670D02*
G03I-13386J0D01*
G01X45866D02*
G03I-13582J0D01*
G01X40158Y324777D02*
G03X24409I-7875J-11785D01*
G01X27470Y306861D02*
G03X27956Y306693I486J619D01*
G01Y319291D02*
G03X27468Y319122I-1J-787D01*
G01X28347Y317394D02*
G03X27034Y318861I-657J734D01*
G01X3937Y354331D02*
G03X0Y350394I0J-3937D01*
G01X60630Y354331D02*
X3937D01*
G01X41772Y336630D02*
X43740D01*
G01Y336384D02*
X42107D01*
G01X42400Y336138D02*
X42065D01*
G01X42945Y335810D02*
X43740D01*
G01Y335605D02*
X42945D01*
G01X42400Y334867D02*
X42610D01*
G01X42777D02*
X43740D01*
G01Y334662D02*
X42400D01*
G01Y334334D02*
X43740D01*
G01X41772D02*
X41981D01*
G01Y334129D02*
X41772D01*
G01X43740D02*
X42400D01*
G01X42903Y333801D02*
X43238D01*
G01X42945Y333596D02*
X43196D01*
G01X42735Y335769D02*
X42945Y335810D01*
G01Y335605D02*
X42735Y335564D01*
G01Y333760D02*
X42903Y333801D01*
G01X42400Y332693D02*
X42651D01*
G01X43489D02*
X44410D01*
G01X43280D02*
X42861D01*
G01X44410Y332488D02*
X42400D01*
G01X49803Y330708D02*
X14764D01*
G01X49803Y328149D02*
X14764D01*
G01X49410Y327756D02*
X15158D01*
G01X44685Y325394D02*
X19882D01*
G01X17520Y325197D02*
X14764D01*
G01X49803D02*
X47047D01*
G01X23622Y324606D02*
X21260D01*
G01X33465D02*
X31103D01*
G01X43307D02*
X40945D01*
G01X23622Y324473D02*
X21260D01*
G01X33465D02*
X31103D01*
G01X43307D02*
X40945D01*
G01X44292Y324311D02*
X20276D01*
G01X23622Y323508D02*
X21260D01*
G01X33465D02*
X31103D01*
G01X43307D02*
X40945D01*
G01X23622Y323477D02*
X21260D01*
G01X33465D02*
X31103D01*
G01X43307D02*
X40945D01*
G01X23622Y323425D02*
X21260D01*
G01X33465D02*
X31103D01*
G01X43307D02*
X40945D01*
G01X23622Y323394D02*
X21260D01*
G01X33465D02*
X31103D01*
G01X43307D02*
X40945D01*
G01X17520Y322933D02*
X15158D01*
G01X17520Y322834D02*
X15158D01*
G01X23622Y322377D02*
X21260D01*
G01X33465D02*
X31103D01*
G01X43307D02*
X40945D01*
G01X23622Y322244D02*
X21260D01*
G01X33465D02*
X31103D01*
G01X43307D02*
X40945D01*
G01X49410Y321949D02*
X47047D01*
G01Y321850D02*
X49410D01*
G01X41536Y321456D02*
X37795D01*
G01X20276Y321358D02*
X44292D01*
G01X15158Y320866D02*
X16339D01*
G01X37795Y320472D02*
X23032D01*
G01X41339Y320275D02*
X23229D01*
G01X48229Y319882D02*
X49410D01*
G01X36612Y319291D02*
X27956D01*
G01X43196Y333596D02*
X43322Y333555D01*
G01X43238Y333801D02*
X43405Y333760D01*
G01X17520Y317323D02*
X15158D01*
G01X49410D02*
X47047D01*
G01X17520Y317126D02*
X15158D01*
G01X49410D02*
X47047D01*
G01X44685Y316732D02*
X47047D01*
G01X17520D02*
X19882D01*
G01X47047Y315945D02*
X17520D01*
G01X23229Y315354D02*
X41339D01*
G01X45866Y314567D02*
X49410D01*
G01X18701D02*
X15158D01*
G01X12107Y313779D02*
X52461D01*
G01X12107Y312205D02*
X52461D01*
G01X45866Y311417D02*
X49410D01*
G01X15158D02*
X18701D01*
G01X41339Y310630D02*
X23229D01*
G01X47047Y310039D02*
X17520D01*
G01X44685Y309252D02*
X47047D01*
G01X19882D02*
X17520D01*
G01Y308858D02*
X15158D01*
G01X49410D02*
X47047D01*
G01X17520Y308661D02*
X15158D01*
G01X49410D02*
X47047D01*
G01X36612Y306693D02*
X27956D01*
G01X48229Y306102D02*
X49410D01*
G01X23229Y305708D02*
X41339D01*
G01X37795Y305512D02*
X23032D01*
G01X15158Y305118D02*
X16339D01*
G01X44292Y304626D02*
X20276D01*
G01X41536Y304527D02*
X37795D01*
G01X49410Y304134D02*
X47047D01*
G01Y304035D02*
X49410D01*
G01X23622Y303740D02*
X21260D01*
G01X33465D02*
X31103D01*
G01X43307D02*
X40945D01*
G01X23622Y303607D02*
X21260D01*
G01X33465D02*
X31103D01*
G01X43307D02*
X40945D01*
G01X17520Y303149D02*
X15158D01*
G01X17520Y303051D02*
X15158D01*
G01X23622Y302590D02*
X21260D01*
G01X33465D02*
X31103D01*
G01X43307D02*
X40945D01*
G01X23622Y302559D02*
X21260D01*
G01X33465D02*
X31103D01*
G01X43307D02*
X40945D01*
G01Y302507D02*
X43307D01*
G01X31103D02*
X33465D01*
G01X21260D02*
X23622D01*
G01Y302476D02*
X21260D01*
G01X33465D02*
X31103D01*
G01X43307D02*
X40945D01*
G01X20276Y301673D02*
X44292D01*
G01X23622Y301511D02*
X21260D01*
G01X33465D02*
X31103D01*
G01X43307D02*
X40945D01*
G01Y301378D02*
X43307D01*
G01X31103D02*
X33465D01*
G01X21260D02*
X23622D01*
G01X17520Y300787D02*
X14764D01*
G01X49803D02*
X47047D01*
G01X44685Y300590D02*
X19882D01*
G01X43322Y333555D02*
X43405Y333514D01*
G01X42651Y332693D02*
X42568Y332734D01*
G01X42861Y332693D02*
X42735Y332775D01*
G01X47047Y315945D02*
X49410Y314567D01*
G01X42107Y336384D02*
X42400Y336138D01*
G01X42065D02*
X41772Y336384D01*
G01X43405Y333760D02*
X43615Y333596D01*
G01X42693Y334949D02*
X42777Y334867D01*
G01X42610D02*
X42526Y334949D01*
G01X42568Y332734D02*
X42484Y332816D01*
G01X17520Y310039D02*
X15158Y311417D01*
G01X42028Y324311D02*
X42717Y323622D01*
G01X42028Y304626D02*
X42717Y303937D01*
G01X43615Y333596D02*
X43698Y333472D01*
G01X42610Y335072D02*
X42693Y334949D01*
G01X42526D02*
X42442Y335072D01*
G01X43405Y333514D02*
X43489Y333390D01*
G01X42735Y332775D02*
X42651Y332898D01*
G01X42484Y332816D02*
X42442Y332898D01*
G01X39764Y300953D02*
X40076Y300452D01*
G01X24492Y325532D02*
X24803Y325030D01*
G01X40158Y301207D02*
X40486Y300716D01*
G01X24082Y325268D02*
X24410Y324777D01*
G01X49410Y321850D02*
X47047Y327756D01*
G01X43698Y333472D02*
X43740Y333308D01*
G01X43489Y333390D02*
X43531Y333226D01*
G01X42568Y335236D02*
X42610Y335072D01*
G01X42442D02*
X42400Y335236D01*
G01X42651Y332898D02*
X42610Y333062D01*
G01X42442Y332898D02*
X42400Y333062D01*
G01X52461Y313779D02*
Y312205D01*
G01X51477Y313779D02*
Y312205D01*
G01X51280D02*
Y313779D01*
G01X49410Y304134D02*
Y321850D01*
G01Y327756D02*
Y321949D01*
G01X48229Y306102D02*
Y319882D01*
G01X48032Y313779D02*
Y312205D01*
G01X47964D02*
Y313779D01*
G01X46851Y312205D02*
Y313779D01*
G01X45866Y314567D02*
Y311417D01*
G01X44685Y315945D02*
Y327756D01*
G01X44410Y332693D02*
Y332488D01*
G01X44292Y321358D02*
Y324311D01*
G01Y301673D02*
Y304626D01*
G01X43898D02*
Y301673D01*
G01Y324311D02*
Y321358D01*
G01Y327756D02*
Y325394D01*
G01X43740Y334334D02*
Y334129D01*
G01Y333308D02*
Y333062D01*
G01Y334867D02*
Y334662D01*
G01Y335810D02*
Y335605D01*
G01Y336630D02*
Y336384D01*
G01X43531Y333226D02*
Y333062D01*
G01X43307Y322244D02*
Y324606D01*
G01Y303740D02*
Y301378D01*
G01X42717Y303937D02*
Y302362D01*
G01Y323622D02*
Y322047D01*
G01X42610Y333062D02*
Y333308D01*
G01X42400Y334662D02*
Y334867D01*
G01Y335236D02*
Y335400D01*
G01Y334129D02*
Y334334D01*
G01Y333062D02*
Y333308D01*
G01Y332488D02*
Y332693D01*
G01X41981Y334334D02*
Y334129D01*
G01X41772Y336384D02*
Y336630D01*
G01Y334129D02*
Y334334D01*
G01X41536Y303740D02*
Y302559D01*
G01Y321456D02*
Y304527D01*
G01Y323425D02*
Y322244D01*
G01X41339Y305708D02*
Y320275D01*
G01X40945Y322244D02*
Y324606D01*
G01Y303740D02*
Y301378D01*
G01X37795Y305512D02*
Y304527D01*
G01Y321456D02*
Y320472D01*
G01X37008Y306800D02*
Y305708D01*
G01Y320275D02*
Y319184D01*
G01X36614Y325032D02*
Y326487D01*
G01Y299497D02*
Y300952D01*
G01X33465Y322244D02*
Y324606D01*
G01Y303740D02*
Y301378D01*
G01X33268Y321260D02*
Y312795D01*
G01X32874Y322244D02*
Y323425D01*
G01Y302559D02*
Y303740D01*
G01X31693D02*
Y302559D01*
G01Y323425D02*
Y322244D01*
G01X31299Y321260D02*
Y312795D01*
G01X31103Y322244D02*
Y324606D01*
G01Y303740D02*
Y301378D01*
G01X27953Y300952D02*
Y299497D01*
G01Y326487D02*
Y325032D01*
G01X27559Y319184D02*
Y320275D01*
G01Y306800D02*
Y305708D01*
G01X23622Y322244D02*
Y324606D01*
G01Y303740D02*
Y301378D01*
G01X23229Y320275D02*
Y305708D01*
G01X23032Y322244D02*
Y323425D01*
G01Y302559D02*
Y303740D01*
G01Y320472D02*
Y305512D01*
G01X21851Y303740D02*
Y302559D01*
G01Y323425D02*
Y322244D01*
G01X21260D02*
Y324606D01*
G01Y303740D02*
Y301378D01*
G01X20670Y327756D02*
Y325394D01*
G01X20276Y304626D02*
Y301673D01*
G01Y324311D02*
Y321358D01*
G01X19882Y315945D02*
Y327756D01*
G01X18701Y311417D02*
Y314567D01*
G01X17717Y313779D02*
Y312205D01*
G01X16603Y313779D02*
Y312205D01*
G01X16536D02*
Y313779D01*
G01X16339Y305118D02*
Y320866D01*
G01X13288Y313779D02*
Y312205D01*
G01X13091D02*
Y313779D01*
G01X12107Y312205D02*
Y313779D01*
G01X43740Y333062D02*
X43698Y332898D01*
G01X43531Y333062D02*
X43489Y332898D01*
G01X42400Y333308D02*
X42442Y333472D01*
G01X42610Y335400D02*
X42568Y335236D01*
G01X42400Y335400D02*
X42442Y335523D01*
G01X42717Y302362D02*
X42028Y301673D01*
G01X39764Y325030D02*
X40076Y325532D01*
G01X24803Y300953D02*
X24492Y300452D01*
G01X43698Y332898D02*
X43657Y332816D01*
G01X42610Y333308D02*
X42693Y333472D01*
G01X42651Y335482D02*
X42610Y335400D01*
G01X49410Y311417D02*
X47047Y310039D01*
G01X42717Y322047D02*
X42028Y321358D01*
G01X43489Y332898D02*
X43405Y332775D01*
G01X42442Y333472D02*
X42526Y333596D01*
G01X42442Y335523D02*
X42526Y335646D01*
G01X24410Y301207D02*
X24082Y300716D01*
G01X40486Y325268D02*
X40158Y324777D01*
G01X17520Y315945D02*
X15158Y314567D01*
G01X43405Y332775D02*
X43280Y332693D01*
G01X43657Y332816D02*
X43573Y332734D01*
G01X42526Y333596D02*
X42651Y333719D01*
G01X42735Y335564D02*
X42651Y335482D01*
G01X42526Y335646D02*
X42610Y335728D01*
G01X42819Y333555D02*
X42945Y333596D01*
G01X42610Y335728D02*
X42735Y335769D01*
G01X43573Y332734D02*
X43489Y332693D01*
G01X42651Y333719D02*
X42735Y333760D01*
G01X42693Y333472D02*
X42819Y333555D01*
G01X44390Y393701D02*
G03I-2658J0D01*
G01X33012Y389764D02*
G03X31044Y387795I0J-1968D01*
G01X33012Y389764D02*
X199666D01*
G01X71407Y517570D02*
G03X76975Y523137I2784J2784D01*
G01X64567Y526040D02*
G03X65720Y523256I3938J0D01*
G01D02*
X94910Y494066D01*
G01X64567Y526040D02*
Y637713D01*
G01X-2692Y600283D02*
G03X0Y604019I-1245J3735D01*
G01Y566847D02*
G03X-2692Y570582I-3937J0D01*
G01X64567Y674885D02*
G03X67259Y671150I3937J0D01*
G01Y641448D02*
G03X64567Y637713I1245J-3735D01*
G01X73686Y669007D02*
X67259Y671150D01*
G01X64567Y674885D02*
Y738976D01*
G01X73686Y643591D02*
X67259Y641448D01*
G01X0Y738976D02*
Y604019D01*
G01X64567Y735039D02*
G03X72441I3937J0D01*
G01Y709842D02*
G03X64567I-3937J0D01*
G01Y738976D02*
G03X60630Y742913I-3937J0D01*
G01X3937D02*
G03X0Y738976I0J-3937D01*
G01X60630Y742913D02*
X3937D01*
G01X121130Y-354220D02*
Y-371543D01*
G01X105886Y-24803D02*
X104311Y-26378D01*
G01X141339Y-4725D02*
X141477Y-788D01*
G01X131339Y-4725D02*
X131477Y-788D01*
G01X146792D02*
Y-4725D01*
G01X144370Y-788D02*
Y-4725D01*
G01X143780Y-788D02*
Y-4725D01*
G01X140886D02*
Y-788D01*
G01X137107D02*
Y-4725D01*
G01X136792D02*
Y-788D01*
G01X132776Y-16142D02*
Y-788D01*
G01X146201D02*
X146338Y-4725D01*
G01X121024D02*
X121162Y-788D01*
G01X111477Y-4725D02*
X111614Y-788D01*
G01X111339Y-4725D02*
X111477Y-788D01*
G01X130886Y-4725D02*
Y-788D01*
G01X126398D02*
Y-4725D01*
G01X125807Y-788D02*
Y-4725D01*
G01X124902Y-788D02*
Y-16142D01*
G01X121870Y-788D02*
Y-4725D01*
G01X121280Y-788D02*
Y-4725D01*
G01X120571D02*
Y-788D01*
G01X116929D02*
Y-4725D01*
G01X116792D02*
Y-788D01*
G01X136516D02*
X136653Y-4725D01*
G01X136338D02*
X136201Y-788D01*
G01X111024Y-4725D02*
Y-788D01*
G01X110886Y-4725D02*
Y-788D01*
G01X109154D02*
Y-4725D01*
G01X108445Y-788D02*
Y-4725D01*
G01X108347Y-25512D02*
Y-7087D01*
G01X105886Y-24803D02*
Y-7087D01*
G01X116339Y-788D02*
X116476Y-4725D01*
G01X116338D02*
X116201Y-788D01*
G01X108563D02*
X108701Y-4725D01*
G01X107855Y-788D02*
X107992Y-4725D01*
G01X84292D02*
X84429Y-788D01*
G01X98603Y-20473D02*
Y-7087D01*
G01X94075D02*
Y-20473D01*
G01X86792Y-24803D02*
Y-7087D01*
G01X79173Y-788D02*
X79036Y-4725D01*
G01X74036D02*
X74173Y-788D01*
G01X84331Y-25512D02*
Y-7087D01*
G01X83839Y-4725D02*
Y-788D01*
G01X79095Y-4725D02*
Y-788D01*
G01X78583D02*
Y-4725D01*
G01X75729D02*
Y-788D01*
G01X73583Y-4725D02*
Y-788D01*
G01X72776Y-17126D02*
Y-788D01*
G01X78504D02*
X78642Y-4725D01*
G01X75275D02*
X75138Y-788D01*
G01X86792Y-24803D02*
X88366Y-26378D01*
G01X146338Y-4725D02*
X156339D01*
G01X75275D02*
X84292D01*
G01X111477D02*
X107992D01*
G01X121870D02*
X116338D01*
G01X131339D02*
X125807D01*
G01X144370D02*
X136338D01*
G01X105886Y-8268D02*
X182146D01*
G01X124902Y-14764D02*
X132776D01*
G01X124902Y-16142D02*
X132776D01*
G01X98603Y-20473D02*
X94075D01*
G01X86792Y-24803D02*
X105886D01*
G01X105492Y-25197D02*
X182146D01*
G01X84331Y-25512D02*
X108347D01*
G01X127362Y78740D02*
G03I-11023J0D01*
G01X134449D02*
G03I-18110J0D01*
G01X137992D02*
G03I-21653J0D01*
G01X115645Y-99D02*
G03X115441Y256I-204J119D01*
G01X117236D02*
G03X117032Y-98I1J-236D01*
G01X120645Y-99D02*
G03X120441Y256I-204J119D01*
G01X122236D02*
G03X122032Y-98I1J-236D01*
G01X125645Y-99D02*
G03X125441Y256I-204J119D01*
G01X127236D02*
G03X127032Y-98I1J-236D01*
G01X130645Y-99D02*
G03X130441Y256I-204J119D01*
G01X132236D02*
G03X132032Y-98I1J-236D01*
G01X135645Y-99D02*
G03X135441Y256I-204J119D01*
G01X137236D02*
G03X137032Y-98I1J-236D01*
G01X140645Y-99D02*
G03X140441Y256I-204J119D01*
G01X142236D02*
G03X142032Y-98I1J-236D01*
G01X145645Y-99D02*
G03X145441Y256I-204J119D01*
G01X147236D02*
G03X147032Y-98I1J-236D01*
G01X110512Y7409D02*
G03I-1673J0D01*
G01X101929Y-67D02*
G03X102126Y130I0J197D01*
G01X103110D02*
G03X103307Y-67I197J0D01*
G01X98780D02*
G03X98977Y130I0J197D01*
G01X99961D02*
G03X100158Y-67I197J0D01*
G01X95630D02*
G03X95827Y130I0J197D01*
G01X96811D02*
G03X97008Y-67I197J0D01*
G01X92481D02*
G03X92677Y130I0J196D01*
G01X93662D02*
G03X93858Y-67I197J0D01*
G01X89331D02*
G03X89528Y130I0J197D01*
G01X90512D02*
G03X90709Y-67I197J0D01*
G01X86181D02*
G03X86378Y130I0J197D01*
G01X87362D02*
G03X87559Y-67I197J0D01*
G01X105079D02*
G03X105276Y130I0J197D01*
G01X106260D02*
G03X106457Y-67I197J0D01*
G01X112236Y256D02*
G03X112032Y-98I1J-236D01*
G01X107236Y256D02*
G03X107032Y-98I1J-236D01*
G01X110645Y-99D02*
G03X110441Y256I-204J119D01*
G01X82638Y2559D02*
G03X83032Y2953I0J394D01*
G01X84607D02*
G03X85000Y2559I394J0D01*
G01X74607Y2953D02*
G03X75000Y2559I394J0D01*
G01X77638D02*
G03X78032Y2953I0J394D01*
G01X79607D02*
G03X80000Y2559I394J0D01*
G01X82365Y-788D02*
G03X82345Y-768I-428J-408D01*
G01X81900Y-105D02*
G03X82095Y-543I589J0D01*
G01X85543D02*
G03X85738Y-105I-394J438D01*
G01X85294Y-768D02*
G03X85273Y-788I396J-437D01*
G01X75294Y-768D02*
G03X75273Y-788I396J-437D01*
G01X75543Y-543D02*
G03X75738Y-105I-394J438D01*
G01X77365Y-788D02*
G03X77345Y-768I-428J-408D01*
G01X76900Y-105D02*
G03X77095Y-543I589J0D01*
G01X80543D02*
G03X80738Y-105I-394J438D01*
G01X80294Y-768D02*
G03X80273Y-788I396J-437D01*
G01X72638Y2559D02*
G03X73032Y2953I0J394D01*
G01X72365Y-788D02*
G03X72345Y-768I-428J-408D01*
G01X109418Y11318D02*
X109541Y11360D01*
G01X107449Y10941D02*
X107326Y10899D01*
G01X107367Y10690D02*
X107449Y10731D01*
G01X107326Y10899D02*
X107203Y10815D01*
G01X109377Y11527D02*
X109213Y11402D01*
G01X145662Y-108D02*
X145270Y-788D01*
G01X85543Y-543D02*
X85294Y-768D01*
G01X80543Y-543D02*
X80294Y-768D01*
G01X75543Y-543D02*
X75294Y-768D01*
G01X109336Y11234D02*
X109418Y11318D01*
G01X107285Y10606D02*
X107367Y10690D01*
G01X107203Y10815D02*
X107121Y10731D01*
G01X140662Y-108D02*
X140270Y-788D01*
G01X135662Y-108D02*
X135270Y-788D01*
G01X130662Y-108D02*
X130270Y-788D01*
G01X109213Y11402D02*
X109090Y11234D01*
G01X125662Y-108D02*
X125270Y-788D01*
G01X120662Y-108D02*
X120270Y-788D01*
G01X115662Y-108D02*
X115270Y-788D01*
G01X110662Y-108D02*
X110270Y-788D01*
G01X109295Y11108D02*
X109336Y11234D01*
G01X109090D02*
X109049Y11108D01*
G01X107121Y10731D02*
X107080Y10606D01*
G01X106851Y-682D02*
X106816Y-788D01*
G01X103701Y-682D02*
X103667Y-788D01*
G01X100551Y-682D02*
X100517Y-788D01*
G01X97402Y-682D02*
X97368Y-788D01*
G01X94252Y-682D02*
X94218Y-788D01*
G01X91103Y-682D02*
X91068Y-788D01*
G01X87953Y-682D02*
X87919Y-788D01*
G01X107244Y10396D02*
X107285Y10606D01*
G01X107080D02*
X107039Y10396D01*
G01X144725Y8472D02*
Y276D01*
G01X142953Y8472D02*
Y275D01*
G01X139725Y8472D02*
Y276D01*
G01X137953Y8472D02*
Y275D01*
G01X134725Y8472D02*
Y276D01*
G01X132953Y8472D02*
Y275D01*
G01X129725Y8472D02*
Y276D01*
G01X127953Y8472D02*
Y275D01*
G01X124725Y8472D02*
Y276D01*
G01X122953Y8472D02*
Y275D01*
G01X119725Y8472D02*
Y276D01*
G01X117953Y8472D02*
Y275D01*
G01X114725Y8472D02*
Y276D01*
G01X112953Y8472D02*
Y275D01*
G01X110566Y9601D02*
Y11569D01*
G01X110320Y10480D02*
Y9601D01*
G01Y11360D02*
Y10731D01*
G01X109725Y8472D02*
Y276D01*
G01X109295Y10983D02*
Y11108D01*
G01X109049D02*
Y10941D01*
G01X108721Y11360D02*
Y11569D01*
G01Y9601D02*
Y10941D01*
G01X108516Y11569D02*
Y11360D01*
G01Y10941D02*
Y9601D01*
G01X108187D02*
Y10941D01*
G01X107982Y10564D02*
Y9601D01*
G01Y10941D02*
Y10731D01*
G01X107953Y8472D02*
Y275D01*
G01X107244Y9601D02*
Y10396D01*
G01X107039D02*
Y9601D01*
G01X106870Y-788D02*
Y-3544D01*
G01X106851Y-67D02*
Y-682D01*
G01X106711Y10941D02*
Y11276D01*
G01X106465Y9601D02*
Y11234D01*
G01X106280Y-3544D02*
Y-788D01*
G01X106260Y8472D02*
Y130D01*
G01X106219Y11569D02*
Y9601D01*
G01X105276Y130D02*
Y8472D01*
G01X104685Y-67D02*
Y-682D01*
G01X104629Y-788D02*
Y-3544D01*
G01X104039Y-788D02*
Y-3544D01*
G01X103701Y-67D02*
Y-682D01*
G01X103110Y8472D02*
Y130D01*
G01X102126D02*
Y8472D01*
G01X101536Y-67D02*
Y-682D01*
G01X100551Y-67D02*
Y-682D01*
G01X99961Y8472D02*
Y130D01*
G01X98977D02*
Y8472D01*
G01X98504Y-3544D02*
Y-788D01*
G01X98386Y-67D02*
Y-682D01*
G01X97914Y-788D02*
Y-3544D01*
G01X97402Y-67D02*
Y-682D01*
G01X96811Y8472D02*
Y130D01*
G01X95827D02*
Y8472D01*
G01X95236Y-67D02*
Y-682D01*
G01X94764Y-788D02*
Y-3544D01*
G01X94252Y-67D02*
Y-682D01*
G01X94173Y-3544D02*
Y-788D01*
G01X93662Y8472D02*
Y130D01*
G01X92677Y8472D02*
Y130D01*
G01X92087Y-67D02*
Y-682D01*
G01X91103Y-67D02*
Y-682D01*
G01X90512Y8472D02*
Y130D01*
G01X89528D02*
Y8472D01*
G01X88937Y-67D02*
Y-682D01*
G01X88639Y-788D02*
Y-3544D01*
G01X88048Y-788D02*
Y-3544D01*
G01X87953Y-67D02*
Y-682D01*
G01X87362Y8472D02*
Y130D01*
G01X86398Y-3544D02*
Y-788D01*
G01X86378Y130D02*
Y8472D01*
G01X85807Y-3544D02*
Y-788D01*
G01X85788Y-67D02*
Y-682D01*
G01X85738Y2559D02*
Y-105D01*
G01X84607Y8472D02*
Y2953D01*
G01X83032Y8472D02*
Y2953D01*
G01X81900Y2559D02*
Y-105D01*
G01X80738Y2559D02*
Y-105D01*
G01X79607Y8472D02*
Y2953D01*
G01X78032Y8472D02*
Y2953D01*
G01X76900Y2559D02*
Y-105D01*
G01X75738Y2559D02*
Y-105D01*
G01X74607Y2953D02*
Y8472D01*
G01X73032D02*
Y2953D01*
G01X109336Y10857D02*
X109295Y10983D01*
G01X109049Y10941D02*
X109090Y10815D01*
G01X147408Y-788D02*
X147015Y-108D01*
G01X142408Y-788D02*
X142015Y-108D01*
G01X104685Y-682D02*
X104720Y-788D01*
G01X101536Y-682D02*
X101570Y-788D01*
G01X98386Y-682D02*
X98420Y-788D01*
G01X95236Y-682D02*
X95271Y-788D01*
G01X92087Y-682D02*
X92121Y-788D01*
G01X137408D02*
X137015Y-108D01*
G01X132408Y-788D02*
X132015Y-108D01*
G01X127408Y-788D02*
X127015Y-108D01*
G01X88937Y-682D02*
X88971Y-788D01*
G01X85788Y-682D02*
X85822Y-788D01*
G01X122408D02*
X122015Y-108D01*
G01X117408Y-788D02*
X117015Y-108D01*
G01X112408Y-788D02*
X112015Y-108D01*
G01X107408Y-788D02*
X107015Y-108D01*
G01X109090Y10815D02*
X109213Y10648D01*
G01X106711Y11276D02*
X106465Y11569D01*
G01Y11234D02*
X106711Y10941D01*
G01X109418Y10773D02*
X109336Y10857D01*
G01X107982Y10731D02*
X107900Y10815D01*
G01Y10648D02*
X107982Y10564D01*
G01X109213Y10648D02*
X109377Y10522D01*
G01X107900Y10815D02*
X107777Y10899D01*
G01Y10731D02*
X107900Y10648D01*
G01X82095Y-543D02*
X82345Y-768D01*
G01X77095Y-543D02*
X77345Y-768D01*
G01X109541Y10731D02*
X109418Y10773D01*
G01X107777Y10899D02*
X107613Y10941D01*
G01Y10773D02*
X107777Y10731D01*
G01X109582Y11569D02*
X109377Y11527D01*
G01X107449Y10731D02*
X107613Y10773D01*
G01X109377Y10522D02*
X109582Y10480D01*
G01X147953Y275D02*
X147236Y276D01*
G01X142953Y275D02*
X142236Y276D01*
G01X137953Y275D02*
X137236Y276D01*
G01X132953Y275D02*
X132236Y276D01*
G01X127953Y275D02*
X127236Y276D01*
G01X122953Y275D02*
X122236Y276D01*
G01X117953Y275D02*
X117236Y276D01*
G01X112953Y275D02*
X112236Y276D01*
G01X107953Y275D02*
X107236Y276D01*
G01X106465Y11569D02*
X106219D01*
G01X108721D02*
X108516D01*
G01X110566D02*
X109582D01*
G01X108516Y11360D02*
X108721D01*
G01X109541D02*
X110320D01*
G01X108187Y10941D02*
X107982D01*
G01X107613D02*
X107449D01*
G01X108721D02*
X108516D01*
G01X110320Y10731D02*
X109541D01*
G01X109582Y10480D02*
X110320D01*
G01Y9601D02*
X110566D01*
G01X108516D02*
X108721D01*
G01X107982D02*
X108187D01*
G01X107039D02*
X107244D01*
G01X106219D02*
X106465D01*
G01X105276Y8472D02*
X106260D01*
G01X102126D02*
X103110D01*
G01X98977D02*
X99961D01*
G01X95827D02*
X96811D01*
G01X92677D02*
X93662D01*
G01X89528D02*
X90512D01*
G01X86378D02*
X87362D01*
G01X74607D02*
X73032D01*
G01X79607D02*
X78032D01*
G01X84607D02*
X83032D01*
G01X109725D02*
X107953D01*
G01X114725D02*
X112953D01*
G01X119725D02*
X117953D01*
G01X124725D02*
X122953D01*
G01X129725D02*
X127953D01*
G01X134725D02*
X132953D01*
G01X139725D02*
X137953D01*
G01X144725D02*
X142953D01*
G01X74607Y6110D02*
X73032D01*
G01X79607D02*
X78032D01*
G01X84607D02*
X83032D01*
G01X107953Y5512D02*
X109725D01*
G01X114725D02*
X112953D01*
G01X119725D02*
X117953D01*
G01X124725D02*
X122953D01*
G01X129725D02*
X127953D01*
G01X134725D02*
X132953D01*
G01X139725D02*
X137953D01*
G01X144725D02*
X142953D01*
G01X83032Y5365D02*
X84607D01*
G01X78032D02*
X79607D01*
G01X74607D02*
X73032D01*
G01X87362Y4668D02*
X86378D01*
G01X90512D02*
X89528D01*
G01X93662D02*
X92677D01*
G01X96811D02*
X95827D01*
G01X99961D02*
X98977D01*
G01X103110D02*
X102126D01*
G01X106260D02*
X105276D01*
G01X73032Y4621D02*
X74607D01*
G01X79607D02*
X78032D01*
G01X84607D02*
X83032D01*
G01Y4547D02*
X84607D01*
G01X78032D02*
X79607D01*
G01X74607D02*
X73032D01*
G01X109725Y4527D02*
X107953D01*
G01X114725D02*
X112953D01*
G01X119725D02*
X117953D01*
G01X124725D02*
X122953D01*
G01X129725D02*
X127953D01*
G01X134725D02*
X132953D01*
G01X139725D02*
X137953D01*
G01X144725D02*
X142953D01*
G01X105276Y4113D02*
X106260D01*
G01X102126D02*
X103110D01*
G01X98977D02*
X99961D01*
G01X95827D02*
X96811D01*
G01X92677D02*
X93662D01*
G01X89528D02*
X90512D01*
G01X86378D02*
X87362D01*
G01X105276Y4062D02*
X106260D01*
G01X102126D02*
X103110D01*
G01X98977D02*
X99961D01*
G01X95827D02*
X96811D01*
G01X92677D02*
X93662D01*
G01X89528D02*
X90512D01*
G01X86378D02*
X87362D01*
G01X73032Y3802D02*
X74607D01*
G01X79607D02*
X78032D01*
G01X84607D02*
X83032D01*
G01X87362Y3558D02*
X86378D01*
G01X90512D02*
X89528D01*
G01X93662D02*
X92677D01*
G01X96811D02*
X95827D01*
G01X99961D02*
X98977D01*
G01X103110D02*
X102126D01*
G01X106260D02*
X105276D01*
G01X109725Y3543D02*
X107953D01*
G01X114725D02*
X112953D01*
G01X119725D02*
X117953D01*
G01X124725D02*
X122953D01*
G01X129725D02*
X127953D01*
G01X134725D02*
X132953D01*
G01X139725D02*
X137953D01*
G01X144725D02*
X142953D01*
G01X87362Y3507D02*
X86378D01*
G01X90512D02*
X89528D01*
G01X93662D02*
X92677D01*
G01X96811D02*
X95827D01*
G01X99961D02*
X98977D01*
G01X103110D02*
X102126D01*
G01X106260D02*
X105276D01*
G01X74607Y3058D02*
X73032D01*
G01X79607D02*
X78032D01*
G01X84607D02*
X83032D01*
G01X87362Y2953D02*
X86378D01*
G01X90512D02*
X89528D01*
G01X93662D02*
X92677D01*
G01X96811D02*
X95827D01*
G01X99961D02*
X98977D01*
G01X103110D02*
X102126D01*
G01X106260D02*
X105276D01*
G01X109725Y2559D02*
X107953D01*
G01X114725D02*
X112953D01*
G01X119725D02*
X117953D01*
G01X124725D02*
X122953D01*
G01X129725D02*
X127953D01*
G01X134725D02*
X132953D01*
G01X139725D02*
X137953D01*
G01X144725D02*
X142953D01*
G01X75738D02*
X75000D01*
G01X77638D02*
X76900D01*
G01X80738D02*
X80000D01*
G01X82638D02*
X81900D01*
G01X85738D02*
X85000D01*
G01X87362Y1914D02*
X86378D01*
G01X90512D02*
X89528D01*
G01X93662D02*
X92677D01*
G01X96811D02*
X95827D01*
G01X99961D02*
X98977D01*
G01X103110D02*
X102126D01*
G01X106260D02*
X105276D01*
G01X87362Y1402D02*
X86378D01*
G01X90512D02*
X89528D01*
G01X93662D02*
X92677D01*
G01X96811D02*
X95827D01*
G01X99961D02*
X98977D01*
G01X103110D02*
X102126D01*
G01X106260D02*
X105276D01*
G01X87362Y1220D02*
X86378D01*
G01X90512D02*
X89528D01*
G01X93662D02*
X92677D01*
G01X96811D02*
X95827D01*
G01X99961D02*
X98977D01*
G01X103110D02*
X102126D01*
G01X106260D02*
X105276D01*
G01Y891D02*
X106260D01*
G01X102126D02*
X103110D01*
G01X98977D02*
X99961D01*
G01X95827D02*
X96811D01*
G01X92677D02*
X93662D01*
G01X89528D02*
X90512D01*
G01X86378D02*
X87362D01*
G01X105276Y708D02*
X106260D01*
G01X102126D02*
X103110D01*
G01X98977D02*
X99961D01*
G01X95827D02*
X96811D01*
G01X92677D02*
X93662D01*
G01X89528D02*
X90512D01*
G01X86378D02*
X87362D01*
G01X110441Y276D02*
X109725D01*
G01X115441D02*
X114725D01*
G01X120441D02*
X119725D01*
G01X125441D02*
X124725D01*
G01X130441D02*
X129725D01*
G01X135441D02*
X134725D01*
G01X140441D02*
X139725D01*
G01X145441D02*
X144725D01*
G01X87362Y197D02*
X86378D01*
G01X90512D02*
X89528D01*
G01X93662D02*
X92677D01*
G01X96811D02*
X95827D01*
G01X99961D02*
X98977D01*
G01X103110D02*
X102126D01*
G01X106260D02*
X105276D01*
G01X86181Y-67D02*
X85788D01*
G01X87953D02*
X87559D01*
G01X89331D02*
X88937D01*
G01X91103D02*
X90709D01*
G01X92481D02*
X92087D01*
G01X94252D02*
X93858D01*
G01X95630D02*
X95236D01*
G01X97402D02*
X97008D01*
G01X98780D02*
X98386D01*
G01X101929D02*
X101536D01*
G01X100551D02*
X100158D01*
G01X103701D02*
X103307D01*
G01X105079D02*
X104685D01*
G01X106851D02*
X106457D01*
G01X106870Y-3544D02*
X85807D01*
G01X118788Y137176D02*
G03I-4291J0D01*
G01X94791Y116738D02*
X99325Y112205D01*
G01X137886Y116738D02*
X133353Y112205D01*
G01X94791Y116738D02*
G03X89224Y111170I-2784J-2784D01*
G01X143454D02*
G03X137886Y116738I-2784J2784D01*
G01X133353Y112205D02*
X99325D01*
G01X72441Y139088D02*
X76975Y134555D01*
G01X72441Y139088D02*
Y246293D01*
G01X134984Y104331D02*
G03X137768Y105484I0J3938D01*
G01X94910D02*
G03X97694Y104331I2784J2785D01*
G01X166957Y134673D02*
X137768Y105484D01*
G01X134984Y104331D02*
X97694D01*
G01X76176Y247538D02*
X72441Y246293D01*
G01X76175Y247538D02*
G03X84252Y258743I-3734J11205D01*
G01D02*
Y276690D01*
G01X76176Y287895D02*
X72441Y289140D01*
G01X84252Y276690D02*
G03X76175Y287895I-11811J0D01*
G01X72441Y289140D02*
Y321260D01*
G01X76378Y276690D02*
G03X73686Y280425I-3937J0D01*
G01Y255008D02*
G03X76378Y258743I-1245J3735D01*
G01D02*
Y276690D01*
G01X119874Y329366D02*
G03I-4291J0D01*
G01X72441Y346456D02*
Y350394D01*
G01X76378Y354331D02*
G03X72441Y350394I0J-3937D01*
G01X76378Y354331D02*
X156299D01*
G01X118788Y525759D02*
G03I-4291J0D01*
G01X94791Y505321D02*
G03X89224Y499753I-2784J-2784D01*
G01X143454D02*
G03X137886Y505321I-2784J2784D01*
G01D02*
X133353Y500787D01*
G01X94791Y505321D02*
X99325Y500787D01*
G01X72441Y527671D02*
X76975Y523137D01*
G01X133353Y500787D02*
X99325D01*
G01X134984Y492913D02*
G03X137768Y494066I0J3938D01*
G01X127362Y467323D02*
G03I-11023J0D01*
G01X94910Y494066D02*
G03X97694Y492913I2784J2785D01*
G01X166957Y523256D02*
X137768Y494066D01*
G01X134984Y492913D02*
X97694D01*
G01X72441Y527671D02*
Y634876D01*
G01X84252Y665272D02*
G03X76175Y676478I-11812J0D01*
G01Y636120D02*
G03X84252Y647326I-3735J11206D01*
G01X76176Y676477D02*
X72441Y677722D01*
G01X84252Y647326D02*
Y665272D01*
G01X72441Y677722D02*
Y709842D01*
G01X76176Y636121D02*
X72441Y634876D01*
G01X76378Y665272D02*
G03X73686Y669007I-3937J0D01*
G01Y643591D02*
G03X76378Y647326I-1245J3735D01*
G01D02*
Y665272D01*
G01X119874Y717948D02*
G03I-4291J0D01*
G01X76378Y742913D02*
G03X72441Y738976I0J-3937D01*
G01X76378Y742913D02*
X156299D01*
G01X72441Y735039D02*
Y738976D01*
G01X121130Y1006410D02*
Y989087D01*
G01X196194Y-7082D02*
X196229Y-7076D01*
G01X196158Y-7086D02*
X196194Y-7082D01*
G01X196122Y-7087D02*
X196158Y-7086D01*
G01X200768Y-5118D02*
G03X201240Y-5591I473J0D01*
G01X202421D02*
G03X202894Y-5118I0J473D01*
G01X200650D02*
G03X201240Y-5709I591J0D01*
G01X202421D02*
G03X203012Y-5118I0J591D01*
G01X212067Y-7284D02*
G03X212855Y-6496I0J788D01*
G01X208524Y-2559D02*
G03X210886I1181J0D01*
G01X209114Y-12599D02*
G03X210295Y-11418I0J1181D01*
G01X201634Y-24410D02*
G03X203603Y-26378I1968J0D01*
G01X183327Y-7087D02*
G03X182146Y-8268I0J-1181D01*
G01X204784Y-10433D02*
X205571Y-9646D01*
G01X182146Y-25197D02*
X180965Y-26378D01*
G01X212855Y2953D02*
Y-6496D01*
G01X210295Y-11418D02*
Y-7992D01*
G01X207382D02*
Y-10433D01*
G01X207146Y3740D02*
Y-7284D01*
G01X206595Y-7992D02*
Y-9646D01*
G01X206555Y6102D02*
Y-9646D01*
G01X205571Y6102D02*
Y-9646D01*
G01X204784Y6890D02*
Y-10433D01*
G01X203012Y5512D02*
Y-5118D01*
G01X202875D02*
Y-1575D01*
G01X202421Y-5709D02*
Y-5571D01*
G01X201634Y-788D02*
Y-24410D01*
G01X201240Y-5571D02*
Y-5709D01*
G01X200787Y-1575D02*
Y-5118D01*
G01X200650D02*
Y5512D01*
G01X200453Y-26378D02*
Y9842D01*
G01X197303Y-7087D02*
Y-24332D01*
G01X196122Y-26378D02*
Y-24332D01*
G01Y-7087D02*
Y-26378D01*
G01X181418Y-4725D02*
X181555Y-788D01*
G01X181024Y-4725D02*
X181162Y-788D01*
G01X189548Y-24332D02*
Y-9134D01*
G01X184508Y394D02*
Y-7087D01*
G01X182146Y-8268D02*
Y-25197D01*
G01X180965Y-4725D02*
Y-788D01*
G01X180571Y-4725D02*
Y-788D01*
G01X171339Y-4725D02*
X171477Y-788D01*
G01X171142Y-4725D02*
X171280Y-788D01*
G01X156477D02*
X156339Y-4725D01*
G01X176988Y-788D02*
Y-4725D01*
G01X176792Y-788D02*
Y-4725D01*
G01X170886D02*
Y-788D01*
G01X170689Y-4725D02*
Y-788D01*
G01X166792D02*
Y-4725D01*
G01X162776Y-16142D02*
Y-788D01*
G01X176535Y-4725D02*
X176398Y-788D01*
G01X176201D02*
X176338Y-4725D01*
G01X151339D02*
X151477Y-788D01*
G01X161792D02*
Y-4725D01*
G01X155886Y-788D02*
Y-4725D01*
G01X154902Y-788D02*
Y-16142D01*
G01X150886Y-4725D02*
Y-788D01*
G01X148898D02*
Y-4725D01*
G01X148307Y-788D02*
Y-4725D01*
G01X166201Y-788D02*
X166338Y-4725D01*
G01X161338D02*
X161201Y-788D01*
G01X193799Y394D02*
X197303Y-7087D01*
G01X192730Y394D02*
X196229Y-7076D01*
G01X197303Y-24332D02*
X198484Y-26378D01*
G01X207382Y-10433D02*
X206595Y-9646D01*
G01X187500Y-7087D02*
X189547Y-9134D01*
G01X189548D02*
X187500Y-7087D01*
G01X191595Y-26378D02*
X189548Y-24332D01*
G01X197299Y-7076D02*
X197191Y-7015D01*
G01X196956Y-6994D02*
X197192Y-7015D01*
G01X171339Y-4725D02*
X161338D01*
G01X181418D02*
X176338D01*
G01X202875Y-5118D02*
X203012D01*
G01X200787D02*
X200650D01*
G01X202421Y-5571D02*
X201240D01*
G01X202421Y-5709D02*
X201240D01*
G01X212067Y-7284D02*
X205571D01*
G01X210295Y-7992D02*
X205571D01*
G01X206555Y-8071D02*
X205571D01*
G01X206595Y-8386D02*
X205571D01*
G01X206555Y-8858D02*
X205571D01*
G01Y-9190D02*
X206555D01*
G01X205571Y-9207D02*
X206555D01*
G01Y-9449D02*
X205571D01*
G01X206555Y-9542D02*
X205571D01*
G01X206595Y-9646D02*
X205571D01*
G01X204784Y-10433D02*
X207382D01*
G01X210295Y-10630D02*
X200453D01*
G01X209114Y-12599D02*
X200453D01*
G01X154902Y-14764D02*
X162776D01*
G01X154902Y-16142D02*
X162776D01*
G01X196622Y-7015D02*
X196959Y-6994D01*
G01X197303Y-24332D02*
X189548D01*
G01X203603Y-26378D02*
X228740D01*
G01X200453D02*
X191595D01*
G01X196229Y-7076D02*
X196625Y-7015D01*
G01X196229Y-7076D02*
X196194Y-7082D01*
G01X202894Y5512D02*
G03X202421Y5984I-472J0D01*
G01X201240D02*
G03X200768Y5512I0J-472D01*
G01X201240Y6102D02*
G03X200650Y5512I0J-590D01*
G01X203012D02*
G03X202421Y6102I-590J0D01*
G01X212855Y2953D02*
G03X212067Y3740I-787J0D01*
G01X210886Y-984D02*
G03X208524I-1181J0D01*
G01X210295Y7874D02*
G03X209114Y9055I-1181J0D01*
G01X185689Y1772D02*
G03X186083Y1378I394J0D01*
G01Y7677D02*
G03X185689Y7283I0J-394D01*
G01X187461D02*
G03X187067Y7677I-394J0D01*
G01Y1378D02*
G03X187461Y1771I0J394D01*
G01X197894Y1338D02*
G03X198327Y1771I0J433D01*
G01X194311D02*
G03X194744Y1338I433J0D01*
G01Y7716D02*
G03X194311Y7283I0J-433D01*
G01X198327D02*
G03X197894Y7716I-433J0D01*
G01X186083Y7874D02*
G03X185492Y7283I0J-591D01*
G01X198484D02*
G03X197894Y7874I-591J0D01*
G01X194744D02*
G03X194154Y7283I0J-590D01*
G01Y1771D02*
G03X194744Y1181I590J0D01*
G01X197894D02*
G03X198484Y1771I0J590D01*
G01X187067Y1181D02*
G03X187658Y1771I0J591D01*
G01Y7283D02*
G03X187067Y7874I-591J0D01*
G01X185492Y1773D02*
G03X186083Y1181I591J-1D01*
G01X192500Y5118D02*
G03I-1575J0D01*
G01X193288D02*
G03I-2363J0D01*
G01X193603D02*
G03I-2658J0D01*
G01X193878D02*
G03I-2953J0D01*
G01X201634Y-788D02*
G03X199666Y1181I-1969J0D01*
G01X172236Y256D02*
G03X172032Y-98I1J-236D01*
G01X175645Y-99D02*
G03X175441Y256I-204J119D01*
G01X177236D02*
G03X177032Y-98I1J-236D01*
G01X180645Y-99D02*
G03X180441Y256I-204J119D01*
G01X150645Y-99D02*
G03X150441Y256I-204J119D01*
G01X152236D02*
G03X152032Y-98I1J-236D01*
G01X155645Y-99D02*
G03X155441Y256I-204J119D01*
G01X157236D02*
G03X157032Y-98I1J-236D01*
G01X160645Y-99D02*
G03X160441Y256I-204J119D01*
G01X162236D02*
G03X162032Y-98I1J-236D01*
G01X165645Y-99D02*
G03X165441Y256I-204J119D01*
G01X167236D02*
G03X167032Y-98I1J-236D01*
G01X170645Y-99D02*
G03X170441Y256I-204J119D01*
G01X207382Y6890D02*
X206595Y6102D01*
G01X180662Y-108D02*
X180270Y-788D01*
G01X175662Y-108D02*
X175270Y-788D01*
G01X170662Y-108D02*
X170270Y-788D01*
G01X165662Y-108D02*
X165270Y-788D01*
G01X160662Y-108D02*
X160270Y-788D01*
G01X155662Y-108D02*
X155270Y-788D01*
G01X150662Y-108D02*
X150270Y-788D01*
G01X210886Y-984D02*
Y-2559D01*
G01X210295Y7874D02*
Y4449D01*
G01X208524Y-984D02*
Y-2559D01*
G01X198091Y9842D02*
X197885Y3937D01*
G01X192973Y9842D02*
X192766Y3937D01*
G01X207382Y6890D02*
Y4449D01*
G01X206595Y6102D02*
Y4449D01*
G01X202957Y-1575D02*
Y394D01*
G01X202875D02*
Y5512D01*
G01X202421Y5965D02*
Y6102D01*
G01X201240Y5965D02*
Y6102D01*
G01X200787Y394D02*
Y5512D01*
G01X200705Y-1575D02*
Y394D01*
G01X198504Y9842D02*
Y-788D01*
G01X198484Y9842D02*
Y7283D01*
G01Y1771D02*
Y-788D01*
G01X198340Y1771D02*
Y7283D01*
G01X197894Y7729D02*
Y7874D01*
G01Y1325D02*
Y1181D01*
G01X197303Y9842D02*
Y3937D01*
G01X194744Y7729D02*
Y7874D01*
G01Y1325D02*
Y1181D01*
G01X194298Y1771D02*
Y7283D01*
G01X194154D02*
Y1771D01*
G01X193760Y9842D02*
Y3937D01*
G01X192382Y9842D02*
Y3937D01*
G01X189626D02*
Y9842D01*
G01X188248D02*
Y3937D01*
G01X187658Y1771D02*
Y7283D01*
G01X187472D02*
Y1771D01*
G01X187067Y1181D02*
Y1367D01*
G01Y9842D02*
Y3937D01*
G01X186083Y7688D02*
Y7874D01*
G01Y1181D02*
Y1367D01*
G01X185678Y1772D02*
Y7283D01*
G01X185492Y-788D02*
Y1773D01*
G01Y7283D02*
Y9842D01*
G01X183524D02*
Y-788D01*
G01X179725Y8472D02*
Y276D01*
G01X177953Y8472D02*
Y275D01*
G01X185478Y-788D02*
X185472Y9842D01*
G01X189036D02*
X189242Y3937D01*
G01X186280Y9842D02*
X186486Y3937D01*
G01X174725Y8472D02*
Y276D01*
G01X172953Y8472D02*
Y275D01*
G01X169725Y8472D02*
Y276D01*
G01X167953Y8472D02*
Y275D01*
G01X164725Y8472D02*
Y276D01*
G01X162953Y8472D02*
Y275D01*
G01X159725Y8472D02*
Y276D01*
G01X157953Y8472D02*
Y275D01*
G01X154725Y8472D02*
Y276D01*
G01X152953Y8472D02*
Y275D01*
G01X149725Y8472D02*
Y276D01*
G01X147953Y8472D02*
Y275D01*
G01X177408Y-788D02*
X177015Y-108D01*
G01X172408Y-788D02*
X172015Y-108D01*
G01X167408Y-788D02*
X167015Y-108D01*
G01X162408Y-788D02*
X162015Y-108D01*
G01X157408Y-788D02*
X157015Y-108D01*
G01X152408Y-788D02*
X152015Y-108D01*
G01X205571Y6102D02*
X204784Y6890D01*
G01X185492Y1772D02*
X185678Y1771D01*
G01X177953Y275D02*
X177236Y276D01*
G01X172953Y275D02*
X172236Y276D01*
G01X167953Y275D02*
X167236Y276D01*
G01X162953Y275D02*
X162236Y276D01*
G01X157953Y275D02*
X157236Y276D01*
G01X152953Y275D02*
X152236Y276D01*
G01X200453Y9842D02*
X183524D01*
G01X200453Y9055D02*
X209114D01*
G01X149725Y8472D02*
X147953D01*
G01X154725D02*
X152953D01*
G01X159725D02*
X157953D01*
G01X164725D02*
X162953D01*
G01X169725D02*
X167953D01*
G01X174725D02*
X172953D01*
G01X179725D02*
X177953D01*
G01X187067Y7874D02*
X186083D01*
G01X197894D02*
X194744D01*
G01Y7729D02*
X197894D01*
G01X187067Y7688D02*
X186083D01*
G01X198340Y7283D02*
X198484D01*
G01X185492D02*
X185678D01*
G01X187658D02*
X187472D01*
G01X194298D02*
X194154D01*
G01X210295Y7086D02*
X200453D01*
G01X204784Y6890D02*
X207382D01*
G01X201240Y6102D02*
X202421D01*
G01X206595D02*
X205571D01*
G01Y6000D02*
X206555D01*
G01X202421Y5965D02*
X201240D01*
G01X206555Y5905D02*
X205571D01*
G01X206555Y5663D02*
X205571D01*
G01Y5647D02*
X206555D01*
G01X149725Y5512D02*
X147953D01*
G01X154725D02*
X152953D01*
G01X159725D02*
X157953D01*
G01X164725D02*
X162953D01*
G01X169725D02*
X167953D01*
G01X174725D02*
X172953D01*
G01X179725D02*
X177953D01*
G01X202875D02*
X203012D01*
G01X200787D02*
X200650D01*
G01X206555Y5315D02*
X205571D01*
G01X206595Y4842D02*
X205571D01*
G01X149725Y4527D02*
X147953D01*
G01X154725D02*
X152953D01*
G01X159725D02*
X157953D01*
G01X164725D02*
X162953D01*
G01X169725D02*
X167953D01*
G01X174725D02*
X172953D01*
G01X179725D02*
X177953D01*
G01X206555D02*
X205571D01*
G01X210295Y4449D02*
X205571D01*
G01X186486Y3937D02*
X197885D01*
G01X212067Y3740D02*
X205571D01*
G01X149725Y3543D02*
X147953D01*
G01X154725D02*
X152953D01*
G01X159725D02*
X157953D01*
G01X164725D02*
X162953D01*
G01X169725D02*
X167953D01*
G01X174725D02*
X172953D01*
G01X179725D02*
X177953D01*
G01X149725Y2559D02*
X147953D01*
G01X154725D02*
X152953D01*
G01X159725D02*
X157953D01*
G01X164725D02*
X162953D01*
G01X169725D02*
X167953D01*
G01X174725D02*
X172953D01*
G01X179725D02*
X177953D01*
G01X187472Y1771D02*
X187658D01*
G01X194298D02*
X194154D01*
G01X198484D02*
X198340D01*
G01X187067Y1367D02*
X186083D01*
G01X197894Y1325D02*
X194744D01*
G01X193799Y394D02*
X184508D01*
G01X202957D02*
X200705D01*
G01X150441Y276D02*
X149725D01*
G01X155441D02*
X154725D01*
G01X160441D02*
X159725D01*
G01X165441D02*
X164725D01*
G01X170441D02*
X169725D01*
G01X175441D02*
X174725D01*
G01X180441D02*
X179725D01*
G01X202957Y-1575D02*
X200705D01*
G01X155703Y134555D02*
G03X161271Y128987I2784J-2784D01*
G01X160236Y246293D02*
Y139088D01*
G01D02*
X155703Y134555D01*
G01X201453Y129175D02*
X201477Y129331D01*
G01X201385Y129043D02*
X201453Y129175D01*
G01X201272Y128931D02*
X201385Y129043D01*
G01X201138Y128861D02*
X201272Y128931D01*
G01X200984Y128838D02*
X201138Y128861D01*
G01X184524Y129175D02*
X184547Y129331D01*
G01X184456Y129043D02*
X184524Y129175D01*
G01X184342Y128931D02*
X184456Y129043D01*
G01X184209Y128861D02*
X184342Y128931D01*
G01X184055Y128838D02*
X184209Y128861D01*
G01X201453Y146104D02*
X201477Y146260D01*
G01X201385Y145972D02*
X201453Y146104D01*
G01X201272Y145860D02*
X201385Y145972D01*
G01X201138Y145790D02*
X201272Y145860D01*
G01X200984Y145768D02*
X201138Y145790D01*
G01X183926Y128855D02*
X183864Y128875D01*
G01X183990Y128843D02*
X183926Y128855D01*
G01X184055Y128838D02*
X183990Y128843D01*
G01X200856Y128855D02*
X200793Y128875D01*
G01X200919Y128843D02*
X200856Y128855D01*
G01X200984Y128838D02*
X200919Y128843D01*
G01X184524Y146104D02*
X184547Y146260D01*
G01X184456Y145972D02*
X184524Y146104D01*
G01X184342Y145860D02*
X184456Y145972D01*
G01X184209Y145790D02*
X184342Y145860D01*
G01X184055Y145768D02*
X184209Y145790D01*
G01X183926Y145784D02*
X183864Y145804D01*
G01X183990Y145772D02*
X183926Y145784D01*
G01X184055Y145768D02*
X183990Y145772D01*
G01X200856Y145784D02*
X200793Y145804D01*
G01X200919Y145772D02*
X200856Y145784D01*
G01X200984Y145768D02*
X200919Y145772D01*
G01X183571Y129238D02*
X183563Y129331D01*
G01X183594Y129157D02*
X183571Y129238D01*
G01X183626Y129090D02*
X183594Y129157D01*
G01X183664Y129033D02*
X183626Y129090D01*
G01X183705Y128985D02*
X183664Y129033D01*
G01X183746Y128947D02*
X183705Y128985D01*
G01X183788Y128916D02*
X183746Y128947D01*
G01X183831Y128891D02*
X183788Y128916D01*
G01X183864Y128875D02*
X183831Y128891D01*
G01X200500Y129238D02*
X200492Y129331D01*
G01X200523Y129157D02*
X200500Y129238D01*
G01X200555Y129090D02*
X200523Y129157D01*
G01X200593Y129033D02*
X200555Y129090D01*
G01X200634Y128985D02*
X200593Y129033D01*
G01X200675Y128947D02*
X200634Y128985D01*
G01X200717Y128916D02*
X200675Y128947D01*
G01X200760Y128891D02*
X200717Y128916D01*
G01X200793Y128875D02*
X200760Y128891D01*
G01X183571Y146167D02*
X183563Y146260D01*
G01X183594Y146087D02*
X183571Y146167D01*
G01X183626Y146019D02*
X183594Y146087D01*
G01X183664Y145962D02*
X183626Y146019D01*
G01X183705Y145914D02*
X183664Y145962D01*
G01X183746Y145876D02*
X183705Y145914D01*
G01X183788Y145846D02*
X183746Y145876D01*
G01X183831Y145820D02*
X183788Y145846D01*
G01X183864Y145804D02*
X183831Y145820D01*
G01X200500Y146167D02*
X200492Y146260D01*
G01X200523Y146087D02*
X200500Y146167D01*
G01X200555Y146019D02*
X200523Y146087D01*
G01X200593Y145962D02*
X200555Y146019D01*
G01X200634Y145914D02*
X200593Y145962D01*
G01X200675Y145876D02*
X200634Y145914D01*
G01X200717Y145846D02*
X200675Y145876D01*
G01X200760Y145820D02*
X200717Y145846D01*
G01X200793Y145804D02*
X200760Y145820D01*
G01X184086Y145768D02*
X184055D01*
G01X184113Y145770D02*
X184086Y145768D01*
G01X184140Y145774D02*
X184113Y145770D01*
G01X184164Y145779D02*
X184140Y145774D01*
G01X184187Y145784D02*
X184164Y145779D01*
G01X184207Y145790D02*
X184187Y145784D01*
G01X184228Y145797D02*
X184207Y145790D01*
G01X184242Y145803D02*
X184228Y145797D01*
G01X201015Y145768D02*
X200984D01*
G01X201043Y145770D02*
X201015Y145768D01*
G01X201069Y145774D02*
X201043Y145770D01*
G01X201093Y145779D02*
X201069Y145774D01*
G01X201116Y145784D02*
X201093Y145779D01*
G01X201137Y145790D02*
X201116Y145784D01*
G01X201157Y145797D02*
X201137Y145790D01*
G01X201171Y145803D02*
X201157Y145797D01*
G01X184086Y128839D02*
X184055Y128838D01*
G01X184113Y128841D02*
X184086Y128839D01*
G01X184140Y128845D02*
X184113Y128841D01*
G01X184164Y128850D02*
X184140Y128845D01*
G01X184187Y128855D02*
X184164Y128850D01*
G01X184207Y128861D02*
X184187Y128855D01*
G01X184228Y128868D02*
X184207Y128861D01*
G01X184242Y128874D02*
X184228Y128868D01*
G01X184531Y146131D02*
X184511Y146069D01*
G01X184543Y146195D02*
X184531Y146131D01*
G01X184547Y146260D02*
X184543Y146195D01*
G01X184531Y129202D02*
X184511Y129139D01*
G01X184543Y129266D02*
X184531Y129202D01*
G01X184547Y129331D02*
X184543Y129266D01*
G01X184299Y145832D02*
X184242Y145803D01*
G01X184349Y145865D02*
X184299Y145832D01*
G01X184392Y145901D02*
X184349Y145865D01*
G01X184427Y145937D02*
X184392Y145901D01*
G01X184454Y145970D02*
X184427Y145937D01*
G01X184482Y146013D02*
X184454Y145970D01*
G01X184499Y146044D02*
X184482Y146013D01*
G01X184511Y146069D02*
X184499Y146044D01*
G01X201015Y128839D02*
X200984Y128838D01*
G01X201043Y128841D02*
X201015Y128839D01*
G01X201069Y128845D02*
X201043Y128841D01*
G01X201093Y128850D02*
X201069Y128845D01*
G01X201116Y128855D02*
X201093Y128850D01*
G01X201137Y128861D02*
X201116Y128855D01*
G01X201157Y128868D02*
X201137Y128861D01*
G01X201171Y128874D02*
X201157Y128868D01*
G01X183900Y128862D02*
X184055Y128838D01*
G01X183765Y128932D02*
X183900Y128862D01*
G01X183654Y129046D02*
X183765Y128932D01*
G01X183584Y129186D02*
X183654Y129046D01*
G01X183563Y129331D02*
X183584Y129186D01*
G01X183900Y145791D02*
X184055Y145768D01*
G01X183765Y145861D02*
X183900Y145791D01*
G01X183654Y145975D02*
X183765Y145861D01*
G01X183584Y146115D02*
X183654Y145975D01*
G01X183563Y146260D02*
X183584Y146115D01*
G01X201460Y146131D02*
X201440Y146069D01*
G01X201472Y146195D02*
X201460Y146131D01*
G01X201477Y146260D02*
X201472Y146195D01*
G01X201460Y129202D02*
X201440Y129139D01*
G01X201472Y129266D02*
X201460Y129202D01*
G01X201477Y129331D02*
X201472Y129266D01*
G01X184299Y128903D02*
X184242Y128874D01*
G01X184349Y128936D02*
X184299Y128903D01*
G01X184392Y128972D02*
X184349Y128936D01*
G01X184427Y129008D02*
X184392Y128972D01*
G01X184454Y129040D02*
X184427Y129008D01*
G01X184482Y129083D02*
X184454Y129040D01*
G01X184499Y129115D02*
X184482Y129083D01*
G01X184511Y129139D02*
X184499Y129115D01*
G01X201229Y145832D02*
X201171Y145803D01*
G01X201278Y145865D02*
X201229Y145832D01*
G01X201321Y145901D02*
X201278Y145865D01*
G01X201356Y145937D02*
X201321Y145901D01*
G01X201383Y145970D02*
X201356Y145937D01*
G01X201411Y146013D02*
X201383Y145970D01*
G01X201428Y146044D02*
X201411Y146013D01*
G01X201440Y146069D02*
X201428Y146044D01*
G01X200829Y128862D02*
X200984Y128838D01*
G01X200694Y128932D02*
X200829Y128862D01*
G01X200583Y129046D02*
X200694Y128932D01*
G01X200513Y129186D02*
X200583Y129046D01*
G01X200492Y129331D02*
X200513Y129186D01*
G01X200829Y145791D02*
X200984Y145768D01*
G01X200694Y145861D02*
X200829Y145791D01*
G01X200583Y145975D02*
X200694Y145861D01*
G01X200513Y146115D02*
X200583Y145975D01*
G01X200492Y146260D02*
X200513Y146115D01*
G01X201229Y128903D02*
X201171Y128874D01*
G01X201278Y128936D02*
X201229Y128903D01*
G01X201321Y128972D02*
X201278Y128936D01*
G01X201356Y129008D02*
X201321Y128972D01*
G01X201383Y129040D02*
X201356Y129008D01*
G01X201411Y129083D02*
X201383Y129040D01*
G01X201428Y129115D02*
X201411Y129083D01*
G01X201440Y129139D02*
X201428Y129115D01*
G01X201457Y146260D02*
G03X200512I-473J0D01*
G01X202658D02*
G03I-1674J0D01*
G01X202756D02*
G03I-1772J0D01*
G01X198427Y137795D02*
G03I-5907J0D01*
G01X199410D02*
G03I-6890J0D01*
G01X199712D02*
G03I-7192J0D01*
G01X199803D02*
G03I-7283J0D01*
G01X197185Y128950D02*
G03X201365Y133130I-4665J8845D01*
G01Y142460D02*
G03X197185Y146640I-8845J-4665D01*
G01X187854D02*
G03X183675Y142460I4667J-8844D01*
G01Y133130D02*
G03X187854Y128950I8846J4664D01*
G01X202756Y137795D02*
G03I-10236J0D01*
G01X201457Y129331D02*
G03X200512I-473J0D01*
G01X203150Y125590D02*
G03X204725Y127165I0J1575D01*
G01X202658Y129331D02*
G03I-1674J0D01*
G01X202756D02*
G03I-1772J0D01*
G01X184528Y146260D02*
G03X183583I-472J0D01*
G01X185729D02*
G03I-1674J0D01*
G01X185827D02*
G03I-1772J0D01*
G01X184528Y129331D02*
G03X183583I-472J0D01*
G01X180315Y127165D02*
G03X181890Y125590I1575J0D01*
G01X185729Y129331D02*
G03I-1674J0D01*
G01X185827D02*
G03I-1772J0D01*
G01X166957Y134673D02*
G03X168110Y137457I-2785J2784D01*
G01X211710Y146762D02*
X211742Y146829D01*
G01X211119Y146796D02*
X211103Y146745D01*
G01X211004Y146762D02*
X211021Y146813D01*
G01X211841Y146829D02*
X211824Y146762D01*
G01X211267Y146863D02*
X211283Y146930D01*
G01X211841Y146343D02*
Y146260D01*
G01Y146863D02*
Y146829D01*
G01X211742D02*
Y146863D01*
G01X211250Y146260D02*
Y146343D01*
G01X211119Y146863D02*
Y146796D01*
G01X211021Y146813D02*
Y146863D01*
G01X210610Y146963D02*
Y146712D01*
G01Y146611D02*
Y146260D01*
G01X210512D02*
Y147047D01*
G01X210236Y130315D02*
Y127559D01*
G01Y148031D02*
Y145275D01*
G01X211824Y146930D02*
X211841Y146863D01*
G01X211103Y146913D02*
X211119Y146863D01*
G01X211021D02*
X211004Y146913D01*
G01X211250Y146343D02*
X211710Y146762D01*
G01X211283Y146930D02*
X211349Y146997D01*
G01X210971Y146729D02*
X211004Y146762D01*
G01X211103Y146745D02*
X211053Y146678D01*
G01X211824Y146762D02*
X211792Y146712D01*
G01X211381Y146913D02*
X211349Y146863D01*
G01X186773Y126771D02*
X186614Y126181D01*
G01X207339Y130315D02*
Y127559D01*
G01Y148031D02*
Y145275D01*
G01X206567D02*
Y148031D01*
G01Y127559D02*
Y130315D01*
G01X206222Y145275D02*
Y148031D01*
G01Y127559D02*
Y130315D01*
G01X205408Y145275D02*
Y148031D01*
G01Y127559D02*
Y130315D01*
G01X205064Y145275D02*
Y148031D01*
G01Y127559D02*
Y130315D01*
G01X204725Y148425D02*
Y127165D01*
G01X204292Y130315D02*
Y127559D01*
G01Y148031D02*
Y145275D01*
G01X204134Y131890D02*
Y126181D01*
G01Y149409D02*
Y143701D01*
G01X203544Y143542D02*
Y132048D01*
G01X203150Y133130D02*
Y142461D01*
G01X197185Y146640D02*
Y148425D01*
G01Y127165D02*
Y128950D01*
G01X198425Y126181D02*
X198267Y126771D01*
G01X211742Y146863D02*
X211710Y146913D01*
G01X211053Y146980D02*
X211103Y146913D01*
G01X211431Y146947D02*
X211381Y146913D01*
G01X211053Y146678D02*
X210988Y146628D01*
G01X211792Y146712D02*
X211381Y146343D01*
G01X187854Y128950D02*
Y127165D01*
G01Y148425D02*
Y146640D01*
G01X181890Y142461D02*
Y133130D01*
G01X181496Y143542D02*
Y132048D01*
G01X180906Y131890D02*
Y126181D01*
G01Y149409D02*
Y143701D01*
G01X180557Y145275D02*
Y148031D01*
G01Y127559D02*
Y130315D01*
G01X180315Y127165D02*
Y148425D01*
G01X179810Y130315D02*
Y127559D01*
G01Y148031D02*
Y145275D01*
G01X179135Y130315D02*
Y127559D01*
G01Y148031D02*
Y145275D01*
G01X178688Y130315D02*
Y127559D01*
G01Y148031D02*
Y145275D01*
G01X178013Y130315D02*
Y127559D01*
G01Y148031D02*
Y145275D01*
G01X174095Y146756D02*
X174111Y146705D01*
G01X174013D02*
X173996Y146756D01*
G01X211759Y146997D02*
X211824Y146930D01*
G01X211004Y146913D02*
X210971Y146947D01*
G01X211349Y146997D02*
X211414Y147030D01*
G01X174045Y146521D02*
X173980Y146471D01*
G01X173963Y146571D02*
X173996Y146605D01*
G01X174341Y146756D02*
X174242Y146638D01*
G01Y146772D02*
X174341Y146890D01*
G01X174095Y146588D02*
X174045Y146521D01*
G01X174111Y146638D02*
X174095Y146588D01*
G01X173996Y146605D02*
X174013Y146655D01*
G01X177266Y145275D02*
Y148031D01*
G01Y127559D02*
Y130315D01*
G01X174803Y145275D02*
Y148031D01*
G01Y130315D02*
Y127559D01*
G01X174439Y146890D02*
Y146102D01*
G01X174341D02*
Y146756D01*
G01X174242Y146638D02*
Y146772D01*
G01X174111Y146705D02*
Y146638D01*
G01X174013Y146655D02*
Y146705D01*
G01X173603Y146806D02*
Y146555D01*
G01Y146454D02*
Y146102D01*
G01X173504D02*
Y146890D01*
G01X168110Y249131D02*
Y137457D01*
G01X174045Y146823D02*
X174095Y146756D01*
G01X210988Y147030D02*
X211053Y146980D01*
G01X211710Y146913D02*
X211660Y146947D01*
G01X210922Y146712D02*
X210971Y146729D01*
G01X173914Y146555D02*
X173963Y146571D01*
G01X173996Y146756D02*
X173963Y146789D01*
G01X173980Y146873D02*
X174045Y146823D01*
G01X211693Y147030D02*
X211759Y146997D01*
G01X210971Y146947D02*
X210922Y146963D01*
G01X173963Y146789D02*
X173914Y146806D01*
G01X211660Y146947D02*
X211578Y146963D01*
G01X210906Y147047D02*
X210988Y147030D01*
G01X181496Y143542D02*
X180906Y143701D01*
G01X203544Y132048D02*
X204134Y131890D01*
G01X173898Y146890D02*
X173980Y146873D01*
G01X211595Y147047D02*
X211693Y147030D01*
G01X211529Y147047D02*
X211595D01*
G01X210512D02*
X210906D01*
G01X210922Y146963D02*
X210610D01*
G01X211578D02*
X211513D01*
G01X174341Y146890D02*
X174439D01*
G01X173504D02*
X173898D01*
G01X211349Y146863D02*
X211267D01*
G01X173914Y146806D02*
X173603D01*
G01X210610Y146712D02*
X210922D01*
G01X210906Y146611D02*
X210610D01*
G01X173603Y146555D02*
X173914D01*
G01X173898Y146454D02*
X173603D01*
G01X211381Y146343D02*
X211841D01*
G01X210610Y146260D02*
X210512D01*
G01X211841D02*
X211250D01*
G01X174439Y146102D02*
X174341D01*
G01X173603D02*
X173504D01*
G01X210236Y145275D02*
X174803D01*
G01X183675Y142461D02*
X181890D01*
G01X203150D02*
X201365D01*
G01Y133130D02*
X203150D01*
G01X181890D02*
X183675D01*
G01X210236Y130315D02*
X174803D01*
G01X210236Y127559D02*
X174803D01*
G01X187854Y127165D02*
X197185D01*
G01X198267Y126771D02*
X186773D01*
G01X186614Y126181D02*
X180906D01*
G01X204134D02*
X198425D01*
G01X203150Y125590D02*
X181890D01*
G01X211414Y147030D02*
X211529Y147047D01*
G01X173980Y146471D02*
X173898Y146454D01*
G01X211513Y146963D02*
X211431Y146947D01*
G01X210988Y146628D02*
X210906Y146611D01*
G01X204134Y143701D02*
X203544Y143542D01*
G01X180906Y131890D02*
X181496Y132048D01*
G01X189848Y212147D02*
X189871Y212039D01*
G01X189822Y212201D02*
X189848Y212147D01*
G01X189796Y212192D02*
X189822Y212201D01*
G01X193885Y174165D02*
X193583Y174212D01*
G01X194159Y174026D02*
X193885Y174165D01*
G01X194378Y173808D02*
X194159Y174026D01*
G01X194519Y173534D02*
X194378Y173808D01*
G01X194567Y173229D02*
X194519Y173534D01*
G01Y172925D02*
X194567Y173229D01*
G01X194380Y172650D02*
X194519Y172925D01*
G01X194162Y172432D02*
X194380Y172650D01*
G01X193887Y172292D02*
X194162Y172432D01*
G01X193583Y172244D02*
X193887Y172292D01*
G01X181308Y221168D02*
X181367Y221180D01*
G01X181272Y221155D02*
X181308Y221168D01*
G01X181260Y221142D02*
X181272Y221155D01*
G01X194340Y173858D02*
X194488Y173614D01*
G01X194126Y174049D02*
X194340Y173858D01*
G01X193866Y174171D02*
X194126Y174049D01*
G01X193583Y174212D02*
X193866Y174171D01*
G01X201506Y221455D02*
X201614Y221450D01*
G01X201436Y221463D02*
X201506Y221455D01*
G01X201418Y221473D02*
X201436Y221463D01*
G01X201453Y221481D02*
X201418Y221473D01*
G01X182445Y221146D02*
X182441Y221142D01*
G01X182457Y221151D02*
X182445Y221146D01*
G01X182477Y221155D02*
X182457Y221151D01*
G01X191933Y221475D02*
X191955Y221653D01*
G01X191868Y221312D02*
X191933Y221475D01*
G01X191765Y221180D02*
X191868Y221312D01*
G01X191633Y221093D02*
X191765Y221180D01*
G01X191484Y221063D02*
X191633Y221093D01*
G01X192389Y223403D02*
X192368Y223228D01*
G01X192454Y223568D02*
X192389Y223403D01*
G01X192558Y223702D02*
X192454Y223568D01*
G01X191922Y221064D02*
X191898Y221063D01*
G01X191947Y221066D02*
X191922Y221064D01*
G01X191972Y221070D02*
X191947Y221066D01*
G01X203773Y221799D02*
X203780Y221801D01*
G01X203765Y221797D02*
X203773Y221799D01*
G01X203758Y221796D02*
X203765Y221797D01*
G01X194974Y210984D02*
X195028Y211120D01*
G01X194855Y210860D02*
X194974Y210984D01*
G01X194682Y210764D02*
X194855Y210860D01*
G01X194470Y210702D02*
X194682Y210764D01*
G01X194242Y210682D02*
X194470Y210702D01*
G01X194385Y211635D02*
X194155Y211614D01*
G01X194596Y211696D02*
X194385Y211635D01*
G01X194767Y211792D02*
X194596Y211696D01*
G01X194886Y211914D02*
X194767Y211792D01*
G01X194942Y212052D02*
X194886Y211914D01*
G01X183018Y221432D02*
X183309Y221446D01*
G01X182780Y221414D02*
X183018Y221432D01*
G01X182617Y221394D02*
X182780Y221414D01*
G01X183621Y221473D02*
X183587Y221481D01*
G01X183604Y221464D02*
X183621Y221473D01*
G01X183534Y221455D02*
X183604Y221464D01*
G01X183425Y221450D02*
X183534Y221455D01*
G01X183768Y221374D02*
X183727Y221369D01*
G01X183827Y221378D02*
X183768Y221374D01*
G01X183900Y221382D02*
X183827Y221378D01*
G01X202260Y221414D02*
X202423Y221394D01*
G01X202022Y221432D02*
X202260Y221414D01*
G01X201730Y221446D02*
X202022Y221432D01*
G01X200251Y221484D02*
X200379Y221512D01*
G01X200257Y221455D02*
X200251Y221484D01*
G01X200399Y221428D02*
X200257Y221455D01*
G01X200665Y221404D02*
X200399Y221428D01*
G01X201024Y221386D02*
X200665Y221404D01*
G01X190154Y211914D02*
X190098Y212052D01*
G01X190272Y211792D02*
X190154Y211914D01*
G01X190444Y211696D02*
X190272Y211792D01*
G01X190654Y211635D02*
X190444Y211696D01*
G01X190884Y211614D02*
X190654Y211635D01*
G01X192041Y223569D02*
X192145Y223702D01*
G01X191976Y223404D02*
X192041Y223569D01*
G01X191955Y223228D02*
X191976Y223404D01*
G01X192130Y221140D02*
X191972Y221070D01*
G01X192258Y221275D02*
X192130Y221140D01*
G01X192340Y221455D02*
X192258Y221275D01*
G01X192368Y221653D02*
X192340Y221455D01*
G01X195218Y212201D02*
X195244Y212192D01*
G01X195192Y212148D02*
X195218Y212201D01*
G01X195169Y212039D02*
X195192Y212148D01*
G01X194558Y173361D02*
X194488Y173614D01*
G01X194558Y173097D02*
Y173361D01*
G01X194488Y172842D02*
X194558Y173097D01*
G01X193865Y172285D02*
X193583Y172244D01*
G01X194125Y172407D02*
X193865Y172285D01*
G01X194339Y172598D02*
X194125Y172407D01*
G01X194488Y172842D02*
X194339Y172598D01*
G01X201213Y221378D02*
X201140Y221382D01*
G01X201272Y221374D02*
X201213Y221378D01*
G01X201313Y221369D02*
X201272Y221374D01*
G01X203768Y221155D02*
X203780Y221142D01*
G01X203732Y221168D02*
X203768Y221155D01*
G01X203673Y221180D02*
X203732Y221168D01*
G01X184374Y221404D02*
X184016Y221386D01*
G01X184640Y221427D02*
X184374Y221404D01*
G01X184783Y221455D02*
X184640Y221427D01*
G01X184789Y221484D02*
X184783Y221455D01*
G01X184661Y221512D02*
X184789Y221484D01*
G01X181274Y221797D02*
X181282Y221796D01*
G01X181267Y221799D02*
X181274Y221797D01*
G01X181260Y221801D02*
X181267Y221799D01*
G01X195139Y213243D02*
X195083Y212971D01*
G01X195204Y213376D02*
X195139Y213243D01*
G01X195269Y213353D02*
X195204Y213376D01*
G01X202779Y221874D02*
X202684Y221827D01*
G01X202866Y221991D02*
X202779Y221874D01*
G01X202934Y222165D02*
X202866Y221991D01*
G01X202978Y222381D02*
X202934Y222165D01*
G01X202992Y222613D02*
X202978Y222381D01*
G01X182062D02*
X182047Y222613D01*
G01X182105Y222166D02*
X182062Y222381D01*
G01X182174Y221991D02*
X182105Y222166D01*
G01X182261Y221875D02*
X182174Y221991D01*
G01X182356Y221827D02*
X182261Y221875D01*
G01X190568Y210703D02*
X190798Y210682D01*
G01X190358Y210764D02*
X190568Y210703D01*
G01X190186Y210860D02*
X190358Y210764D01*
G01X190067Y210982D02*
X190186Y210860D01*
G01X190012Y211120D02*
X190067Y210982D01*
G01X189836Y213376D02*
X189770Y213353D01*
G01X189901Y213243D02*
X189836Y213376D01*
G01X189957Y212971D02*
X189901Y213243D01*
G01X202583Y221151D02*
X202563Y221155D01*
G01X202595Y221146D02*
X202583Y221151D01*
G01X202599Y221142D02*
X202595Y221146D01*
G01X200551Y212992D02*
G03X201339Y213779I0J788D01*
G01Y211614D02*
G03X202599Y212874I0J1260D01*
G01X200551Y211811D02*
G03X202520Y213779I0J1969D01*
G01X205118Y214173D02*
G03X207087Y216142I0J1969D01*
G01X201339Y210433D02*
G03X203780Y212874I0J2441D01*
G01X197244Y214370D02*
G03X199764Y216890I0J2520D01*
G01X198032Y207086D02*
G03X200000Y209055I0J1968D01*
G01X194567Y173228D02*
G03I-984J0D01*
G01X183701Y213779D02*
G03X184488Y212992I787J0D01*
G01X182441Y212874D02*
G03X183701Y211614I1260J0D01*
G01X182520Y213779D02*
G03X184488Y211811I1968J0D01*
G01X177953Y216142D02*
G03X179921Y214173I1969J0D01*
G01X185040Y209055D02*
G03X187008Y207086I1969J0D01*
G01X181260Y212874D02*
G03X183701Y210433I2441J0D01*
G01X184567Y173228D02*
G03I-984J0D01*
G01X194488D02*
G03I-5905J0D01*
G01X196457D02*
G03I-7874J0D01*
G01X204725Y148425D02*
G03X203150Y150000I-1575J0D01*
G01X181890D02*
G03X180315Y148425I0J-1575D01*
G01X196403Y211614D02*
X195269Y213353D01*
G01X195244Y212192D02*
X196390Y210433D01*
G01X193307Y222953D02*
X192520Y224055D01*
G01X199246Y215360D02*
X198268Y216338D01*
G01X190098Y212052D02*
X189957Y212971D01*
G01X189871Y212039D02*
X190012Y211120D01*
G01X192647Y172923D02*
X192599Y173229D01*
G01X202156Y173643D02*
X202180Y173542D01*
G01X198366Y173618D02*
X198391Y173542D01*
G01X198243D02*
X198219Y173618D01*
G01X202820Y173341D02*
X203263Y172638D01*
G01X203066D02*
X202697Y173216D01*
G01X202033Y173542D02*
X201983Y173618D01*
G01X198267Y148819D02*
X198425Y149409D01*
G01X202180Y173492D02*
X202156Y173391D01*
G01X201319Y173542D02*
X201344Y173643D01*
G01X207087Y256299D02*
Y216142D01*
G01X205276Y211614D02*
Y210433D01*
G01X205237D02*
Y211614D01*
G01X205209D02*
Y210433D01*
G01X204567Y258268D02*
Y214173D01*
G01X203876Y210433D02*
Y211614D01*
G01X203780Y212874D02*
Y259567D01*
G01Y211614D02*
Y210433D01*
G01X203701Y211811D02*
Y216142D01*
G01X203673Y221180D02*
Y227639D01*
G01X203657Y222441D02*
Y226378D01*
G01X203477Y210433D02*
Y211614D01*
G01X202992Y222602D02*
Y226206D01*
G01Y210433D02*
Y211614D01*
G01X202599Y212874D02*
Y259567D01*
G01X202563Y221155D02*
Y227664D01*
G01X202525Y173819D02*
Y173241D01*
G01Y173040D02*
Y172638D01*
G01X202520Y213779D02*
Y258661D01*
G01X202423Y227424D02*
Y221394D01*
G01X202377Y172638D02*
Y173819D01*
G01X202180Y172763D02*
Y172638D01*
G01Y173542D02*
Y173492D01*
G01X202033D02*
Y173542D01*
G01X201969Y211614D02*
Y210433D01*
G01X201761Y226378D02*
Y222441D01*
G01X201730Y221446D02*
Y227373D01*
G01X201614Y221450D02*
Y227369D01*
G01X201575Y211614D02*
Y210433D01*
G01X201453Y227337D02*
Y221481D01*
G01X201418Y210433D02*
Y211616D01*
G01Y227347D02*
Y221471D01*
G01X201339Y258661D02*
Y213779D01*
G01X201313Y227450D02*
Y221369D01*
G01X201295Y172638D02*
Y172763D01*
G01X201140Y221382D02*
Y227437D01*
G01X201024Y221386D02*
Y227433D01*
G01X200788Y210433D02*
Y211614D01*
G01X200630D02*
Y210433D01*
G01Y226378D02*
Y222441D01*
G01X200551Y211811D02*
Y212992D01*
G01X200394Y216338D02*
Y216142D01*
G01Y226771D02*
Y222047D01*
G01X200379Y227307D02*
Y221512D01*
G01X200236Y227348D02*
Y221471D01*
G01X200000Y211614D02*
Y209055D01*
G01X199917Y173819D02*
Y172638D01*
G01X199769Y172814D02*
Y173819D01*
G01X199764Y255551D02*
Y216890D01*
G01X199632Y221653D02*
Y219291D01*
G01X199212Y211614D02*
Y210433D01*
G01X199080Y173668D02*
Y172638D01*
G01X199016Y222244D02*
Y218701D01*
G01X198932Y172638D02*
Y173819D01*
G01X198819Y222047D02*
Y218897D01*
G01X198818Y210433D02*
Y211614D01*
G01X198735Y173819D02*
Y172638D01*
G01X198588D02*
Y173819D01*
G01X198555Y218897D02*
Y222047D01*
G01X198515Y218897D02*
Y222047D01*
G01X198425Y211614D02*
Y210433D01*
G01X198418Y211614D02*
Y210433D01*
G01X198391Y173542D02*
Y173442D01*
G01X198386Y217421D02*
Y223523D01*
G01X198288D02*
Y217421D01*
G01X198268Y256102D02*
Y216338D01*
G01X198243Y173467D02*
Y173542D01*
G01X198180Y218012D02*
Y222933D01*
G01X198032Y222047D02*
Y218897D01*
G01X197873D02*
Y222047D01*
G01X197835Y222244D02*
Y218701D01*
G01X197764Y218897D02*
Y222047D01*
G01X197628Y173693D02*
Y173316D01*
G01Y173165D02*
Y172638D01*
G01X197500Y217421D02*
Y223523D01*
G01X197481Y172638D02*
Y173819D01*
G01X197447Y218012D02*
Y222933D01*
G01X197402Y217992D02*
Y217421D01*
G01Y223523D02*
Y222953D01*
G01X197311Y211614D02*
Y210433D01*
G01X197008Y211614D02*
Y210433D01*
G01X196912Y211614D02*
Y210433D01*
G01X196851Y219291D02*
Y217992D01*
G01Y222953D02*
Y221653D01*
G01X196654Y218701D02*
Y222244D01*
G01X196540Y210433D02*
Y211614D01*
G01X196464Y210433D02*
Y211614D01*
G01X196221Y210433D02*
Y211614D01*
G01X195758D02*
Y210433D01*
G01X195579D02*
Y211614D01*
G01X195551D02*
Y210433D01*
G01X195512Y211614D02*
Y210433D01*
G01X195448Y218012D02*
Y222933D01*
G01X195394D02*
Y218012D01*
G01X194981Y224606D02*
Y220275D01*
G01X194714Y218012D02*
Y222933D01*
G01X194607D02*
Y218012D01*
G01X194554Y219291D02*
Y221653D01*
G01X194488Y178436D02*
Y168020D01*
G01Y222953D02*
Y217992D01*
G01X194410Y222933D02*
Y218012D01*
G01X194370Y222953D02*
Y217992D01*
G01X194213Y218012D02*
Y222933D01*
G01X194016Y216338D02*
Y256102D01*
G01X193799Y224606D02*
Y220275D01*
G01X193701Y225295D02*
Y223523D01*
G01X193622Y222953D02*
Y217992D01*
G01X193583Y223622D02*
Y219449D01*
G01X193504D02*
Y225433D01*
G01X193462Y221063D02*
Y225000D01*
G01X193307Y222953D02*
Y217992D01*
G01X195138Y149016D02*
X195142Y148819D01*
G01X194942Y212052D02*
X195028Y211120D01*
G01X194155Y211614D02*
X194242Y210682D01*
G01X184519Y173534D02*
X184567Y173227D01*
G01X182647Y172923D02*
X182599Y173229D01*
G01X186614Y149409D02*
X186773Y148819D01*
G01X179641Y173718D02*
X179862Y173040D01*
G01X179985Y172638D02*
X179887Y172939D01*
G01X179739Y173819D02*
X180133Y172638D01*
G01X192787Y172648D02*
X192647Y172925D01*
G01X184378Y173808D02*
X184519Y173531D01*
G01X182787Y172648D02*
X182647Y172925D01*
G01X199695Y172638D02*
X199080Y173668D01*
G01X199154Y173819D02*
X199769Y172814D01*
G01X198293Y173718D02*
X198366Y173618D01*
G01X202057Y173743D02*
X202156Y173643D01*
G01X198219Y173618D02*
X198170Y173668D01*
G01X202423Y221394D02*
X203673Y221180D01*
G01X202563Y221155D02*
X201313Y221369D01*
G01X182356Y221827D02*
X184661Y221512D01*
G01X183587Y221481D02*
X181282Y221796D01*
G01X202156Y173391D02*
X202107Y173316D01*
G01X201491Y173618D02*
X201442Y173542D01*
G01X192647Y173531D02*
X192787Y173808D01*
G01X201983Y173391D02*
X202033Y173492D01*
G01X198391Y173442D02*
X198366Y173366D01*
G01X198219Y173391D02*
X198243Y173467D01*
G01X192599Y173227D02*
X192647Y173534D01*
G01X184567Y173229D02*
X184519Y172923D01*
G01X182599Y173227D02*
X182647Y173534D01*
G01X195028Y211120D02*
X195169Y212039D01*
G01X195083Y212971D02*
X194942Y212052D01*
G01X190798Y210682D02*
X190884Y211614D01*
G01X190012Y211120D02*
X190098Y212052D01*
G01X189902Y149016D02*
X189898Y148819D01*
G01X192520Y214370D02*
Y258071D01*
G01X192493Y221063D02*
Y225000D01*
G01X192368Y223228D02*
Y221653D01*
G01X192126Y216338D02*
Y215551D01*
G01X191972Y225000D02*
Y221070D01*
G01X191955Y221653D02*
Y223228D01*
G01X191366Y221063D02*
Y225000D01*
G01X191339D02*
Y220472D01*
G01X190397Y221063D02*
Y225000D01*
G01X190355D02*
Y221063D01*
G01X190256Y224409D02*
Y220472D01*
G01X190059Y224606D02*
Y220275D01*
G01X189528Y211614D02*
Y210433D01*
G01X189489D02*
Y211614D01*
G01X189461D02*
Y210433D01*
G01X189282D02*
Y211614D01*
G01X189272Y224606D02*
Y220275D01*
G01X189075Y220472D02*
Y224409D01*
G01X188977Y215551D02*
Y216338D01*
G01X188819Y211614D02*
Y210433D01*
G01X188583Y217716D02*
Y214960D01*
G01X188576Y211614D02*
Y210433D01*
G01X188500Y211614D02*
Y210433D01*
G01X188128D02*
Y211614D01*
G01X188091Y224409D02*
Y220472D01*
G01X188032Y211614D02*
Y210433D01*
G01X187992Y225197D02*
Y220079D01*
G01X187894Y224606D02*
Y220275D01*
G01X187729Y210433D02*
Y211614D01*
G01X186713Y224606D02*
Y220275D01*
G01X186621Y210433D02*
Y211614D01*
G01X186614D02*
Y210433D01*
G01X186221Y211614D02*
Y210433D01*
G01X185827Y211614D02*
Y210433D01*
G01X185040Y211614D02*
Y209055D01*
G01X184803Y227348D02*
Y221471D01*
G01X184661Y221512D02*
Y227307D01*
G01X184646Y222047D02*
Y226771D01*
G01Y216142D02*
Y216338D01*
G01X184488Y212992D02*
Y211811D01*
G01X184410Y222441D02*
Y226378D01*
G01Y210433D02*
Y211614D01*
G01X184252D02*
Y210433D01*
G01X184016Y227433D02*
Y221386D01*
G01X183900Y227437D02*
Y221382D01*
G01X183727Y221369D02*
Y227450D01*
G01X183701Y213779D02*
Y258661D01*
G01X183622Y210433D02*
Y211616D01*
G01Y227347D02*
Y221471D01*
G01X183587Y221481D02*
Y227337D01*
G01X183464Y211614D02*
Y210433D01*
G01X183425Y227369D02*
Y221450D01*
G01X183309Y227373D02*
Y221446D01*
G01X183279Y222441D02*
Y226378D01*
G01X183070Y210433D02*
Y211614D01*
G01X182617Y221394D02*
Y227424D01*
G01X182520Y258661D02*
Y213779D01*
G01X182477Y227664D02*
Y221155D01*
G01X182441Y259567D02*
Y212874D01*
G01X182047Y211614D02*
Y210433D01*
G01Y226206D02*
Y222613D01*
G01X181563Y211614D02*
Y210433D01*
G01X181383Y226378D02*
Y222441D01*
G01X181367Y227639D02*
Y221180D01*
G01X181339Y211811D02*
Y216142D01*
G01X181260Y211614D02*
Y210433D01*
G01Y259567D02*
Y212874D01*
G01X181164Y211614D02*
Y210433D01*
G01X180473Y214173D02*
Y236201D01*
G01X179831Y210433D02*
Y211614D01*
G01X179803D02*
Y210433D01*
G01X179764Y211614D02*
Y210433D01*
G01X178952Y173819D02*
Y172638D01*
G01X178804D02*
Y173618D01*
G01X178657Y173442D02*
Y173643D01*
G01X177953Y236201D02*
Y216142D01*
G01X175729Y173618D02*
X175753Y173542D01*
G01X175606D02*
X175581Y173618D01*
G01X177057Y172638D02*
X176442Y173668D01*
G01X176516Y173819D02*
X177131Y172814D01*
G01X175655Y173718D02*
X175729Y173618D01*
G01X175581D02*
X175532Y173668D01*
G01X193006Y172431D02*
X192786Y172650D01*
G01X184159Y174026D02*
X184380Y173806D01*
G01X183006Y172431D02*
X182786Y172650D01*
G01X198194Y173794D02*
X198293Y173718D01*
G01X201983Y173618D02*
X201910Y173668D01*
G01X201959Y173794D02*
X202057Y173743D01*
G01X201614Y221450D02*
X201730Y221446D01*
G01X201140Y221382D02*
X201024Y221386D01*
G01X202684Y221827D02*
X203758Y221796D01*
G01X199764Y223523D02*
X193583D01*
G01X197500Y223504D02*
X198288D01*
G01X197500Y223425D02*
X198288D01*
G01Y223350D02*
X197500D01*
G01Y223327D02*
X198288D01*
G01Y223291D02*
X197500D01*
G01X191955Y223228D02*
X192368D01*
G01X189075D02*
X188091D01*
G01X198288Y223203D02*
X197500D01*
G01X198288Y223179D02*
X197500D01*
G01Y223149D02*
X198288D01*
G01X197500Y223031D02*
X198288D01*
G01X189075D02*
X188091D01*
G01X198386Y222953D02*
X193307D01*
G01X193622Y222933D02*
X198288D01*
G01X202992Y222602D02*
X203779D01*
G01X184410Y222441D02*
X181260D01*
G01X203780D02*
X200630D01*
G01X196654Y222244D02*
X199016D01*
G01X184646Y222047D02*
X182520D01*
G01X198819D02*
X197500D01*
G01X202520D02*
X200394D01*
G01X189075Y221850D02*
X188091D01*
G01X191955Y221653D02*
X192368D01*
G01X189075D02*
X188091D01*
G01X199764D02*
X194554D01*
G01X198819Y221260D02*
X198032D01*
G01Y221063D02*
X198819D01*
G01X193504D02*
X190355D01*
G01X182441Y220905D02*
X181260D01*
G01X203780D02*
X202599D01*
G01X192520Y220890D02*
X193504D01*
G01X202599Y220877D02*
X203780D01*
G01X181260D02*
X182441D01*
G01X202599Y220866D02*
X203780D01*
G01X182441D02*
X181260D01*
G01X188091Y220472D02*
X193504D01*
G01X186713Y220275D02*
X194981D01*
G01X182441Y220092D02*
X181260D01*
G01X203780D02*
X202599D01*
G01X193583Y220079D02*
X187992D01*
G01X193504Y219980D02*
X192520D01*
G01X198032Y219882D02*
X198819D01*
G01X193504D02*
X192520D01*
G01Y219811D02*
X193504D01*
G01Y219764D02*
X192520D01*
G01Y219714D02*
X193504D01*
G01X198819Y219685D02*
X198032D01*
G01X192520Y219622D02*
X193504D01*
G01X193583Y219449D02*
X192520D01*
G01X199764Y219291D02*
X194554D01*
G01X202599Y219094D02*
X203780D01*
G01X182441D02*
X181260D01*
G01X197500Y218897D02*
X198819D01*
G01X196654Y218701D02*
X199016D01*
G01X182441Y218307D02*
X181260D01*
G01X203780D02*
X202599D01*
G01X198288Y218012D02*
X193622D01*
G01X198386Y217992D02*
X193307D01*
G01X197500Y217913D02*
X198288D01*
G01Y217795D02*
X197500D01*
G01Y217766D02*
X198288D01*
G01X197500Y217742D02*
X198288D01*
G01X192520Y217716D02*
X188583D01*
G01X197500Y217654D02*
X198288D01*
G01Y217618D02*
X197500D01*
G01Y217594D02*
X198288D01*
G01Y217519D02*
X197500D01*
G01X198288Y217441D02*
X197500D01*
G01X198386Y217421D02*
X197402D01*
G01X182441Y216338D02*
X181260D01*
G01X200394D02*
X184646D01*
G01X203780D02*
X202599D01*
G01X203701Y216142D02*
X181339D01*
G01X182441Y215551D02*
X181260D01*
G01X192126D02*
X188977D01*
G01X203780D02*
X202599D01*
G01X182520Y214960D02*
X181339D01*
G01X192520D02*
X188583D01*
G01X203701D02*
X202520D01*
G01X197244Y214370D02*
X192520D01*
G01X202599Y214173D02*
X205118D01*
G01X182441D02*
X179921D01*
G01X182520Y213779D02*
X183701D01*
G01X201339D02*
X202520D01*
G01X202599Y213386D02*
X203780D01*
G01X181260D02*
X182441D01*
G01X195227D02*
X189813D01*
G01X195269Y213353D02*
X189770D01*
G01X200551Y212992D02*
X184488D01*
G01X189957Y212971D02*
X195083D01*
G01X195227Y212205D02*
X189813D01*
G01X195244Y212192D02*
X189796D01*
G01X189871Y212039D02*
X195169D01*
G01X203701Y211811D02*
X181339D01*
G01X181260Y222591D02*
X182047Y222613D01*
G01X181282Y221796D02*
X182356Y221827D01*
G01X183309Y221446D02*
X183425Y221450D01*
G01X184016Y221386D02*
X183900Y221382D01*
G01X202107Y173316D02*
X201491Y172763D01*
G01X201295D02*
X201983Y173391D01*
G01X192786Y173806D02*
X193006Y174026D01*
G01X202697Y173216D02*
X202525Y173040D01*
G01X201344Y173643D02*
X201442Y173743D01*
G01X198170Y173341D02*
X198219Y173391D01*
G01X202525Y173241D02*
X203066Y173819D01*
G01X203263D02*
X202820Y173341D01*
G01X198366Y173366D02*
X198293Y173266D01*
G01X184519Y172925D02*
X184378Y172648D01*
G01X182647Y173531D02*
X182787Y173808D01*
G01X179149Y172638D02*
X179543Y173819D01*
G01X179395Y172939D02*
X179296Y172638D01*
G01X179420Y173040D02*
X179641Y173718D01*
G01X175753Y173442D02*
X175729Y173366D01*
G01X175581Y173391D02*
X175606Y173467D01*
G01X177279Y173819D02*
Y172638D01*
G01X177131Y172814D02*
Y173819D01*
G01X176442Y173668D02*
Y172638D01*
G01X176295D02*
Y173819D01*
G01X176098D02*
Y172638D01*
G01X175950D02*
Y173819D01*
G01X175753Y173542D02*
Y173442D01*
G01X175606Y173467D02*
Y173542D01*
G01X174990Y173693D02*
Y173316D01*
G01Y173165D02*
Y172638D01*
G01X174843D02*
Y173819D01*
G01X175556Y173794D02*
X175655Y173718D01*
G01X193281Y172291D02*
X193004Y172432D01*
G01X183885Y174165D02*
X184162Y174024D01*
G01X183281Y172291D02*
X183004Y172432D01*
G01X198170Y173668D02*
X198096Y173693D01*
G01X179765Y211614D02*
X205275D01*
G01X194242Y210682D02*
X190798D01*
G01X179765Y210433D02*
X205275D01*
G01X200000Y209645D02*
X185040D01*
G01X198032Y207086D02*
X187008D01*
G01X200379Y221512D02*
X202684Y221827D01*
G01X203758Y221796D02*
X201453Y221481D01*
G01X181367Y221180D02*
X182617Y221394D01*
G01X183727Y221369D02*
X182477Y221155D01*
G01X201565Y173668D02*
X201491Y173618D01*
G01X198293Y173266D02*
X198194Y173190D01*
G01X184380Y172650D02*
X184159Y172431D01*
G01X182786Y173806D02*
X183006Y174026D01*
G01X175532Y173341D02*
X175581Y173391D01*
G01X178804Y173618D02*
X178657Y173442D01*
G01Y173643D02*
X178804Y173819D01*
G01X175729Y173366D02*
X175655Y173266D01*
G01X192520Y216890D02*
X193307Y217992D01*
G01X188650Y210433D02*
X189796Y212192D01*
G01X189770Y213353D02*
X188637Y211614D01*
G01X175532Y173668D02*
X175458Y173693D01*
G01X201910Y173668D02*
X201787Y173693D01*
G01X198071Y173819D02*
X198194Y173794D01*
G01X175433Y173819D02*
X175556Y173794D01*
G01X201811Y173819D02*
X201959Y173794D01*
G01X183583Y174212D02*
X183887Y174164D01*
G01X193583Y172244D02*
X193279Y172292D01*
G01X183583Y172244D02*
X183279Y172292D01*
G01X198096Y173316D02*
X198170Y173341D01*
G01X193004Y174024D02*
X193281Y174165D01*
G01X184162Y172432D02*
X183885Y172291D01*
G01X183004Y174024D02*
X183281Y174165D01*
G01X201442Y173743D02*
X201541Y173794D01*
G01X175655Y173266D02*
X175556Y173190D01*
G01X194016Y216338D02*
X192520Y214842D01*
G01X203066Y173819D02*
X203263D01*
G01X202377D02*
X202525D01*
G01X201713D02*
X201811D01*
G01X199769D02*
X199917D01*
G01X198932D02*
X199154D01*
G01X198588D02*
X198735D01*
G01X197481D02*
X198071D01*
G01X179543D02*
X179739D01*
G01X178804D02*
X178952D01*
G01X176295D02*
X176516D01*
G01X177131D02*
X177279D01*
G01X175950D02*
X176098D01*
G01X174843D02*
X175433D01*
G01X175458Y173693D02*
X174990D01*
G01X198096D02*
X197628D01*
G01X201787D02*
X201688D01*
G01X201442Y173542D02*
X201319D01*
G01X197628Y173316D02*
X198096D01*
G01X174990D02*
X175458D01*
G01X175433Y173165D02*
X174990D01*
G01X198071D02*
X197628D01*
G01X179862Y173040D02*
X179420D01*
G01X179887Y172939D02*
X179395D01*
G01X201491Y172763D02*
X202180D01*
G01X176098Y172638D02*
X175950D01*
G01X174990D02*
X174843D01*
G01X176442D02*
X176295D01*
G01X177279D02*
X177057D01*
G01X179296D02*
X179149D01*
G01X178952D02*
X178804D01*
G01X180133D02*
X179985D01*
G01X197628D02*
X197481D01*
G01X199080D02*
X198932D01*
G01X198735D02*
X198588D01*
G01X199917D02*
X199695D01*
G01X202525D02*
X202377D01*
G01X202180D02*
X201295D01*
G01X203263D02*
X203066D01*
G01X175458Y173316D02*
X175532Y173341D01*
G01X201541Y173794D02*
X201713Y173819D01*
G01X183583Y174212D02*
X183279Y174164D01*
G01X193583Y174212D02*
X193279Y174164D01*
G01X183583Y172244D02*
X183887Y172292D01*
G01X175556Y173190D02*
X175433Y173165D01*
G01X198194Y173190D02*
X198071Y173165D01*
G01X201688Y173693D02*
X201565Y173668D01*
G01X181890Y150000D02*
X203150D01*
G01X186614Y149409D02*
X180906D01*
G01X204134D02*
X198425D01*
G01X195138Y149016D02*
X189902D01*
G01X189898Y148819D02*
X186773D01*
G01X198267D02*
X195142D01*
G01X197185Y148425D02*
X187854D01*
G01X174803Y148031D02*
X210236D01*
G01X160236Y321260D02*
Y289140D01*
G01D02*
X156501Y287895D01*
G01X156502D02*
G03X148425Y276690I3734J-11205D01*
G01D02*
Y258743D01*
G01D02*
G03X156502Y247538I11811J0D01*
G01X160236Y246293D02*
X156501Y247538D01*
G01X195192Y260293D02*
X195169Y260402D01*
G01X195218Y260240D02*
X195192Y260293D01*
G01X195244Y260249D02*
X195218Y260240D01*
G01X182062Y250059D02*
X182047Y249828D01*
G01X182105Y250275D02*
X182062Y250059D01*
G01X182174Y250449D02*
X182105Y250275D01*
G01X182261Y250566D02*
X182174Y250449D01*
G01X182356Y250614D02*
X182261Y250566D01*
G01X202977Y246000D02*
X202992Y246235D01*
G01X202934Y245787D02*
X202977Y246000D01*
G01X202866Y245614D02*
X202934Y245787D01*
G01X202780Y245498D02*
X202866Y245614D01*
G01X202684Y245449D02*
X202780Y245498D01*
G01X200253Y238849D02*
X200327Y238828D01*
G01X200238Y238871D02*
X200253Y238849D01*
G01X200284Y238892D02*
X200238Y238871D01*
G01X181308Y244790D02*
X181367Y244802D01*
G01X181272Y244777D02*
X181308Y244790D01*
G01X181260Y244764D02*
X181272Y244777D01*
G01X202562Y234323D02*
X202572Y234555D01*
G01X202531Y234108D02*
X202562Y234323D01*
G01X202482Y233934D02*
X202531Y234108D01*
G01X202419Y233817D02*
X202482Y233934D01*
G01X202350Y233768D02*
X202419Y233817D01*
G01X203732Y251273D02*
X203673Y251261D01*
G01X203768Y251286D02*
X203732Y251273D01*
G01X203780Y251299D02*
X203768Y251286D01*
G01X203732Y227651D02*
X203673Y227639D01*
G01X203768Y227664D02*
X203732Y227651D01*
G01X203780Y227676D02*
X203768Y227664D01*
G01X190654Y260806D02*
X190884Y260827D01*
G01X190444Y260745D02*
X190654Y260806D01*
G01X190273Y260649D02*
X190444Y260745D01*
G01X190154Y260526D02*
X190273Y260649D01*
G01X190098Y260388D02*
X190154Y260526D01*
G01X202578Y239534D02*
X202551Y239526D01*
G01X202593Y239543D02*
X202578Y239534D01*
G01X202599Y239552D02*
X202593Y239543D01*
G01X203746Y239524D02*
X203704Y239510D01*
G01X203771Y239538D02*
X203746Y239524D01*
G01X203780Y239552D02*
X203771Y239538D01*
G01X200238Y233570D02*
X200284Y233549D01*
G01X200253Y233592D02*
X200238Y233570D01*
G01X200327Y233612D02*
X200253Y233592D01*
G01X183535Y227363D02*
X183425Y227369D01*
G01X183603Y227355D02*
X183535Y227363D01*
G01X183622Y227346D02*
X183603Y227355D01*
G01X183587Y227337D02*
X183622Y227346D01*
G01X202595Y227672D02*
X202599Y227676D01*
G01X202583Y227668D02*
X202595Y227672D01*
G01X202563Y227664D02*
X202583Y227668D01*
G01X192691Y223789D02*
X192558Y223702D01*
G01X192839Y223819D02*
X192691Y223789D01*
G01X189822Y260240D02*
X189796Y260249D01*
G01X189848Y260293D02*
X189822Y260240D01*
G01X189871Y260402D02*
X189848Y260293D01*
G01X203765Y245419D02*
X203758Y245418D01*
G01X203773Y245421D02*
X203765Y245419D01*
G01X203780Y245423D02*
X203773Y245421D01*
G01X201506Y245078D02*
X201614Y245072D01*
G01X201436Y245086D02*
X201506Y245078D01*
G01X201418Y245095D02*
X201436Y245086D01*
G01X201453Y245103D02*
X201418Y245095D01*
G01X191933Y230727D02*
X191955Y230905D01*
G01X191868Y230564D02*
X191933Y230727D01*
G01X191765Y230432D02*
X191868Y230564D01*
G01X191633Y230345D02*
X191765Y230432D01*
G01X191484Y230315D02*
X191633Y230345D01*
G01X191933Y238601D02*
X191955Y238779D01*
G01X191868Y238438D02*
X191933Y238601D01*
G01X191765Y238306D02*
X191868Y238438D01*
G01X191633Y238219D02*
X191765Y238306D01*
G01X191484Y238189D02*
X191633Y238219D01*
G01X192389Y231278D02*
X192368Y231102D01*
G01X192454Y231442D02*
X192389Y231278D01*
G01X192558Y231576D02*
X192454Y231442D01*
G01X192691Y231663D02*
X192558Y231576D01*
G01X192839Y231693D02*
X192691Y231663D01*
G01X192389Y239152D02*
X192368Y238976D01*
G01X192454Y239317D02*
X192389Y239152D01*
G01X192558Y239450D02*
X192454Y239317D01*
G01X192691Y239537D02*
X192558Y239450D01*
G01X192839Y239567D02*
X192691Y239537D01*
G01X191922Y230316D02*
X191898Y230315D01*
G01X191947Y230318D02*
X191922Y230316D01*
G01X191972Y230322D02*
X191947Y230318D01*
G01X191922Y238190D02*
X191898Y238189D01*
G01X191947Y238192D02*
X191922Y238190D01*
G01X191972Y238196D02*
X191947Y238192D01*
G01X181267Y227020D02*
X181260Y227018D01*
G01X181274Y227021D02*
X181267Y227020D01*
G01X181282Y227023D02*
X181274Y227021D01*
G01X202022Y227386D02*
X201730Y227373D01*
G01X202260Y227404D02*
X202022Y227386D01*
G01X202423Y227424D02*
X202260Y227404D01*
G01X201418Y227346D02*
X201453Y227337D01*
G01X201436Y227355D02*
X201418Y227346D01*
G01X201506Y227363D02*
X201436Y227355D01*
G01X201614Y227369D02*
X201506Y227363D01*
G01X201272Y227445D02*
X201313Y227450D01*
G01X201213Y227440D02*
X201272Y227445D01*
G01X201140Y227437D02*
X201213Y227440D01*
G01X182261Y245496D02*
X182356Y245449D01*
G01X182174Y245613D02*
X182261Y245496D01*
G01X182105Y245787D02*
X182174Y245613D01*
G01X182062Y246003D02*
X182105Y245787D01*
G01X182047Y246235D02*
X182062Y246003D01*
G01X182261Y226944D02*
X182356Y226992D01*
G01X182174Y226828D02*
X182261Y226944D01*
G01X182105Y226653D02*
X182174Y226828D01*
G01X182062Y226438D02*
X182105Y226653D01*
G01X182047Y226206D02*
X182062Y226438D01*
G01X192279Y239537D02*
X192426Y239567D01*
G01X192145Y239450D02*
X192279Y239537D01*
G01X192041Y239317D02*
X192145Y239450D01*
G01X191976Y239152D02*
X192041Y239317D01*
G01X191955Y238976D02*
X191976Y239152D01*
G01X192279Y231663D02*
X192426Y231693D01*
G01X192145Y231576D02*
X192279Y231663D01*
G01X192041Y231443D02*
X192145Y231576D01*
G01X191976Y231278D02*
X192041Y231443D01*
G01X191955Y231102D02*
X191976Y231278D01*
G01X192279Y223789D02*
X192426Y223819D01*
G01X192145Y223702D02*
X192279Y223789D01*
G01X192130Y238266D02*
X191972Y238196D01*
G01X192258Y238401D02*
X192130Y238266D01*
G01X192340Y238581D02*
X192258Y238401D01*
G01X192368Y238779D02*
X192340Y238581D01*
G01X192130Y230392D02*
X191972Y230322D01*
G01X192258Y230527D02*
X192130Y230392D01*
G01X192340Y230707D02*
X192258Y230527D01*
G01X192368Y230905D02*
X192340Y230707D01*
G01X181274Y250643D02*
X181282Y250645D01*
G01X181267Y250642D02*
X181274Y250643D01*
G01X181260Y250640D02*
X181267Y250642D01*
G01X183533Y250985D02*
X183425Y250991D01*
G01X183603Y250977D02*
X183533Y250985D01*
G01X183621Y250968D02*
X183603Y250977D01*
G01X183587Y250959D02*
X183621Y250968D01*
G01X182445Y244768D02*
X182441Y244764D01*
G01X182457Y244773D02*
X182445Y244768D01*
G01X182477Y244777D02*
X182457Y244773D01*
G01X202595Y251294D02*
X202599Y251299D01*
G01X202583Y251290D02*
X202595Y251294D01*
G01X202563Y251286D02*
X202583Y251290D01*
G01X183018Y245054D02*
X183309Y245068D01*
G01X182780Y245036D02*
X183018Y245054D01*
G01X182617Y245016D02*
X182780Y245036D01*
G01X202022Y251009D02*
X201730Y250995D01*
G01X202260Y251026D02*
X202022Y251009D01*
G01X202423Y251046D02*
X202260Y251026D01*
G01X183621Y245095D02*
X183587Y245103D01*
G01X183604Y245086D02*
X183621Y245095D01*
G01X183534Y245078D02*
X183604Y245086D01*
G01X183425Y245072D02*
X183534Y245078D01*
G01X184789Y245106D02*
X184661Y245134D01*
G01X184783Y245077D02*
X184789Y245106D01*
G01X184642Y245050D02*
X184783Y245077D01*
G01X184379Y245026D02*
X184642Y245050D01*
G01X184016Y245008D02*
X184379Y245026D01*
G01X183768Y244996D02*
X183727Y244991D01*
G01X183827Y245000D02*
X183768Y244996D01*
G01X183900Y245004D02*
X183827Y245000D01*
G01X184789Y227334D02*
X184661Y227307D01*
G01X184783Y227363D02*
X184789Y227334D01*
G01X184641Y227391D02*
X184783Y227363D01*
G01X184375Y227415D02*
X184641Y227391D01*
G01X184016Y227433D02*
X184375Y227415D01*
G01X183016Y227387D02*
X183309Y227373D01*
G01X182781Y227404D02*
X183016Y227387D01*
G01X182617Y227424D02*
X182781Y227404D01*
G01X183827Y227440D02*
X183900Y227437D01*
G01X183768Y227445D02*
X183827Y227440D01*
G01X183727Y227450D02*
X183768Y227445D01*
G01X191592Y234240D02*
X191503Y234252D01*
G01X191676Y234206D02*
X191592Y234240D01*
G01X191754Y234152D02*
X191676Y234206D01*
G01X191822Y234079D02*
X191754Y234152D01*
G01X191879Y233988D02*
X191822Y234079D01*
G01X191921Y233886D02*
X191879Y233988D01*
G01X191946Y233776D02*
X191921Y233886D01*
G01X191955Y233661D02*
X191946Y233776D01*
G01X191592Y242114D02*
X191503Y242126D01*
G01X191676Y242080D02*
X191592Y242114D01*
G01X191754Y242026D02*
X191676Y242080D01*
G01X191822Y241953D02*
X191754Y242026D01*
G01X191879Y241862D02*
X191822Y241953D01*
G01X191921Y241760D02*
X191879Y241862D01*
G01X191946Y241650D02*
X191921Y241760D01*
G01X191955Y241535D02*
X191946Y241650D01*
G01X192951Y232885D02*
X193040Y232874D01*
G01X192866Y232919D02*
X192951Y232885D01*
G01X192788Y232974D02*
X192866Y232919D01*
G01X192720Y233047D02*
X192788Y232974D01*
G01X192663Y233138D02*
X192720Y233047D01*
G01X192622Y233239D02*
X192663Y233138D01*
G01X192596Y233350D02*
X192622Y233239D01*
G01X192588Y233464D02*
X192596Y233350D01*
G01X192951Y240759D02*
X193040Y240748D01*
G01X192866Y240793D02*
X192951Y240759D01*
G01X192788Y240848D02*
X192866Y240793D01*
G01X192720Y240921D02*
X192788Y240848D01*
G01X192663Y241012D02*
X192720Y240921D01*
G01X192622Y241113D02*
X192663Y241012D01*
G01X192596Y241224D02*
X192622Y241113D01*
G01X192588Y241338D02*
X192596Y241224D01*
G01X191471Y251362D02*
X191352Y251378D01*
G01X191584Y251317D02*
X191471Y251362D01*
G01X191687Y251245D02*
X191584Y251317D01*
G01X191778Y251147D02*
X191687Y251245D01*
G01X191854Y251026D02*
X191778Y251147D01*
G01X191909Y250890D02*
X191854Y251026D01*
G01X191943Y250743D02*
X191909Y250890D01*
G01X191955Y250590D02*
X191943Y250743D01*
G01X193072Y248637D02*
X193191Y248622D01*
G01X192959Y248682D02*
X193072Y248637D01*
G01X192855Y248755D02*
X192959Y248682D01*
G01X192764Y248852D02*
X192855Y248755D01*
G01X192688Y248974D02*
X192764Y248852D01*
G01X192633Y249109D02*
X192688Y248974D01*
G01X192599Y249256D02*
X192633Y249109D01*
G01X192588Y249409D02*
X192599Y249256D01*
G01X202780Y226943D02*
X202684Y226992D01*
G01X202866Y226827D02*
X202780Y226943D01*
G01X202934Y226654D02*
X202866Y226827D01*
G01X202977Y226441D02*
X202934Y226654D01*
G01X202992Y226206D02*
X202977Y226441D01*
G01X202419Y238624D02*
X202350Y238672D01*
G01X202481Y238507D02*
X202419Y238624D01*
G01X202531Y238333D02*
X202481Y238507D01*
G01X202562Y238118D02*
X202531Y238333D01*
G01X202572Y237886D02*
X202562Y238118D01*
G01X201293Y233840D02*
X201224Y233790D01*
G01X201355Y233956D02*
X201293Y233840D01*
G01X201403Y234129D02*
X201355Y233956D01*
G01X201435Y234342D02*
X201403Y234129D01*
G01X201445Y234577D02*
X201435Y234342D01*
G01X190066Y261457D02*
X190012Y261321D01*
G01X190185Y261580D02*
X190066Y261457D01*
G01X190358Y261677D02*
X190185Y261580D01*
G01X190570Y261738D02*
X190358Y261677D01*
G01X190798Y261759D02*
X190570Y261738D01*
G01X201418Y250968D02*
X201453Y250959D01*
G01X201436Y250977D02*
X201418Y250968D01*
G01X201506Y250985D02*
X201436Y250977D01*
G01X201614Y250991D02*
X201506Y250985D01*
G01X201272Y251067D02*
X201313Y251072D01*
G01X201213Y251062D02*
X201272Y251067D01*
G01X201140Y251059D02*
X201213Y251062D01*
G01X202260Y245036D02*
X202423Y245016D01*
G01X202022Y245054D02*
X202260Y245036D01*
G01X201730Y245068D02*
X202022Y245054D01*
G01X182780Y251026D02*
X182617Y251046D01*
G01X183018Y251009D02*
X182780Y251026D01*
G01X183309Y250995D02*
X183018Y251009D01*
G01X200251Y245106D02*
X200379Y245134D01*
G01X200257Y245077D02*
X200251Y245106D01*
G01X200399Y245050D02*
X200257Y245077D01*
G01X200665Y245026D02*
X200399Y245050D01*
G01X201024Y245008D02*
X200665Y245026D01*
G01X184789Y250956D02*
X184661Y250929D01*
G01X184783Y250985D02*
X184789Y250956D01*
G01X184641Y251013D02*
X184783Y250985D01*
G01X184375Y251037D02*
X184641Y251013D01*
G01X184016Y251055D02*
X184375Y251037D01*
G01X201213Y245000D02*
X201140Y245004D01*
G01X201272Y244996D02*
X201213Y245000D01*
G01X201313Y244991D02*
X201272Y244996D01*
G01X191964Y233348D02*
X191955Y233464D01*
G01X191990Y233237D02*
X191964Y233348D01*
G01X192031Y233136D02*
X191990Y233237D01*
G01X192087Y233047D02*
X192031Y233136D01*
G01X192157Y232972D02*
X192087Y233047D01*
G01X192235Y232918D02*
X192157Y232972D01*
G01X192319Y232885D02*
X192235Y232918D01*
G01X192407Y232874D02*
X192319Y232885D01*
G01X192579Y233778D02*
X192588Y233661D01*
G01X192553Y233888D02*
X192579Y233778D01*
G01X192511Y233990D02*
X192553Y233888D01*
G01X192455Y234079D02*
X192511Y233990D01*
G01X192386Y234153D02*
X192455Y234079D01*
G01X192308Y234207D02*
X192386Y234153D01*
G01X192223Y234241D02*
X192308Y234207D01*
G01X192135Y234252D02*
X192223Y234241D01*
G01X191964Y241222D02*
X191955Y241338D01*
G01X191990Y241111D02*
X191964Y241222D01*
G01X192031Y241010D02*
X191990Y241111D01*
G01X192087Y240921D02*
X192031Y241010D01*
G01X192157Y240847D02*
X192087Y240921D01*
G01X192235Y240792D02*
X192157Y240847D01*
G01X192319Y240759D02*
X192235Y240792D01*
G01X192407Y240748D02*
X192319Y240759D01*
G01X192579Y241652D02*
X192588Y241535D01*
G01X192553Y241762D02*
X192579Y241652D01*
G01X192511Y241864D02*
X192553Y241762D01*
G01X192455Y241953D02*
X192511Y241864D01*
G01X192386Y242027D02*
X192455Y241953D01*
G01X192308Y242081D02*
X192386Y242027D01*
G01X192223Y242115D02*
X192308Y242081D01*
G01X192135Y242126D02*
X192223Y242115D01*
G01X181267Y245421D02*
X181260Y245423D01*
G01X181274Y245419D02*
X181267Y245421D01*
G01X181282Y245418D02*
X181274Y245419D01*
G01X200666Y227415D02*
X201024Y227433D01*
G01X200399Y227391D02*
X200666Y227415D01*
G01X200257Y227363D02*
X200399Y227391D01*
G01X200251Y227334D02*
X200257Y227363D01*
G01X200379Y227307D02*
X200251Y227334D01*
G01X203765Y227021D02*
X203758Y227023D01*
G01X203773Y227020D02*
X203765Y227021D01*
G01X203780Y227018D02*
X203773Y227020D01*
G01X181308Y227651D02*
X181367Y227639D01*
G01X181272Y227664D02*
X181308Y227651D01*
G01X181260Y227676D02*
X181272Y227664D01*
G01X182457Y227668D02*
X182477Y227664D01*
G01X182445Y227672D02*
X182457Y227668D01*
G01X182441Y227676D02*
X182445Y227672D01*
G01X202780Y250565D02*
X202684Y250614D01*
G01X202866Y250449D02*
X202780Y250565D01*
G01X202934Y250276D02*
X202866Y250449D01*
G01X202977Y250063D02*
X202934Y250276D01*
G01X202992Y249828D02*
X202977Y250063D01*
G01X194886Y260526D02*
X194942Y260388D01*
G01X194768Y260648D02*
X194886Y260526D01*
G01X194596Y260744D02*
X194768Y260648D01*
G01X194386Y260806D02*
X194596Y260744D01*
G01X194155Y260827D02*
X194386Y260806D01*
G01X183827Y251062D02*
X183900Y251059D01*
G01X183768Y251067D02*
X183827Y251062D01*
G01X183727Y251072D02*
X183768Y251067D01*
G01X191967Y249254D02*
X191955Y249409D01*
G01X192001Y249107D02*
X191967Y249254D01*
G01X192057Y248971D02*
X192001Y249107D01*
G01X192132Y248852D02*
X192057Y248971D01*
G01X192224Y248753D02*
X192132Y248852D01*
G01X192328Y248681D02*
X192224Y248753D01*
G01X192441Y248637D02*
X192328Y248681D01*
G01X192558Y248622D02*
X192441Y248637D01*
G01X192576Y250746D02*
X192588Y250590D01*
G01X192541Y250893D02*
X192576Y250746D01*
G01X192486Y251028D02*
X192541Y250893D01*
G01X192411Y251147D02*
X192486Y251028D01*
G01X192318Y251246D02*
X192411Y251147D01*
G01X192214Y251318D02*
X192318Y251246D01*
G01X192102Y251363D02*
X192214Y251318D01*
G01X191984Y251378D02*
X192102Y251363D01*
G01X203773Y250642D02*
X203780Y250640D01*
G01X203765Y250643D02*
X203773Y250642D01*
G01X203758Y250645D02*
X203765Y250643D01*
G01X203768Y244777D02*
X203780Y244764D01*
G01X203732Y244790D02*
X203768Y244777D01*
G01X203673Y244802D02*
X203732Y244790D01*
G01X181272Y251286D02*
X181260Y251299D01*
G01X181308Y251273D02*
X181272Y251286D01*
G01X181367Y251261D02*
X181308Y251273D01*
G01X200666Y251037D02*
X201024Y251055D01*
G01X200399Y251013D02*
X200666Y251037D01*
G01X200257Y250985D02*
X200399Y251013D01*
G01X200251Y250956D02*
X200257Y250985D01*
G01X200379Y250929D02*
X200251Y250956D01*
G01X201418Y238867D02*
X201436Y238876D01*
G01X201424Y238859D02*
X201418Y238867D01*
G01X201454Y238850D02*
X201424Y238859D01*
G01X202593Y232897D02*
X202599Y232888D01*
G01X202578Y232906D02*
X202593Y232897D01*
G01X202551Y232915D02*
X202578Y232906D01*
G01X203771Y232903D02*
X203780Y232888D01*
G01X203746Y232917D02*
X203771Y232903D01*
G01X203704Y232931D02*
X203746Y232917D01*
G01X201424Y233582D02*
X201454Y233590D01*
G01X201418Y233573D02*
X201424Y233582D01*
G01X201436Y233565D02*
X201418Y233573D01*
G01X195204Y259064D02*
X195269Y259087D01*
G01X195139Y259197D02*
X195204Y259064D01*
G01X195083Y259470D02*
X195139Y259197D01*
G01X189901Y259198D02*
X189957Y259470D01*
G01X189836Y259064D02*
X189901Y259198D01*
G01X189770Y259087D02*
X189836Y259064D01*
G01X201435Y238098D02*
X201445Y237875D01*
G01X201404Y238311D02*
X201435Y238098D01*
G01X201355Y238484D02*
X201404Y238311D01*
G01X201293Y238600D02*
X201355Y238484D01*
G01X201224Y238650D02*
X201293Y238600D01*
G01X182457Y251290D02*
X182477Y251286D01*
G01X182445Y251294D02*
X182457Y251290D01*
G01X182441Y251299D02*
X182445Y251294D01*
G01X202583Y244773D02*
X202563Y244777D01*
G01X202595Y244768D02*
X202583Y244773D01*
G01X202599Y244764D02*
X202595Y244768D01*
G01X194472Y261738D02*
X194242Y261759D01*
G01X194682Y261677D02*
X194472Y261738D01*
G01X194854Y261581D02*
X194682Y261677D01*
G01X194973Y261459D02*
X194854Y261581D01*
G01X195028Y261321D02*
X194973Y261459D01*
G01X201339Y258661D02*
G03X200551Y259449I-788J0D01*
G01X202599Y259567D02*
G03X201339Y260827I-1260J0D01*
G01X202520Y258661D02*
G03X200551Y260630I-1969J0D01*
G01X207087Y256299D02*
G03X205118Y258268I-1969J0D01*
G01X203780Y259567D02*
G03X201339Y262008I-2441J0D01*
G01X184646Y301207D02*
G03X200394I7874J11785D01*
G01X207284Y312992D02*
G03I-14764J0D01*
G01X208071D02*
G03I-15551J0D01*
G01X210514D02*
G03I-17994J0D01*
G01X211297D02*
G03I-18777J0D01*
G01X212205D02*
G03I-19685J0D01*
G01X200000Y263386D02*
G03X198032Y265354I-1968J0D01*
G01X187008D02*
G03X185040Y263386I0J-1968D01*
G01X165418Y282567D02*
G03X168110Y286302I-1245J3735D01*
G01X158992Y280425D02*
G03X156299Y276690I1244J-3735D01*
G01X184488Y259449D02*
G03X183701Y258661I0J-787D01*
G01Y260827D02*
G03X182441Y259567I0J-1260D01*
G01X184488Y260630D02*
G03X182520Y258661I0J-1968D01*
G01X179921Y258268D02*
G03X177953Y256299I0J-1968D01*
G01X183701Y262008D02*
G03X181260Y259567I0J-2441D01*
G01X199764Y255551D02*
G03X197244Y258071I-2520J0D01*
G01X168110Y249131D02*
G03X165418Y252866I-3937J0D01*
G01X156299Y258743D02*
G03X158992Y255008I3937J0D01*
G01X175394Y298228D02*
X209646D01*
G01X175000Y297834D02*
X210040D01*
G01X175000Y295275D02*
X210040D01*
G01X189796Y260249D02*
X188650Y262008D01*
G01X188637Y260827D02*
X189770Y259087D01*
G01X192520Y255551D02*
X193307Y254449D01*
G01Y246575D02*
X192520Y247677D01*
G01X194016Y256102D02*
X192520Y257598D01*
G01X186607Y253528D02*
X187668Y252638D01*
G01X186455D02*
X185394Y253528D01*
G01X195169Y260402D02*
X195028Y261321D01*
G01X194942Y260388D02*
X195083Y259470D01*
G01X193307Y238701D02*
X192520Y239803D01*
G01X193307Y230827D02*
X192520Y231929D01*
G01X165418Y252866D02*
X158991Y255008D01*
G01X182477Y251286D02*
X183727Y251072D01*
G01X182617Y251046D02*
X181367Y251261D01*
G01X202423Y245016D02*
X203673Y244802D01*
G01X202563Y244777D02*
X201313Y244991D01*
G01X201453Y250959D02*
X203758Y250645D01*
G01X202684Y250614D02*
X200379Y250929D01*
G01X198032Y265354D02*
X187008D01*
G01X185040Y262795D02*
X200000D01*
G01X179765Y262008D02*
X205275D01*
G01X190798Y261759D02*
X194242D01*
G01X179765Y260827D02*
X205275D01*
G01X203701Y260630D02*
X181339D01*
G01X195169Y260402D02*
X189871D01*
G01X189796Y260249D02*
X195244D01*
G01X195227Y260236D02*
X189813D01*
G01X195083Y259470D02*
X189957D01*
G01X184488Y259449D02*
X200551D01*
G01X189770Y259087D02*
X195269D01*
G01X182441Y259055D02*
X181260D01*
G01X195227D02*
X189813D01*
G01X203780D02*
X202599D01*
G01X183701Y258661D02*
X182520D01*
G01X202520D02*
X201339D01*
G01X182441Y258268D02*
X179921D01*
G01X205118D02*
X202599D01*
G01X192520Y258071D02*
X197244D01*
G01X202520Y257480D02*
X203701D01*
G01X181339D02*
X182520D01*
G01X192520D02*
X188583D01*
G01X210040Y295275D02*
Y330708D01*
G01X209646Y304035D02*
Y298228D01*
G01X203704Y232931D02*
X201436Y233565D01*
G01X200284Y233549D02*
X202551Y232915D01*
G01X202350Y238672D02*
X201454Y238850D01*
G01X200327Y238828D02*
X201224Y238650D01*
G01X182356Y245449D02*
X184661Y245134D01*
G01X183587Y245103D02*
X181282Y245418D01*
G01X183900Y251059D02*
X184016Y251055D01*
G01X183425Y250991D02*
X183309Y250995D01*
G01X201614Y245072D02*
X201730Y245068D01*
G01X201140Y245004D02*
X201024Y245008D01*
G01X182356Y250614D02*
X181282Y250645D01*
G01X181260Y249850D02*
X182047Y249828D01*
G01X203780Y246213D02*
X202992Y246235D01*
G01X202684Y245449D02*
X203758Y245418D01*
G01X202599Y256890D02*
X203780D01*
G01X181260D02*
X182441D01*
G01X192126D02*
X188977D01*
G01X181339Y256299D02*
X203701D01*
G01X184646Y256102D02*
X200394D01*
G01X182441D02*
X181260D01*
G01X203780D02*
X202599D01*
G01X198386Y255019D02*
X197402D01*
G01X197500Y255000D02*
X198288D01*
G01X197500Y254921D02*
X198288D01*
G01Y254846D02*
X197500D01*
G01Y254823D02*
X198288D01*
G01Y254787D02*
X197500D01*
G01X192520Y254724D02*
X188583D01*
G01X198288Y254699D02*
X197500D01*
G01X198288Y254675D02*
X197500D01*
G01Y254645D02*
X198288D01*
G01X197500Y254527D02*
X198288D01*
G01X193307Y254449D02*
X198386D01*
G01X193622Y254429D02*
X198288D01*
G01X185394Y254419D02*
X192520D01*
G01X202599Y254134D02*
X203780D01*
G01X181260D02*
X182441D01*
G01X196654Y253740D02*
X199016D01*
G01X198819Y253543D02*
X197500D01*
G01X192520Y253528D02*
X186607D01*
G01X182441Y253346D02*
X181260D01*
G01X203780D02*
X202599D01*
G01X199764Y253149D02*
X194554D01*
G01X193583Y252992D02*
X192520D01*
G01X193504Y252819D02*
X192520D01*
G01X198819Y252756D02*
X198032D01*
G01X193504Y252726D02*
X192520D01*
G01Y252677D02*
X193504D01*
G01X187668Y252638D02*
X186455D01*
G01X193504Y252630D02*
X192520D01*
G01X198032Y252559D02*
X198819D01*
G01X193504D02*
X192520D01*
G01X193504Y252460D02*
X192520D01*
G01X187992Y252362D02*
X193583D01*
G01X202599Y252349D02*
X203780D01*
G01X181260D02*
X182441D01*
G01X186713Y252165D02*
X194981D01*
G01X193504Y251968D02*
X188091D01*
G01X193504Y251608D02*
X192520D01*
G01X182441Y251575D02*
X181260D01*
G01X203780D02*
X202599D01*
G01X182441Y251563D02*
X181260D01*
G01X203780D02*
X202599D01*
G01Y251535D02*
X203780D01*
G01X181260D02*
X182441D01*
G01X198032Y251378D02*
X198819D01*
G01X190355D02*
X193504D01*
G01X198819Y251181D02*
X198032D01*
G01X189075Y250787D02*
X188091D01*
G01X199764D02*
X194554D01*
G01X188091Y250590D02*
X189075D01*
G01X192588D02*
X191955D01*
G01X197500Y250394D02*
X198819D01*
G01X184646D02*
X182520D01*
G01X202520D02*
X200394D01*
G01X196654Y250197D02*
X199016D01*
G01X200630Y250000D02*
X203780D01*
G01X184410D02*
X181260D01*
G01X198288Y249508D02*
X193622D01*
G01X198386Y249488D02*
X193307D01*
G01X197500Y249409D02*
X198288D01*
G01X188091D02*
X189075D01*
G01X192588D02*
X191955D01*
G01X198288Y249291D02*
X197500D01*
G01Y249262D02*
X198288D01*
G01X197500Y249238D02*
X198288D01*
G01X189075Y249212D02*
X188091D01*
G01X197500Y249150D02*
X198288D01*
G01Y249114D02*
X197500D01*
G01Y249090D02*
X198288D01*
G01Y249016D02*
X197500D01*
G01X198288Y248937D02*
X197500D01*
G01X199764Y248917D02*
X193583D01*
G01X195748Y248819D02*
X193583D01*
G01X195551Y248622D02*
X192558D01*
G01X188091Y248031D02*
X193504D01*
G01X186713Y247834D02*
X194981D01*
G01X193504Y247539D02*
X192520D01*
G01X195551Y247441D02*
X190355D01*
G01X192520Y247370D02*
X193504D01*
G01Y247323D02*
X192520D01*
G01Y247273D02*
X193504D01*
G01X195748Y247244D02*
X187992D01*
G01X192520Y247210D02*
X193504D01*
G01X192520Y247181D02*
X193504D01*
G01X199764Y247145D02*
X193701D01*
G01X197500Y247126D02*
X198288D01*
G01X197500Y247047D02*
X198288D01*
G01X193583Y247008D02*
X192520D01*
G01X198288Y246972D02*
X197500D01*
G01Y246949D02*
X198288D01*
G01Y246913D02*
X197500D01*
G01X198288Y246825D02*
X197500D01*
G01X198288Y246801D02*
X197500D01*
G01Y246771D02*
X198288D01*
G01X197500Y246653D02*
X198288D01*
G01X193307Y246575D02*
X198386D01*
G01X193622Y246555D02*
X198288D01*
G01X184410Y246063D02*
X181260D01*
G01X203780D02*
X200630D01*
G01X196654Y245866D02*
X199016D01*
G01X184646Y245669D02*
X182520D01*
G01X198819D02*
X197500D01*
G01X202520D02*
X200394D01*
G01X199764Y245275D02*
X194554D01*
G01X198819Y244882D02*
X198032D01*
G01Y244685D02*
X198819D01*
G01X182441Y244527D02*
X181260D01*
G01X203780D02*
X202599D01*
G01Y244499D02*
X203780D01*
G01X181260D02*
X182441D01*
G01X202599Y244488D02*
X203780D01*
G01X181260D02*
X182441D01*
G01Y243714D02*
X181260D01*
G01X203780D02*
X202599D01*
G01X198032Y243504D02*
X198819D01*
G01Y243307D02*
X198032D01*
G01X193583Y243149D02*
X192520D01*
G01X193504Y242976D02*
X192520D01*
G01X199764Y242913D02*
X194554D01*
G01X203780D02*
X202599D01*
G01X193504Y242884D02*
X192520D01*
G01Y242834D02*
X193504D01*
G01Y242787D02*
X192520D01*
G01X202599Y242716D02*
X203780D01*
G01X182441D02*
X181260D01*
G01X193504D02*
X192520D01*
G01X193504Y242618D02*
X192520D01*
G01X197500Y242519D02*
X198819D01*
G01X193583D02*
X187992D01*
G01X196654Y242323D02*
X199016D01*
G01X186713D02*
X194981D01*
G01X193504Y242299D02*
X192520D01*
G01X203758Y250645D02*
X202684Y250614D01*
G01X202992Y249828D02*
X203780Y249850D01*
G01X182047Y246235D02*
X181260Y246213D01*
G01X181282Y245418D02*
X182356Y245449D01*
G01X201024Y251055D02*
X201140Y251059D01*
G01X201730Y250995D02*
X201614Y250991D01*
G01X183309Y245068D02*
X183425Y245072D01*
G01X184016Y245008D02*
X183900Y245004D01*
G01X207284Y295275D02*
Y330708D01*
G01X205276Y260827D02*
Y262008D01*
G01X205237Y260827D02*
Y262008D01*
G01X205209D02*
Y260827D01*
G01X204921Y310039D02*
Y298228D01*
G01X204134Y300590D02*
Y298228D01*
G01X203876Y260827D02*
Y262008D01*
G01X203780D02*
Y260827D01*
G01X203704Y239510D02*
Y232931D01*
G01X203701Y256299D02*
Y260630D01*
G01Y241929D02*
Y230512D01*
G01X203673Y244802D02*
Y251261D01*
G01X203657Y246063D02*
Y250000D01*
G01X203477Y260827D02*
Y262008D01*
G01X202992Y260827D02*
Y262008D01*
G01Y249828D02*
Y246235D01*
G01X202572Y237875D02*
Y234555D01*
G01X202563Y244777D02*
Y251286D01*
G01X202551Y239526D02*
Y232915D01*
G01X202423Y251046D02*
Y245016D01*
G01X201969Y262008D02*
Y260827D01*
G01X201761Y250000D02*
Y246063D01*
G01X201730Y245068D02*
Y250995D01*
G01X201614Y245072D02*
Y250991D01*
G01X201575Y262008D02*
Y260827D01*
G01X201454Y233590D02*
Y238850D01*
G01X201453Y250959D02*
Y245103D01*
G01X201445Y237864D02*
Y234577D01*
G01X201436Y238876D02*
Y233565D01*
G01X201418Y260824D02*
Y262008D01*
G01Y238865D02*
Y233576D01*
G01Y250970D02*
Y245093D01*
G01X201313Y251072D02*
Y244991D01*
G01X201140Y245004D02*
Y251059D01*
G01X201024Y245008D02*
Y251055D01*
G01X200788Y260827D02*
Y262008D01*
G01X200630Y250000D02*
Y246063D01*
G01Y262008D02*
Y260827D01*
G01X200551Y259449D02*
Y260630D01*
G01X200394Y250394D02*
Y245669D01*
G01Y256299D02*
Y256102D01*
G01X200379Y250929D02*
Y245134D01*
G01X200327Y233612D02*
Y238828D01*
G01X200284Y238892D02*
Y233549D01*
G01X200236Y238865D02*
Y233576D01*
G01Y250970D02*
Y245093D01*
G01X200000Y263386D02*
Y260827D01*
G01X199632Y229527D02*
Y227165D01*
G01Y237401D02*
Y235039D01*
G01Y245275D02*
Y242913D01*
G01Y253149D02*
Y250787D01*
G01X199212Y262008D02*
Y260827D01*
G01X199016Y230118D02*
Y226575D01*
G01Y237992D02*
Y234449D01*
G01Y245866D02*
Y242323D01*
G01Y253740D02*
Y250197D01*
G01X198819Y229921D02*
Y226771D01*
G01Y237795D02*
Y234645D01*
G01Y245669D02*
Y242519D01*
G01Y253543D02*
Y250394D01*
G01X198818Y260827D02*
Y262008D01*
G01X198555Y250394D02*
Y253543D01*
G01Y242519D02*
Y245669D01*
G01Y234645D02*
Y237795D01*
G01Y226771D02*
Y229921D01*
G01X198515Y250394D02*
Y253543D01*
G01Y242519D02*
Y245669D01*
G01Y234645D02*
Y237795D01*
G01Y226771D02*
Y229921D01*
G01X198425Y262008D02*
Y260827D01*
G01X198418Y262008D02*
Y260827D01*
G01X198386Y248917D02*
Y255019D01*
G01Y241043D02*
Y247145D01*
G01Y233169D02*
Y239271D01*
G01Y225295D02*
Y231397D01*
G01X198288D02*
Y225295D01*
G01Y239271D02*
Y233169D01*
G01Y247145D02*
Y241043D01*
G01Y255019D02*
Y248917D01*
G01X198180Y249508D02*
Y254429D01*
G01Y241634D02*
Y246555D01*
G01Y233760D02*
Y238681D01*
G01Y225886D02*
Y230807D01*
G01X198032Y229921D02*
Y226771D01*
G01Y237795D02*
Y234645D01*
G01Y245669D02*
Y242519D01*
G01Y253543D02*
Y250394D01*
G01X197873D02*
Y253543D01*
G01Y242519D02*
Y245669D01*
G01Y234645D02*
Y237795D01*
G01Y226771D02*
Y229921D01*
G01X197835Y230118D02*
Y226575D01*
G01Y237992D02*
Y234449D01*
G01Y245866D02*
Y242323D01*
G01Y253740D02*
Y250197D01*
G01X197764Y250394D02*
Y253543D01*
G01Y242519D02*
Y245669D01*
G01Y234645D02*
Y237795D01*
G01Y226771D02*
Y229921D01*
G01X197500Y248917D02*
Y255019D01*
G01Y241043D02*
Y247145D01*
G01Y233169D02*
Y239271D01*
G01Y225295D02*
Y231397D01*
G01X197447Y249508D02*
Y254429D01*
G01Y241634D02*
Y246555D01*
G01Y233760D02*
Y238681D01*
G01Y225886D02*
Y230807D01*
G01X197402Y225866D02*
Y225295D01*
G01Y231397D02*
Y230827D01*
G01Y233740D02*
Y233169D01*
G01Y239271D02*
Y238701D01*
G01Y241614D02*
Y241043D01*
G01Y247145D02*
Y246575D01*
G01Y249488D02*
Y248917D01*
G01Y255019D02*
Y254449D01*
G01X197311Y262008D02*
Y260827D01*
G01X197008Y262008D02*
Y260827D01*
G01X196912Y262008D02*
Y260827D01*
G01X196851Y227165D02*
Y225866D01*
G01Y230827D02*
Y229527D01*
G01Y235039D02*
Y233740D01*
G01Y238701D02*
Y237401D01*
G01Y242913D02*
Y241614D01*
G01Y246575D02*
Y245275D01*
G01Y250787D02*
Y249488D01*
G01Y254449D02*
Y253149D01*
G01X196654Y250197D02*
Y253740D01*
G01Y242323D02*
Y245866D01*
G01Y234449D02*
Y237992D01*
G01Y226575D02*
Y230118D01*
G01X196540Y260827D02*
Y262008D01*
G01X196464Y260827D02*
Y262008D01*
G01X196221Y260827D02*
Y262008D01*
G01X195758D02*
Y260827D01*
G01X195748Y225197D02*
Y223622D01*
G01Y233071D02*
Y231496D01*
G01Y240945D02*
Y239370D01*
G01Y248819D02*
Y247244D01*
G01X195579Y260827D02*
Y262008D01*
G01X195551Y225000D02*
Y223819D01*
G01Y232874D02*
Y231693D01*
G01Y240748D02*
Y239567D01*
G01Y248622D02*
Y247441D01*
G01Y262008D02*
Y260827D01*
G01X195512D02*
Y262008D01*
G01X195448Y249508D02*
Y254429D01*
G01Y241634D02*
Y246555D01*
G01Y233760D02*
Y238681D01*
G01Y225886D02*
Y230807D01*
G01X195394D02*
Y225886D01*
G01Y238681D02*
Y233760D01*
G01Y246555D02*
Y241634D01*
G01Y254429D02*
Y249508D01*
G01X194981Y234449D02*
Y230118D01*
G01Y242323D02*
Y237992D01*
G01Y252165D02*
Y247834D01*
G01X194919Y225000D02*
Y223819D01*
G01Y232874D02*
Y231693D01*
G01Y240748D02*
Y239567D01*
G01Y248622D02*
Y247441D01*
G01X194714Y249508D02*
Y254429D01*
G01Y241634D02*
Y246555D01*
G01Y233760D02*
Y238681D01*
G01Y225886D02*
Y230807D01*
G01X194607D02*
Y225886D01*
G01Y238681D02*
Y233760D01*
G01Y246555D02*
Y241634D01*
G01Y254429D02*
Y249508D01*
G01X194567Y225000D02*
Y223819D01*
G01Y232874D02*
Y231693D01*
G01Y240748D02*
Y239567D01*
G01Y248622D02*
Y247441D01*
G01X194554Y250787D02*
Y253149D01*
G01Y242913D02*
Y245275D01*
G01Y235039D02*
Y237401D01*
G01Y227165D02*
Y229527D01*
G01X194488Y230827D02*
Y225866D01*
G01Y238701D02*
Y233740D01*
G01Y246575D02*
Y241614D01*
G01Y254449D02*
Y249488D01*
G01X194410Y230807D02*
Y225886D01*
G01Y238681D02*
Y233760D01*
G01Y246555D02*
Y241634D01*
G01Y254429D02*
Y249508D01*
G01X194370Y230827D02*
Y225866D01*
G01Y238701D02*
Y233740D01*
G01Y246575D02*
Y241614D01*
G01Y254449D02*
Y249488D01*
G01X194286Y225000D02*
Y223819D01*
G01Y232874D02*
Y231693D01*
G01Y240748D02*
Y239567D01*
G01Y248622D02*
Y247441D01*
G01X194213Y249508D02*
Y254429D01*
G01Y241634D02*
Y246555D01*
G01Y233760D02*
Y238681D01*
G01Y225886D02*
Y230807D01*
G01X193799Y234449D02*
Y230118D01*
G01Y242323D02*
Y237992D01*
G01Y252165D02*
Y247834D01*
G01X193701Y233169D02*
Y231397D01*
G01Y241043D02*
Y239271D01*
G01Y248917D02*
Y247145D01*
G01X193622Y230827D02*
Y225866D01*
G01Y238701D02*
Y233740D01*
G01Y246575D02*
Y241614D01*
G01Y254449D02*
Y249488D01*
G01X193583Y225433D02*
Y225197D01*
G01Y231496D02*
Y229291D01*
G01Y235275D02*
Y233071D01*
G01Y239370D02*
Y237165D01*
G01Y243149D02*
Y240945D01*
G01Y247244D02*
Y247008D01*
G01Y252992D02*
Y248819D01*
G01X193504Y247008D02*
Y252992D01*
G01Y237165D02*
Y243149D01*
G01Y229291D02*
Y235275D01*
G01X193462Y247441D02*
Y251378D01*
G01Y238189D02*
Y242126D01*
G01Y230315D02*
Y234252D01*
G01X193307Y233740D02*
Y238701D01*
G01Y230827D02*
Y225866D01*
G01Y246575D02*
Y241614D01*
G01Y254449D02*
Y249488D01*
G01X192588Y233661D02*
Y233464D01*
G01Y241535D02*
Y241338D01*
G01Y250590D02*
Y249409D01*
G01X190884Y260827D02*
X190798Y261759D01*
G01X190098Y260388D02*
X190012Y261321D01*
G01X182477Y227664D02*
X183727Y227450D01*
G01X181367Y227639D02*
X182617Y227424D01*
G01X201453Y227337D02*
X203758Y227023D01*
G01X202684Y226992D02*
X200379Y227307D01*
G01X183900Y227437D02*
X184016Y227433D01*
G01X183425Y227369D02*
X183309Y227373D01*
G01X182356Y226992D02*
X181282Y227023D01*
G01X182047Y226206D02*
X181260Y226228D01*
G01X201445Y234577D02*
X202572Y234555D01*
G01X202350Y233768D02*
X201224Y233790D01*
G01X193504Y242126D02*
X188091D01*
G01X203780D02*
X202599D01*
G01X203701Y241929D02*
X202520D01*
G01X198288Y241634D02*
X193622D01*
G01X198386Y241614D02*
X193307D01*
G01X197500Y241535D02*
X198288D01*
G01X192588D02*
X191955D01*
G01X198288Y241417D02*
X197500D01*
G01Y241388D02*
X198288D01*
G01X197500Y241364D02*
X198288D01*
G01X192588Y241338D02*
X191955D01*
G01X203780D02*
X202599D01*
G01X197500Y241276D02*
X198288D01*
G01Y241240D02*
X197500D01*
G01Y241216D02*
X198288D01*
G01X202599Y241152D02*
X203780D01*
G01X202599Y241150D02*
X203780D01*
G01X198288Y241142D02*
X197500D01*
G01X198288Y241063D02*
X197500D01*
G01X193583Y241043D02*
X199764D01*
G01X189075Y240945D02*
X188091D01*
G01X195748D02*
X193583D01*
G01X192407Y240748D02*
X195551D01*
G01X189075D02*
X188091D01*
G01X203701D02*
X202520D01*
G01X203780Y240034D02*
X202599D01*
G01X203780Y239579D02*
X202599D01*
G01X189075Y239567D02*
X188091D01*
G01X195551D02*
X192426D01*
G01X189075Y239370D02*
X188091D01*
G01X195748D02*
X193583D01*
G01X199764Y239271D02*
X193583D01*
G01X197500Y239252D02*
X198288D01*
G01X202599Y239248D02*
X203780D01*
G01X197500Y239173D02*
X198288D01*
G01Y239098D02*
X197500D01*
G01Y239075D02*
X198288D01*
G01Y239039D02*
X197500D01*
G01X191955Y238976D02*
X192368D01*
G01X198288Y238951D02*
X197500D01*
G01X198288Y238927D02*
X197500D01*
G01Y238897D02*
X198288D01*
G01X197500Y238779D02*
X198288D01*
G01X191955D02*
X192368D01*
G01X193307Y238701D02*
X198386D01*
G01X193622Y238681D02*
X198288D01*
G01X188091Y238189D02*
X193504D01*
G01X192520Y238016D02*
X193504D01*
G01X196654Y237992D02*
X199016D01*
G01X186713D02*
X194981D01*
G01X201445Y237875D02*
X202572D01*
G01X193583Y237795D02*
X187992D01*
G01X198819D02*
X197500D01*
G01X193504Y237697D02*
X192520D01*
G01X193504Y237598D02*
X192520D01*
G01Y237527D02*
X193504D01*
G01Y237480D02*
X192520D01*
G01Y237431D02*
X193504D01*
G01X199764Y237401D02*
X194554D01*
G01X192520Y237338D02*
X193504D01*
G01X193583Y237165D02*
X192520D01*
G01X198819Y237008D02*
X198032D01*
G01Y236811D02*
X198819D01*
G01X182441Y236240D02*
X177953D01*
G01X182441Y236201D02*
X177953D01*
G01X198032Y235630D02*
X198819D01*
G01Y235433D02*
X198032D01*
G01X193583Y235275D02*
X192520D01*
G01X193504Y235102D02*
X192520D01*
G01X199764Y235039D02*
X194554D01*
G01X193504Y235010D02*
X192520D01*
G01Y234960D02*
X193504D01*
G01Y234913D02*
X192520D01*
G01X182441Y234855D02*
X181260D01*
G01X193504Y234842D02*
X192520D01*
G01X182441Y234829D02*
X181260D01*
G01X193504Y234744D02*
X192520D01*
G01X197500Y234645D02*
X198819D01*
G01X193583D02*
X187992D01*
G01X196654Y234449D02*
X199016D01*
G01X186713D02*
X194981D01*
G01X193504Y234425D02*
X192520D01*
G01X193504Y234252D02*
X188091D01*
G01X182441Y233806D02*
X181260D01*
G01X182441Y233779D02*
X181260D01*
G01X198288Y233760D02*
X193622D01*
G01X198386Y233740D02*
X193307D01*
G01X197500Y233661D02*
X198288D01*
G01X192588D02*
X191955D01*
G01X198288Y233543D02*
X197500D01*
G01Y233514D02*
X198288D01*
G01X197500Y233490D02*
X198288D01*
G01X192588Y233464D02*
X191955D01*
G01X197500Y233402D02*
X198288D01*
G01Y233366D02*
X197500D01*
G01Y233342D02*
X198288D01*
G01Y233268D02*
X197500D01*
G01X203780Y233193D02*
X202599D01*
G01X198288Y233189D02*
X197500D01*
G01X199764Y233169D02*
X193583D01*
G01X189075Y233071D02*
X188091D01*
G01X195748D02*
X193583D01*
G01X192407Y232874D02*
X195551D01*
G01X189075D02*
X188091D01*
G01X202599Y232856D02*
X203780D01*
G01X202599Y232407D02*
X203780D01*
G01X182441Y232303D02*
X181260D01*
G01X182441Y232264D02*
X181260D01*
G01X189075Y231693D02*
X188091D01*
G01X195551D02*
X192426D01*
G01X203701D02*
X202520D01*
G01X189075Y231496D02*
X188091D01*
G01X195748D02*
X193583D01*
G01X199764Y231397D02*
X193583D01*
G01X197500Y231378D02*
X198288D01*
G01X197500Y231299D02*
X198288D01*
G01X203780Y231284D02*
X202599D01*
G01Y231282D02*
X203780D01*
G01X198288Y231224D02*
X197500D01*
G01Y231201D02*
X198288D01*
G01Y231165D02*
X197500D01*
G01X202599Y231102D02*
X203780D01*
G01X191955D02*
X192368D01*
G01X198288Y231077D02*
X197500D01*
G01X198288Y231053D02*
X197500D01*
G01Y231023D02*
X198288D01*
G01X197500Y230905D02*
X198288D01*
G01X191955D02*
X192368D01*
G01X198386Y230827D02*
X193307D01*
G01X193622Y230807D02*
X198288D01*
G01X203701Y230512D02*
X202520D01*
G01X188091Y230315D02*
X193504D01*
G01X203780D02*
X202599D01*
G01X192520Y230142D02*
X193504D01*
G01X196654Y230118D02*
X199016D01*
G01X186713D02*
X194981D01*
G01X193583Y229921D02*
X187992D01*
G01X198819D02*
X197500D01*
G01X193504Y229823D02*
X192520D01*
G01X182441Y229724D02*
X181260D01*
G01X193504D02*
X192520D01*
G01X203780D02*
X202599D01*
G01X192520Y229653D02*
X193504D01*
G01Y229606D02*
X192520D01*
G01Y229557D02*
X193504D01*
G01X202599Y229527D02*
X203780D01*
G01X199764D02*
X194554D01*
G01X192520Y229464D02*
X193504D01*
G01X193583Y229291D02*
X192520D01*
G01X198819Y229134D02*
X198032D01*
G01Y228937D02*
X198819D01*
G01X202599Y228727D02*
X203780D01*
G01X181260D02*
X182441D01*
G01Y227953D02*
X181260D01*
G01X203780D02*
X202599D01*
G01X182441Y227941D02*
X181260D01*
G01X203780D02*
X202599D01*
G01X182441Y227913D02*
X181260D01*
G01X203780D02*
X202599D01*
G01X198032Y227756D02*
X198819D01*
G01Y227559D02*
X198032D01*
G01X199764Y227165D02*
X194554D01*
G01X201224Y238650D02*
X202350Y238672D01*
G01X181282Y250645D02*
X183587Y250959D01*
G01X184661Y250929D02*
X182356Y250614D01*
G01X200379Y245134D02*
X202684Y245449D01*
G01X203758Y245418D02*
X201453Y245103D01*
G01X201313Y251072D02*
X202563Y251286D01*
G01X203673Y251261D02*
X202423Y251046D01*
G01X181367Y244802D02*
X182617Y245016D01*
G01X183727Y244991D02*
X182477Y244777D01*
G01X195028Y261321D02*
X194942Y260388D01*
G01X194242Y261759D02*
X194155Y260827D01*
G01X192520Y254419D02*
Y253528D01*
G01X192493Y247441D02*
Y251378D01*
G01Y238189D02*
Y242126D01*
G01Y230315D02*
Y234252D01*
G01X192368Y231102D02*
Y230905D01*
G01Y238976D02*
Y238779D01*
G01X192126Y256890D02*
Y256102D01*
G01X191972Y234252D02*
Y230322D01*
G01Y242126D02*
Y238196D01*
G01Y251378D02*
Y247441D01*
G01X191955Y249409D02*
Y250590D01*
G01Y241338D02*
Y241535D01*
G01Y238779D02*
Y238976D01*
G01Y233464D02*
Y233661D01*
G01Y230905D02*
Y231102D01*
G01X191366Y247441D02*
Y251378D01*
G01Y238189D02*
Y242126D01*
G01Y230315D02*
Y234252D01*
G01X191339D02*
Y230315D01*
G01Y242126D02*
Y238189D01*
G01Y251968D02*
Y247441D01*
G01X190397D02*
Y251378D01*
G01Y238189D02*
Y242126D01*
G01Y230315D02*
Y234252D01*
G01X190355D02*
Y230315D01*
G01Y242126D02*
Y238189D01*
G01Y251378D02*
Y247441D01*
G01X190256Y234252D02*
Y230315D01*
G01Y242126D02*
Y238189D01*
G01Y251968D02*
Y248031D01*
G01X190059Y247834D02*
Y252165D01*
G01Y234449D02*
Y230118D01*
G01Y242323D02*
Y237992D01*
G01X189528Y260827D02*
Y262008D01*
G01X189489Y260827D02*
Y262008D01*
G01X189461D02*
Y260827D01*
G01X189282D02*
Y262008D01*
G01X189272Y234449D02*
Y230118D01*
G01Y242323D02*
Y237992D01*
G01Y252165D02*
Y247834D01*
G01X189075Y248031D02*
Y251968D01*
G01Y238189D02*
Y242126D01*
G01Y230315D02*
Y234252D01*
G01X188977Y256102D02*
Y256890D01*
G01X188819Y262008D02*
Y260827D01*
G01X188583Y257480D02*
Y254724D01*
G01X188576Y262008D02*
Y260827D01*
G01X188500Y262008D02*
Y260827D01*
G01X188128D02*
Y262008D01*
G01X188091Y234252D02*
Y230315D01*
G01Y242126D02*
Y238189D01*
G01Y251968D02*
Y248031D01*
G01X188032Y262008D02*
Y260827D01*
G01X187992Y234645D02*
Y229921D01*
G01Y242519D02*
Y237795D01*
G01Y252362D02*
Y247244D01*
G01X187894Y234449D02*
Y230118D01*
G01Y242323D02*
Y237992D01*
G01Y252165D02*
Y247834D01*
G01X187729Y260827D02*
Y262008D01*
G01X186713Y234449D02*
Y230118D01*
G01Y242323D02*
Y237992D01*
G01Y252165D02*
Y247834D01*
G01X186621Y260827D02*
Y262008D01*
G01X186614D02*
Y260827D01*
G01X186221Y262008D02*
Y260827D01*
G01X185827Y262008D02*
Y260827D01*
G01X185394Y253528D02*
Y254419D01*
G01X185040Y263386D02*
Y260827D01*
G01X184803Y250970D02*
Y245093D01*
G01X184661Y245134D02*
Y250929D01*
G01X184646Y256102D02*
Y256299D01*
G01Y245669D02*
Y250394D01*
G01X184488Y260630D02*
Y259449D01*
G01X184410Y260827D02*
Y262008D01*
G01Y246063D02*
Y250000D01*
G01X184252Y262008D02*
Y260827D01*
G01X184016Y251055D02*
Y245008D01*
G01X183900Y251059D02*
Y245004D01*
G01X183727Y244991D02*
Y251072D01*
G01X183622Y260824D02*
Y262008D01*
G01Y250970D02*
Y245093D01*
G01X183587Y245103D02*
Y250959D01*
G01X183464Y262008D02*
Y260827D01*
G01X183425Y250991D02*
Y245072D01*
G01X183309Y250995D02*
Y245068D01*
G01X183279Y250000D02*
Y246063D01*
G01X183070Y260827D02*
Y262008D01*
G01X182617Y245016D02*
Y251046D01*
G01X182477Y251286D02*
Y244777D01*
G01X182047Y246235D02*
Y249828D01*
G01Y262008D02*
Y260827D01*
G01X181563Y262008D02*
Y260827D01*
G01X181383Y250000D02*
Y246063D01*
G01X181367Y251261D02*
Y244802D01*
G01X181339Y256299D02*
Y260630D01*
G01X181260Y262008D02*
Y260827D01*
G01X181164Y262008D02*
Y260827D01*
G01X180906Y300590D02*
Y298228D01*
G01X180473Y236240D02*
Y258268D01*
G01X180118Y298228D02*
Y310039D01*
G01X179831Y260827D02*
Y262008D01*
G01X179803D02*
Y260827D01*
G01X179764D02*
Y262008D01*
G01X177953Y256299D02*
Y236240D01*
G01X177756Y295275D02*
Y330708D01*
G01X197500Y226771D02*
X198819D01*
G01X184646D02*
X182520D01*
G01X202520D02*
X200394D01*
G01X196654Y226575D02*
X199016D01*
G01X200630Y226378D02*
X203780D01*
G01X184410D02*
X181260D01*
G01X198288Y225886D02*
X193622D01*
G01X198386Y225866D02*
X193307D01*
G01X197500Y225787D02*
X198288D01*
G01Y225669D02*
X197500D01*
G01Y225640D02*
X198288D01*
G01X197500Y225616D02*
X198288D01*
G01X197500Y225528D02*
X198288D01*
G01Y225492D02*
X197500D01*
G01Y225468D02*
X198288D01*
G01X193583Y225433D02*
X192520D01*
G01X198288Y225394D02*
X197500D01*
G01X198288Y225315D02*
X197500D01*
G01X199764Y225295D02*
X193701D01*
G01X193504Y225260D02*
X192520D01*
G01X187992Y225197D02*
X195748D01*
G01X193504Y225173D02*
X192520D01*
G01X193504Y225167D02*
X192520D01*
G01Y225118D02*
X193504D01*
G01Y225071D02*
X192520D01*
G01X190355Y225000D02*
X195551D01*
G01X193504Y224901D02*
X192520D01*
G01X186713Y224606D02*
X194981D01*
G01X193504Y224409D02*
X188091D01*
G01X195551Y223819D02*
X192426D01*
G01X195748Y223622D02*
X193583D01*
G01X203758Y227023D02*
X202684Y226992D01*
G01X203780Y226228D02*
X202992Y226206D01*
G01X201024Y227433D02*
X201140Y227437D01*
G01X201730Y227373D02*
X201614Y227369D01*
G01X183587Y227337D02*
X181282Y227023D01*
G01X182356Y226992D02*
X184661Y227307D01*
G01X201313Y227450D02*
X202563Y227664D01*
G01X201224Y233790D02*
X200327Y233612D01*
G01X201454Y233590D02*
X202350Y233768D01*
G01X202551Y239526D02*
X200284Y238892D01*
G01X201436Y238876D02*
X203704Y239510D01*
G01X189957Y259470D02*
X190098Y260388D01*
G01X190012Y261321D02*
X189871Y260402D01*
G01X175394Y327756D02*
Y298228D01*
G01X175000Y330708D02*
Y295275D01*
G01X168110Y350394D02*
Y286302D01*
G01X203673Y227639D02*
X202423Y227424D01*
G01X207284Y298228D02*
X209646Y304134D01*
G01X156299Y276690D02*
Y258743D01*
G01X192520Y224764D02*
X193307Y225866D01*
G01Y233740D02*
X192520Y232638D01*
G01Y240512D02*
X193307Y241614D01*
G01X192520Y248386D02*
X193307Y249488D01*
G01X195269Y259087D02*
X196403Y260827D01*
G01X196390Y262008D02*
X195244Y260249D01*
G01X198268Y256102D02*
X199246Y257081D01*
G01X165418Y282567D02*
X158991Y280425D01*
G01X225227Y362205D02*
G03Y354331I0J-3937D01*
G01X207116D02*
G03Y362205I0J3937D01*
G01X160236Y346456D02*
G03X168110I3937J0D01*
G01Y321260D02*
G03X160236I-3937J0D01*
G01Y350394D02*
G03X156299Y354331I-3937J0D01*
G01X160236Y350394D02*
Y346456D01*
G01X201634Y364173D02*
G03X203603Y362205I1968J0D01*
G01X201634Y387795D02*
Y364173D01*
G01X203603Y362205D02*
X228740D01*
G01X202364Y345739D02*
G03Y349755I0J2008D01*
G01D02*
G03Y345739I0J-2008D01*
G01X208664Y343847D02*
X196064D01*
G01X208664Y351647D02*
Y343847D01*
G01X196064Y351647D02*
X208664D01*
G01X196064Y343847D02*
Y351647D01*
G01X209764Y342747D02*
X194964D01*
G01X209764Y352747D02*
Y342747D01*
G01X194964Y352747D02*
X209764D01*
G01X194964Y342747D02*
Y352747D01*
G01X176925Y320886D02*
X176575Y320866D01*
G01X177250Y320947D02*
X176925Y320886D01*
G01X177516Y321046D02*
X177250Y320947D01*
G01X177694Y321174D02*
X177516Y321046D01*
G01X177756Y321320D02*
X177694Y321174D01*
G01X208115Y306082D02*
X208465Y306102D01*
G01X207790Y306021D02*
X208115Y306082D01*
G01X207524Y305922D02*
X207790Y306021D01*
G01X207346Y305794D02*
X207524Y305922D01*
G01X207284Y305648D02*
X207346Y305794D01*
G01X177694Y304809D02*
X177756Y304664D01*
G01X177517Y304938D02*
X177694Y304809D01*
G01X177250Y305036D02*
X177517Y304938D01*
G01X176926Y305097D02*
X177250Y305036D01*
G01X176575Y305118D02*
X176926Y305097D01*
G01X207346Y320190D02*
X207284Y320336D01*
G01X207523Y320062D02*
X207346Y320190D01*
G01X207789Y319963D02*
X207523Y320062D01*
G01X208114Y319902D02*
X207789Y319963D01*
G01X208465Y319882D02*
X208114Y319902D01*
G01X197334Y319123D02*
G03X196848Y319291I-486J-619D01*
G01X197769Y318861D02*
G03X196457Y317394I-656J-733D01*
G01X193504Y321260D02*
G03X191536I-984J0D01*
G01X196848Y306693D02*
G03X197334Y306861I0J787D01*
G01X191536Y312795D02*
G03X193504I984J0D01*
G01X188583Y317394D02*
G03X196457I3937J-4402D01*
G01X197334Y306861D02*
G03X199949Y310630I-4814J6131D01*
G01X185091D02*
G03X187706Y306861I7429J2362D01*
G01X199949Y315354D02*
G03X197334Y319123I-7429J-2362D01*
G01X187705Y319122D02*
G03X185091Y315354I4814J-6131D01*
G01X187271Y318861D02*
G03X197769I5249J-5869D01*
G01X183860Y310629D02*
G03X187273Y305709I8660J2363D01*
G01X197767D02*
G03X201180Y310629I-5247J7283D01*
G01X187273Y320275D02*
G03X183860Y315355I5247J-7283D01*
G01X201180D02*
G03X197767Y320275I-8660J-2363D01*
G01X183481Y309857D02*
G03X186302Y305722I9038J3136D01*
G01X198738D02*
G03X201559Y309857I-6217J7271D01*
G01Y316127D02*
G03X198738Y320262I-9038J-3136D01*
G01X186302D02*
G03X183481Y316127I6217J-7271D01*
G01X183479Y309744D02*
G03X186243Y305720I9040J3248D01*
G01X198797D02*
G03X201561Y309744I-6276J7272D01*
G01Y316240D02*
G03X198797Y320264I-9040J-3248D01*
G01X186243D02*
G03X183479Y316240I6276J-7272D01*
G01X205315Y312992D02*
G03I-12795J0D01*
G01X205906D02*
G03I-13386J0D01*
G01X206103D02*
G03I-13583J0D01*
G01X200394Y324777D02*
G03X184646I-7874J-11785D01*
G01X188192Y319291D02*
G03X187705Y319122I0J-786D01*
G01X188583Y317394D02*
G03X187271Y318861I-656J734D01*
G01X187706Y306861D02*
G03X188192Y306693I486J619D01*
G01X172047Y354331D02*
G03X168110Y350394I0J-3937D01*
G01X202343Y336384D02*
X202636Y336138D01*
G01X202301D02*
X202008Y336384D01*
G01X203642Y333760D02*
X203851Y333596D01*
G01X203097Y332693D02*
X202971Y332775D01*
G01X203558Y333555D02*
X203642Y333514D01*
G01X202888Y332693D02*
X202804Y332734D01*
G01X203432Y333596D02*
X203558Y333555D01*
G01X203474Y333801D02*
X203642Y333760D01*
G01X228740Y354331D02*
X172047D01*
G01X202264Y324311D02*
X202953Y323622D01*
G01X202930Y334949D02*
X203013Y334867D01*
G01X202846D02*
X202762Y334949D01*
G01X202804Y332734D02*
X202720Y332816D01*
G01X207284Y315945D02*
X209646Y314567D01*
G01X202008Y336630D02*
X203977D01*
G01Y336384D02*
X202343D01*
G01X202636Y336138D02*
X202301D01*
G01X203181Y335810D02*
X203977D01*
G01Y335605D02*
X203181D01*
G01X202636Y334867D02*
X202846D01*
G01X203013D02*
X203977D01*
G01Y334662D02*
X202636D01*
G01Y334334D02*
X203977D01*
G01X202008D02*
X202218D01*
G01Y334129D02*
X202008D01*
G01X203977D02*
X202636D01*
G01X203139Y333801D02*
X203474D01*
G01X203181Y333596D02*
X203432D01*
G01X202720Y332816D02*
X202678Y332898D01*
G01X203851Y333596D02*
X203935Y333472D01*
G01X202846Y335072D02*
X202930Y334949D01*
G01X202762D02*
X202678Y335072D01*
G01X203642Y333514D02*
X203725Y333390D01*
G01X202971Y332775D02*
X202888Y332898D01*
G01X202264Y304626D02*
X202953Y303937D01*
G01X177756Y310039D02*
X175394Y311417D01*
G01X202636Y332693D02*
X202888D01*
G01X203725D02*
X204647D01*
G01X203516D02*
X203097D01*
G01X204647Y332488D02*
X202636D01*
G01X210040Y330708D02*
X175000D01*
G01X210040Y328149D02*
X175000D01*
G01X209646Y327756D02*
X175394D01*
G01X204921Y325394D02*
X180118D01*
G01X177756Y325197D02*
X175000D01*
G01X210040D02*
X207284D01*
G01X183858Y324606D02*
X181496D01*
G01X193701D02*
X191339D01*
G01X203544D02*
X201181D01*
G01X183858Y324473D02*
X181496D01*
G01X193701D02*
X191339D01*
G01X203544D02*
X201181D01*
G01X204528Y324311D02*
X180512D01*
G01X183858Y323508D02*
X181496D01*
G01X193701D02*
X191339D01*
G01X203544D02*
X201181D01*
G01X183858Y323477D02*
X181496D01*
G01X193701D02*
X191339D01*
G01X203544D02*
X201181D01*
G01X183858Y323425D02*
X181496D01*
G01X193701D02*
X191339D01*
G01X203544D02*
X201181D01*
G01X183858Y323394D02*
X181496D01*
G01X193701D02*
X191339D01*
G01X203544D02*
X201181D01*
G01X177756Y322933D02*
X175394D01*
G01X177756Y322834D02*
X175394D01*
G01X183858Y322377D02*
X181496D01*
G01X193701D02*
X191339D01*
G01X203544D02*
X201181D01*
G01X183858Y322244D02*
X181496D01*
G01X193701D02*
X191339D01*
G01X203544D02*
X201181D01*
G01X209646Y321949D02*
X207284D01*
G01Y321850D02*
X209646D01*
G01X201772Y321456D02*
X198032D01*
G01X180512Y321358D02*
X204528D01*
G01X175394Y320866D02*
X176575D01*
G01X198032Y320472D02*
X183268D01*
G01X201575Y320275D02*
X183465D01*
G01X208465Y319882D02*
X209646D01*
G01X196848Y319291D02*
X188192D01*
G01X209646Y321850D02*
X207284Y327756D01*
G01X200000Y300953D02*
X200312Y300452D01*
G01X184728Y325532D02*
X185040Y325030D01*
G01X200394Y301207D02*
X200722Y300716D01*
G01X184318Y325268D02*
X184646Y324777D01*
G01X177756Y317323D02*
X175394D01*
G01X209646D02*
X207284D01*
G01X177756Y317126D02*
X175394D01*
G01X209646D02*
X207284D01*
G01X204921Y316732D02*
X207284D01*
G01X177756D02*
X180118D01*
G01X207284Y315945D02*
X177756D01*
G01X183465Y315354D02*
X201575D01*
G01X206103Y314567D02*
X209646D01*
G01X178937D02*
X175394D01*
G01X172343Y313779D02*
X212697D01*
G01X172343Y312205D02*
X212697D01*
G01X206103Y311417D02*
X209646D01*
G01X175394D02*
X178937D01*
G01X201575Y310630D02*
X183465D01*
G01X207284Y310039D02*
X177756D01*
G01X204921Y309252D02*
X207284D01*
G01X180118D02*
X177756D01*
G01Y308858D02*
X175394D01*
G01X209646D02*
X207284D01*
G01X177756Y308661D02*
X175394D01*
G01X209646D02*
X207284D01*
G01X196848Y306693D02*
X188192D01*
G01X208465Y306102D02*
X209646D01*
G01X183465Y305708D02*
X201575D01*
G01X198032Y305512D02*
X183268D01*
G01X175394Y305118D02*
X176575D01*
G01X204528Y304626D02*
X180512D01*
G01X201772Y304527D02*
X198032D01*
G01X209646Y304134D02*
X207284D01*
G01Y304035D02*
X209646D01*
G01X183858Y303740D02*
X181496D01*
G01X193701D02*
X191339D01*
G01X203544D02*
X201181D01*
G01X183858Y303607D02*
X181496D01*
G01X193701D02*
X191339D01*
G01X203544D02*
X201181D01*
G01X177756Y303149D02*
X175394D01*
G01X177756Y303051D02*
X175394D01*
G01X202971Y335769D02*
X203181Y335810D01*
G01Y335605D02*
X202971Y335564D01*
G01Y333760D02*
X203139Y333801D01*
G01X203935Y333472D02*
X203977Y333308D01*
G01X203725Y333390D02*
X203767Y333226D01*
G01X202804Y335236D02*
X202846Y335072D01*
G01X202678D02*
X202636Y335236D01*
G01X202888Y332898D02*
X202846Y333062D01*
G01X202678Y332898D02*
X202636Y333062D01*
G01X183858Y302590D02*
X181496D01*
G01X193701D02*
X191339D01*
G01X203544D02*
X201181D01*
G01X183858Y302559D02*
X181496D01*
G01X193701D02*
X191339D01*
G01X203544D02*
X201181D01*
G01Y302507D02*
X203544D01*
G01X191339D02*
X193701D01*
G01X181496D02*
X183858D01*
G01Y302476D02*
X181496D01*
G01X193701D02*
X191339D01*
G01X203544D02*
X201181D01*
G01X180512Y301673D02*
X204528D01*
G01X183858Y301511D02*
X181496D01*
G01X193701D02*
X191339D01*
G01X203544D02*
X201181D01*
G01Y301378D02*
X203544D01*
G01X191339D02*
X193701D01*
G01X181496D02*
X183858D01*
G01X177756Y300787D02*
X175000D01*
G01X210040D02*
X207284D01*
G01X204921Y300590D02*
X180118D01*
G01X212697Y313779D02*
Y312205D01*
G01X211713Y313779D02*
Y312205D01*
G01X211516D02*
Y313779D01*
G01X209646Y304134D02*
Y321850D01*
G01Y327756D02*
Y321949D01*
G01X208465Y306102D02*
Y319882D01*
G01X208268Y313779D02*
Y312205D01*
G01X208200D02*
Y313779D01*
G01X207087Y312205D02*
Y313779D01*
G01X206103Y314567D02*
Y311417D01*
G01X204921Y315945D02*
Y327756D01*
G01X204647Y332693D02*
Y332488D01*
G01X204528Y321358D02*
Y324311D01*
G01Y301673D02*
Y304626D01*
G01X204134D02*
Y301673D01*
G01Y324311D02*
Y321358D01*
G01Y327756D02*
Y325394D01*
G01X203977Y334334D02*
Y334129D01*
G01Y333308D02*
Y333062D01*
G01Y334867D02*
Y334662D01*
G01Y335810D02*
Y335605D01*
G01Y336630D02*
Y336384D01*
G01X203767Y333226D02*
Y333062D01*
G01X203544Y322244D02*
Y324606D01*
G01Y303740D02*
Y301378D01*
G01X202953Y303937D02*
Y302362D01*
G01Y323622D02*
Y322047D01*
G01X202846Y333062D02*
Y333308D01*
G01X202636Y334662D02*
Y334867D01*
G01Y335236D02*
Y335400D01*
G01Y334129D02*
Y334334D01*
G01Y333062D02*
Y333308D01*
G01Y332488D02*
Y332693D01*
G01X202218Y334334D02*
Y334129D01*
G01X202008Y336384D02*
Y336630D01*
G01Y334129D02*
Y334334D01*
G01X201772Y303740D02*
Y302559D01*
G01Y321456D02*
Y304527D01*
G01Y323425D02*
Y322244D01*
G01X201575Y305708D02*
Y320275D01*
G01X201181Y322244D02*
Y324606D01*
G01Y303740D02*
Y301378D01*
G01X198032Y305512D02*
Y304527D01*
G01Y321456D02*
Y320472D01*
G01X197244Y306800D02*
Y305708D01*
G01Y320275D02*
Y319184D01*
G01X196851Y325032D02*
Y326487D01*
G01Y299497D02*
Y300952D01*
G01X193701Y322244D02*
Y324606D01*
G01Y303740D02*
Y301378D01*
G01X193504Y321260D02*
Y312795D01*
G01X193110Y322244D02*
Y323425D01*
G01Y302559D02*
Y303740D01*
G01X191929D02*
Y302559D01*
G01Y323425D02*
Y322244D01*
G01X191536Y321260D02*
Y312795D01*
G01X191339Y322244D02*
Y324606D01*
G01Y303740D02*
Y301378D01*
G01X188189Y300952D02*
Y299497D01*
G01Y326487D02*
Y325032D01*
G01X187795Y319184D02*
Y320275D01*
G01Y306800D02*
Y305708D01*
G01X183858Y322244D02*
Y324606D01*
G01Y303740D02*
Y301378D01*
G01X183465Y320275D02*
Y305708D01*
G01X183268Y322244D02*
Y323425D01*
G01Y302559D02*
Y303740D01*
G01Y320472D02*
Y305512D01*
G01X182087Y303740D02*
Y302559D01*
G01Y323425D02*
Y322244D01*
G01X181496D02*
Y324606D01*
G01Y303740D02*
Y301378D01*
G01X180906Y327756D02*
Y325394D01*
G01X180512Y304626D02*
Y301673D01*
G01Y324311D02*
Y321358D01*
G01X180118Y315945D02*
Y327756D01*
G01X178937Y311417D02*
Y314567D01*
G01X177953Y313779D02*
Y312205D01*
G01X176839Y313779D02*
Y312205D01*
G01X176772D02*
Y313779D01*
G01X176575Y305118D02*
Y320866D01*
G01X173524Y313779D02*
Y312205D01*
G01X173327D02*
Y313779D01*
G01X172343Y312205D02*
Y313779D01*
G01X203977Y333062D02*
X203935Y332898D01*
G01X203767Y333062D02*
X203725Y332898D01*
G01X202636Y333308D02*
X202678Y333472D01*
G01X202846Y335400D02*
X202804Y335236D01*
G01X202636Y335400D02*
X202678Y335523D01*
G01X203935Y332898D02*
X203893Y332816D01*
G01X200000Y325030D02*
X200312Y325532D01*
G01X185040Y300953D02*
X184728Y300452D01*
G01X202846Y333308D02*
X202930Y333472D01*
G01X202888Y335482D02*
X202846Y335400D01*
G01X203725Y332898D02*
X203642Y332775D01*
G01X202678Y333472D02*
X202762Y333596D01*
G01X202678Y335523D02*
X202762Y335646D01*
G01X184646Y301207D02*
X184318Y300716D01*
G01X200722Y325268D02*
X200394Y324777D01*
G01X202953Y302362D02*
X202264Y301673D01*
G01X203893Y332816D02*
X203809Y332734D01*
G01X202953Y322047D02*
X202264Y321358D01*
G01X202762Y333596D02*
X202888Y333719D01*
G01X202971Y335564D02*
X202888Y335482D01*
G01X202762Y335646D02*
X202846Y335728D01*
G01X209646Y311417D02*
X207284Y310039D01*
G01X177756Y315945D02*
X175394Y314567D01*
G01X203642Y332775D02*
X203516Y332693D01*
G01X202930Y333472D02*
X203055Y333555D01*
G01X203809Y332734D02*
X203725Y332693D01*
G01X202888Y333719D02*
X202971Y333760D01*
G01X203055Y333555D02*
X203181Y333596D01*
G01X202846Y335728D02*
X202971Y335769D01*
G01X193603Y393701D02*
G03I-2658J0D01*
G01X201634Y387795D02*
G03X199666Y389764I-1969J0D01*
G01X155703Y523137D02*
G03X161271Y517570I2784J-2783D01*
G01X160236Y527671D02*
X155703Y523137D01*
G01X166957Y523256D02*
G03X168110Y526040I-2785J2784D01*
G01Y637713D02*
Y526040D01*
G01X160236Y634876D02*
Y527671D01*
G01X156502Y676478D02*
G03X148425Y665272I3735J-11206D01*
G01Y647326D02*
G03X156502Y636120I11812J0D01*
G01X160236Y634876D02*
X156501Y636121D01*
G01X160236Y709842D02*
Y677722D01*
G01X148425Y665272D02*
Y647326D01*
G01X160236Y677722D02*
X156501Y676477D01*
G01X165418Y671150D02*
G03X168110Y674885I-1245J3735D01*
G01X158992Y669007D02*
G03X156299Y665272I1244J-3735D01*
G01X168110Y637713D02*
G03X165418Y641448I-3937J0D01*
G01X156299Y647326D02*
G03X158992Y643591I3937J0D01*
G01X165418Y641448D02*
X158991Y643591D01*
G01X168110Y738976D02*
Y674885D01*
G01X156299Y665272D02*
Y647326D01*
G01X165418Y671150D02*
X158991Y669007D01*
G01X160236Y735039D02*
G03X168110I3937J0D01*
G01Y709842D02*
G03X160236I-3937J0D01*
G01Y738976D02*
G03X156299Y742913I-3937J0D01*
G01X160236Y738976D02*
Y735039D01*
G01X202364Y734322D02*
G03Y738338I0J2008D01*
G01D02*
G03Y734322I0J-2008D01*
G01X208664Y732430D02*
X196064D01*
G01X208664Y740230D02*
Y732430D01*
G01X196064Y740230D02*
X208664D01*
G01X196064Y732430D02*
Y740230D01*
G01X209764Y731330D02*
X194964D01*
G01X209764Y741330D02*
Y731330D01*
G01X194964Y741330D02*
X209764D01*
G01X194964Y731330D02*
Y741330D01*
G01X172047Y742913D02*
G03X168110Y738976I0J-3937D01*
G01X228740Y742913D02*
X172047D01*
G01X294359Y-354220D02*
Y-371543D01*
G01X236614Y-14567D02*
X244488D01*
G01X236614D02*
G03X232677Y-18504I0J-3937D01*
G01X248425D02*
G03X244488Y-14567I-3937J0D01*
G01X278739Y-17787D02*
G03Y-21803I0J-2008D01*
G01D02*
G03Y-17787I0J2008D01*
G01X272439Y-15895D02*
X285039D01*
G01X272439Y-23695D02*
Y-15895D01*
G01X285039Y-23695D02*
X272439D01*
G01X285039Y-15895D02*
Y-23695D01*
G01X271339Y-14795D02*
X286139D01*
G01X271339Y-24795D02*
Y-14795D01*
G01X286139Y-24795D02*
X271339D01*
G01X286139Y-14795D02*
Y-24795D01*
G01X248425Y-22441D02*
G03X252362Y-26378I3937J0D01*
G01D02*
X309055D01*
G01X248425Y112921D02*
Y-22441D01*
G01X293954Y-40010D02*
X330154D01*
G01X278739Y-24795D02*
X293954Y-40010D01*
G01X285809Y-28330D02*
X278739Y-24795D01*
G01D02*
X282274Y-31865D01*
G01D02*
X285809Y-28330D01*
G01X228740Y-26378D02*
G03X232677Y-22441I0J3937D01*
G01D02*
Y178669D01*
G01X236614Y16929D02*
X244488D01*
G01X232677Y20866D02*
G03X236614Y16929I3937J0D01*
G01X244488D02*
G03X248425Y20866I0J3937D01*
G01X246249Y145762D02*
G03X248425Y149283I-1761J3521D01*
G01Y112921D02*
G03X246249Y116442I-3937J0D01*
G01X242727Y144001D02*
G03X240551Y140480I1761J-3521D01*
G01Y121724D02*
G03X242727Y118203I3937J0D01*
G01X240551Y140480D02*
Y121724D01*
G01X242728Y118203D02*
X246249Y116442D01*
G01X242728Y144001D02*
X246249Y145762D01*
G01X248425Y350394D02*
Y149283D01*
G01X234853Y182190D02*
G03X232677Y178669I1761J-3521D01*
G01Y215031D02*
G03X234853Y211510I3937J0D01*
G01X238375Y183951D02*
G03X240551Y187472I-1761J3521D01*
G01Y206228D02*
G03X238375Y209749I-3937J0D01*
G01X240551Y187472D02*
Y206228D01*
G01X232677Y215031D02*
Y350394D01*
G01X238375Y209749D02*
X234854Y211510D01*
G01X238375Y183951D02*
X234854Y182190D01*
G01X273986Y362205D02*
G03Y354331I0J-3937D01*
G01X255876D02*
G03Y362205I0J3937D01*
G01X236614Y374016D02*
X244488D01*
G01X236614D02*
G03X232677Y370079I0J-3937D01*
G01X248425D02*
G03X244488Y374016I-3937J0D01*
G01X236614Y342519D02*
X244488D01*
G01X236614Y311023D02*
X244488D01*
G01X236614D02*
G03X232677Y307086I0J-3937D01*
G01Y346456D02*
G03X236614Y342519I3937J0D01*
G01X244488D02*
G03X248425Y346456I0J3937D01*
G01Y307086D02*
G03X244488Y311023I-3937J0D01*
G01X278739Y370796D02*
G03Y366780I0J-2008D01*
G01D02*
G03Y370796I0J2008D01*
G01X272439Y372688D02*
X285039D01*
G01X272439Y364888D02*
Y372688D01*
G01X285039Y364888D02*
X272439D01*
G01X285039Y372688D02*
Y364888D01*
G01X271339Y373788D02*
X286139D01*
G01X271339Y363788D02*
Y373788D01*
G01X286139Y363788D02*
X271339D01*
G01X286139Y373788D02*
Y363788D01*
G01X248425Y366142D02*
G03X252362Y362205I3937J0D01*
G01D02*
X309055D01*
G01X248425Y501504D02*
Y366142D01*
G01X228740Y362205D02*
G03X232677Y366142I0J3937D01*
G01D02*
Y567252D01*
G01X279469Y352362D02*
G03X277500Y354331I-1969J0D01*
G01X252362D02*
G03X248425Y350394I0J-3937D01*
G01X292815Y322834D02*
G03I-2657J0D01*
G01X279469Y328740D02*
G03X281437Y326771I1969J0D01*
G01X279469Y328740D02*
Y352362D01*
G01X448091Y326771D02*
X281437D01*
G01X277500Y354331D02*
X252362D01*
G01X232677Y350394D02*
G03X228740Y354331I-3937J0D01*
G01X236614Y405512D02*
X244488D01*
G01X232677Y409449D02*
G03X236614Y405512I3937J0D01*
G01X244488D02*
G03X248425Y409449I0J3937D01*
G01Y501504D02*
G03X246249Y505025I-3937J0D01*
G01X240551Y510307D02*
G03X242727Y506786I3937J0D01*
G01X240551Y529063D02*
Y510307D01*
G01X242728Y506786D02*
X246249Y505025D01*
G01X240551Y598748D02*
Y783037D01*
G01X246249Y534345D02*
G03X248425Y537866I-1761J3521D01*
G01X242727Y532584D02*
G03X240551Y529063I1761J-3521D01*
G01X248425Y738976D02*
Y537866D01*
G01X242728Y532584D02*
X246249Y534345D01*
G01X234853Y570773D02*
G03X232677Y567252I1761J-3521D01*
G01Y603614D02*
G03X234853Y600093I3937J0D01*
G01X238375Y572534D02*
G03X240551Y576055I-1761J3521D01*
G01Y594811D02*
G03X238375Y598332I-3937J0D01*
G01X240551Y576055D02*
Y594811D01*
G01X238375Y598332D02*
X234854Y600093D01*
G01X238375Y572534D02*
X234854Y570773D01*
G01X232677Y603614D02*
Y738976D01*
G01X236614Y731102D02*
X244488D01*
G01X236614Y699606D02*
X244488D01*
G01X236614D02*
G03X232677Y695669I0J-3937D01*
G01Y735039D02*
G03X236614Y731102I3937J0D01*
G01X244488D02*
G03X248425Y735039I0J3937D01*
G01Y695669D02*
G03X244488Y699606I-3937J0D01*
G01X279469Y740945D02*
G03X277500Y742913I-1968J0D01*
G01X252362D02*
G03X248425Y738976I0J-3937D01*
G01X292815Y711417D02*
G03I-2657J0D01*
G01X279469Y717323D02*
G03X281437Y715354I1969J0D01*
G01X279469Y717323D02*
Y740945D01*
G01X448091Y715354D02*
X281437D01*
G01X277500Y742913D02*
X252362D01*
G01X232677Y738976D02*
G03X228740Y742913I-3937J0D01*
G01X294359Y1006410D02*
Y989087D01*
G01X369811Y-1413D02*
G03I-4291J0D01*
G01X320866Y-18504D02*
G03X312992I-3937J0D01*
G01X320866Y-22441D02*
G03X324803Y-26378I3937J0D01*
G01X404725D02*
X324803D01*
G01X320866Y-22441D02*
Y-18504D01*
G01X309055Y-26378D02*
G03X312992Y-22441I0J3937D01*
G01D02*
Y41650D01*
G01Y6693D02*
G03X320866I3937J0D01*
G01X324600Y40057D02*
G03X332677Y51263I-3735J11206D01*
G01Y69209D02*
G03X324600Y80415I-11812J0D01*
G01X320866Y6693D02*
Y38813D01*
G01X332677Y51263D02*
Y69209D01*
G01X320866Y38813D02*
X324601Y40058D01*
G01X315685Y45385D02*
G03X312992Y41650I1244J-3735D01*
G01X322111Y47528D02*
G03X324803Y51263I-1245J3735D01*
G01Y69209D02*
G03X322111Y72944I-3937J0D01*
G01X324803Y51263D02*
Y69209D01*
G01X315684Y45385D02*
X322111Y47528D01*
G01X320866Y81659D02*
X324601Y80414D01*
G01X320866Y81659D02*
Y188864D01*
G01X312992Y78822D02*
G03X315685Y75087I3937J0D01*
G01X315684D02*
X322111Y72944D01*
G01X312992Y78822D02*
Y190495D01*
G01X370897Y190776D02*
G03I-4291J0D01*
G01X337649Y216782D02*
G03X343217Y211214I2784J-2784D01*
G01X325400Y193398D02*
G03X319832Y198965I-2784J2784D01*
G01X343217Y211214D02*
X347750Y215748D01*
G01X320866Y188864D02*
X325400Y193398D01*
G01X347750Y215748D02*
X381778D01*
G01X314145Y193279D02*
G03X312992Y190495I2785J-2784D01*
G01X346119Y223622D02*
G03X343335Y222469I0J-3938D01*
G01X314145Y193279D02*
X343335Y222469D01*
G01X375788Y249212D02*
G03I-11024J0D01*
G01X346119Y223622D02*
X383409D01*
G01X320866Y370079D02*
G03X312992I-3937J0D01*
G01X320866Y366142D02*
G03X324803Y362205I3937J0D01*
G01X404725D02*
X324803D01*
G01X320866Y366142D02*
Y370079D01*
G01X309055Y362205D02*
G03X312992Y366142I0J3937D01*
G01D02*
Y430233D01*
G01X369811Y387169D02*
G03I-4291J0D01*
G01X312992Y395275D02*
G03X320866I3937J0D01*
G01X324600Y428640D02*
G03X332677Y439845I-3734J11205D01*
G01X320866Y395275D02*
Y427395D01*
G01X332677Y439845D02*
Y457792D01*
G01X320866Y427395D02*
X324601Y428640D01*
G01X315685Y433968D02*
G03X312992Y430233I1244J-3735D01*
G01X322111Y436110D02*
G03X324803Y439845I-1245J3735D01*
G01D02*
Y457792D01*
G01X315684Y433968D02*
X322111Y436110D01*
G01X332677Y457792D02*
G03X324600Y468997I-11811J0D01*
G01X320866Y470242D02*
X324601Y468997D01*
G01X320866Y470242D02*
Y577447D01*
G01X312992Y467404D02*
G03X315685Y463669I3937J0D01*
G01X324803Y457792D02*
G03X322111Y461527I-3937J0D01*
G01X315684Y463669D02*
X322111Y461527D01*
G01X312992Y467404D02*
Y579078D01*
G01X370897Y579359D02*
G03I-4291J0D01*
G01X337649Y605365D02*
G03X343217Y599797I2784J-2784D01*
G01X325400Y581980D02*
G03X319832Y587548I-2784J2784D01*
G01X343217Y599797D02*
X347750Y604331D01*
G01X320866Y577447D02*
X325400Y581980D01*
G01X314145Y581862D02*
G03X312992Y579078I2785J-2784D01*
G01X314145Y581862D02*
X343335Y611051D01*
G01X347750Y604331D02*
X381778D01*
G01X346119Y612205D02*
G03X343335Y611051I1J-3937D01*
G01X375788Y637795D02*
G03I-11024J0D01*
G01X346119Y612205D02*
X383409D01*
G01X416536Y-18504D02*
G03X408662I-3937J0D01*
G01X404725Y-26378D02*
G03X408662Y-22441I0J3937D01*
G01Y-18504D02*
Y-22441D01*
G01X416536D02*
G03X420473Y-26378I3937J0D01*
G01D02*
X477166D01*
G01X416536Y41650D02*
Y-22441D01*
G01X408662Y6693D02*
G03X416536I3937J0D01*
G01X396851Y51263D02*
G03X404928Y40057I11812J0D01*
G01Y80415D02*
G03X396851Y69209I3735J-11206D01*
G01X404927Y40058D02*
X408662Y38813D01*
G01X396851Y69209D02*
Y51263D01*
G01X408662Y38813D02*
Y6693D01*
G01X416536Y41650D02*
G03X413843Y45385I-3937J0D01*
G01X404725Y51263D02*
G03X407417Y47528I3937J0D01*
G01Y72944D02*
G03X404725Y69209I1245J-3735D01*
G01X407417Y47528D02*
X413844Y45385D01*
G01X404725Y69209D02*
Y51263D01*
G01X408662Y188864D02*
Y81659D01*
G01X404927Y80414D02*
X408662Y81659D01*
G01X413843Y75087D02*
G03X416536Y78822I-1244J3735D01*
G01Y190495D02*
Y78822D01*
G01X407417Y72944D02*
X413844Y75087D01*
G01X409696Y198965D02*
G03X404128Y193398I-2784J-2783D01*
G01X386311Y211214D02*
G03X391879Y216782I2784J2784D01*
G01X386311Y211214D02*
X381778Y215748D01*
G01X408662Y188864D02*
X404128Y193398D01*
G01X386193Y222469D02*
G03X383409Y223622I-2784J-2785D01*
G01X416536Y190495D02*
G03X415383Y193279I-3938J0D01*
G01D02*
X386193Y222469D01*
G01X416536Y370079D02*
G03X408662I-3937J0D01*
G01X404725Y362205D02*
G03X408662Y366142I0J3937D01*
G01Y370079D02*
Y366142D01*
G01X416536D02*
G03X420473Y362205I3937J0D01*
G01D02*
X477166D01*
G01X416536Y430233D02*
Y366142D01*
G01X442028Y322834D02*
G03I-2658J0D01*
G01X448091Y326771D02*
G03X450059Y328740I0J1968D01*
G01X452028Y354331D02*
G03X450059Y352362I0J-1969D01*
G01D02*
Y328740D01*
G01X408662Y395275D02*
G03X416536I3937J0D01*
G01X396851Y439845D02*
G03X404928Y428640I11811J0D01*
G01X404927D02*
X408662Y427395D01*
G01X396851Y457792D02*
Y439845D01*
G01X408662Y427395D02*
Y395275D01*
G01X416536Y430233D02*
G03X413843Y433968I-3937J0D01*
G01X404725Y439845D02*
G03X407417Y436110I3937J0D01*
G01D02*
X413844Y433968D01*
G01X404725Y457792D02*
Y439845D01*
G01X404928Y468997D02*
G03X396851Y457792I3734J-11205D01*
G01X408662Y577447D02*
Y470242D01*
G01X404927Y468997D02*
X408662Y470242D01*
G01X413843Y463669D02*
G03X416536Y467404I-1244J3735D01*
G01X407417Y461527D02*
G03X404725Y457792I1245J-3735D01*
G01X416536Y579078D02*
Y467404D01*
G01X407417Y461527D02*
X413844Y463669D01*
G01X409696Y587548D02*
G03X404128Y581980I-2784J-2784D01*
G01X386311Y599797D02*
G03X391879Y605365I2784J2784D01*
G01X386311Y599797D02*
X381778Y604331D01*
G01X408662Y577447D02*
X404128Y581980D01*
G01X416536Y579078D02*
G03X415383Y581862I-3938J0D01*
G01D02*
X386193Y611051D01*
G01D02*
G03X383409Y612205I-2785J-2783D01*
G01X442028Y711417D02*
G03I-2658J0D01*
G01X448091Y715354D02*
G03X450059Y717323I0J1968D01*
G01X452028Y742913D02*
G03X450059Y740945I0J-1969D01*
G01D02*
Y717323D01*
G01X467587Y-354220D02*
Y-371543D01*
G01X488977Y-22441D02*
G03X492914Y-26378I3937J0D01*
G01X497599D02*
G03X512599Y-11378I0J15000D01*
G01X488977Y-18504D02*
G03X481103I-3937J0D01*
G01X492914Y-26378D02*
X497599D01*
G01X512599Y-11378D02*
Y455139D01*
G01X488977Y-22441D02*
Y-18504D01*
G01X477166Y-26378D02*
G03X481103Y-22441I0J3937D01*
G01D02*
Y112517D01*
G01X493553Y2518D02*
G03I-4000J0D01*
G01X491553D02*
G03I-2000J0D01*
G01X481103Y20866D02*
G03X488977I3937J0D01*
G01D02*
Y109679D01*
G01X492711Y110924D02*
G03X500788Y122129I-3734J11205D01*
G01Y140076D02*
G03X492711Y151281I-11811J0D01*
G01X488977Y109679D02*
X492712Y110924D01*
G01X500788Y122129D02*
Y140076D01*
G01X483795Y116252D02*
G03X481103Y112517I1245J-3735D01*
G01Y149688D02*
G03X483795Y145953I3937J0D01*
G01X490221Y118394D02*
G03X492914Y122129I-1244J3735D01*
G01Y140076D02*
G03X490221Y143811I-3937J0D01*
G01X483795Y145953D02*
X490222Y143811D01*
G01X483795Y116251D02*
X490222Y118394D01*
G01X492914Y122129D02*
Y140076D01*
G01X488977Y152525D02*
X492712Y151280D01*
G01X488977Y152525D02*
Y307086D01*
G01X481103Y149688D02*
Y350394D01*
G01X511199Y270106D02*
X513999D01*
G01X511199Y301601D02*
X513999D01*
G01X511199Y333096D02*
X513999D01*
G01X511199Y364591D02*
X513999D01*
G01X488977Y307086D02*
G03X481103I-3937J0D01*
G01Y346456D02*
G03X488977I3937J0D01*
G01Y370079D02*
G03X481103I-3937J0D01*
G01X488977Y346456D02*
Y370079D01*
G01X477166Y362205D02*
G03X481103Y366142I0J3937D01*
G01D02*
Y501099D01*
G01Y350394D02*
G03X477166Y354331I-3937J0D01*
G01D02*
X452028D01*
G01X511199Y396086D02*
X513999D01*
G01X511199Y427581D02*
X513999D01*
G01X481103Y409449D02*
G03X488977I3937J0D01*
G01D02*
Y498262D01*
G01X512599Y463013D02*
Y727913D01*
G01Y459076D02*
Y458683D01*
G01Y459076D02*
Y459470D01*
G01X512107Y459076D02*
X513091D01*
G01X512599Y463013D02*
G03Y455139I0J-3937D01*
G01X492711Y499506D02*
G03X500788Y510711I-3734J11205D01*
G01X488977Y498262D02*
X492712Y499507D01*
G01X500788Y510711D02*
Y528658D01*
G01X483795Y504834D02*
G03X481103Y501099I1245J-3735D01*
G01X490221Y506976D02*
G03X492914Y510711I-1244J3735D01*
G01X483795Y504834D02*
X490222Y506976D01*
G01X492914Y510711D02*
Y528658D01*
G01Y532595D02*
Y783037D01*
G01X500788Y528658D02*
G03X492711Y539863I-11811J0D01*
G01X488977Y541108D02*
X492712Y539863D01*
G01X488977Y541108D02*
Y695669D01*
G01X481103Y538271D02*
G03X483795Y534535I3937J-1D01*
G01X492914Y528658D02*
G03X490221Y532393I-3937J0D01*
G01X483795Y534536D02*
X490222Y532393D01*
G01X481103Y538271D02*
Y738976D01*
G01X512599Y731850D02*
Y781913D01*
G01X499107Y713716D02*
G03I-4291J0D01*
G01X492914Y742913D02*
G03X488977Y738976I0J-3937D01*
G01X512599Y727913D02*
G03X497599Y742913I-15000J0D01*
G01X488977Y695669D02*
G03X481103I-3937J0D01*
G01Y735039D02*
G03X488977I3937J0D01*
G01X492914Y742913D02*
X497599D01*
G01X488977Y735039D02*
Y738976D01*
G01X481103D02*
G03X477166Y742913I-3937J0D01*
G01D02*
X452028D01*
G01X467587Y1006410D02*
Y989087D01*
G01X601036Y202169D02*
X601524Y201447D01*
G01X601036D02*
Y202169D01*
G01X601524Y201447D02*
X601036D01*
G01X594703Y209386D02*
X595190Y208665D01*
G01X593728Y210108D02*
X594703Y209386D01*
G01X592754D02*
X593728Y210108D01*
G01X592267Y208665D02*
X592754Y209386D01*
G01X591780Y207221D02*
X592267Y208665D01*
G01X591780Y204334D02*
Y207221D01*
G01X592267Y202890D02*
X591780Y204334D01*
G01X592754Y202169D02*
X592267Y202890D01*
G01X593728Y201447D02*
X592754Y202169D01*
G01X594703D02*
X593728Y201447D01*
G01X595190Y202890D02*
X594703Y202169D01*
G01X595677Y204334D02*
X595190Y202890D01*
G01Y205777D02*
X595677Y204334D01*
G01X593728Y206499D02*
X595190Y205777D01*
G01X592267D02*
X593728Y206499D01*
G01X591780Y204334D02*
X592267Y205777D01*
G01X594703Y228546D02*
X593728Y227825D01*
G01X595190Y229268D02*
X594703Y228546D01*
G01X595677Y230712D02*
X595190Y229268D01*
G01X595677Y233599D02*
Y230712D01*
G01X595190Y235043D02*
X595677Y233599D01*
G01X594703Y235764D02*
X595190Y235043D01*
G01X593728Y236486D02*
X594703Y235764D01*
G01X592754D02*
X593728Y236486D01*
G01X592267Y235043D02*
X592754Y235764D01*
G01X591780Y233599D02*
X592267Y235043D01*
G01X591780Y230712D02*
Y233599D01*
G01X592267Y229268D02*
X591780Y230712D01*
G01X592754Y228546D02*
X592267Y229268D01*
G01X593728Y227825D02*
X592754Y228546D01*
G01X601036D02*
X601524Y227825D01*
G01X601036D02*
Y228546D01*
G01X601524Y227825D02*
X601036D01*
G01X594703Y307287D02*
X593728Y306565D01*
G01X595190Y308008D02*
X594703Y307287D01*
G01X595677Y309452D02*
X595190Y308008D01*
G01X595677Y312339D02*
Y309452D01*
G01X595190Y313783D02*
X595677Y312339D01*
G01X594703Y314504D02*
X595190Y313783D01*
G01X593728Y315226D02*
X594703Y314504D01*
G01X592754D02*
X593728Y315226D01*
G01X592267Y313783D02*
X592754Y314504D01*
G01X591780Y312339D02*
X592267Y313783D01*
G01X591780Y309452D02*
Y312339D01*
G01X592267Y308008D02*
X591780Y309452D01*
G01X592754Y307287D02*
X592267Y308008D01*
G01X593728Y306565D02*
X592754Y307287D01*
G01X594703Y340095D02*
X595190Y339373D01*
G01X593728Y340817D02*
X594703Y340095D01*
G01X592754D02*
X593728Y340817D01*
G01X592267Y339373D02*
X592754Y340095D01*
G01X591780Y337930D02*
X592267Y339373D01*
G01X591780Y335043D02*
Y337930D01*
G01X592267Y333599D02*
X591780Y335043D01*
G01X592754Y332877D02*
X592267Y333599D01*
G01X593728Y332155D02*
X592754Y332877D01*
G01X594703D02*
X593728Y332155D01*
G01X595190Y333599D02*
X594703Y332877D01*
G01X595677Y335043D02*
X595190Y333599D01*
G01Y336486D02*
X595677Y335043D01*
G01X593728Y337208D02*
X595190Y336486D01*
G01X592267D02*
X593728Y337208D01*
G01X591780Y335043D02*
X592267Y336486D01*
G01X583984Y332155D02*
X587882D01*
G01X584471Y334321D02*
X583984Y332155D01*
G01X585446Y335764D02*
X584471Y334321D01*
G01X586420Y336486D02*
X585446Y335764D01*
G01X587395Y337208D02*
X586420Y336486D01*
G01X587882Y337930D02*
X587395Y337208D01*
G01X587882Y339373D02*
Y337930D01*
G01X587395Y340095D02*
X587882Y339373D01*
G01X586420Y340817D02*
X587395Y340095D01*
G01X585446Y340817D02*
X586420D01*
G01X584471Y340095D02*
X585446Y340817D01*
G01X583984Y339373D02*
X584471Y340095D01*
G01X583984Y306565D02*
X587882D01*
G01X584471Y308730D02*
X583984Y306565D01*
G01X585446Y310174D02*
X584471Y308730D01*
G01X586420Y310896D02*
X585446Y310174D01*
G01X587395Y311617D02*
X586420Y310896D01*
G01X587882Y312339D02*
X587395Y311617D01*
G01X587882Y313783D02*
Y312339D01*
G01X587395Y314504D02*
X587882Y313783D01*
G01X586420Y315226D02*
X587395Y314504D01*
G01X585446Y315226D02*
X586420D01*
G01X584471Y314504D02*
X585446Y315226D01*
G01X583984Y313783D02*
X584471Y314504D01*
G01X601036Y307287D02*
X601524Y306565D01*
G01X601036D02*
Y307287D01*
G01X601524Y306565D02*
X601036D01*
G01Y332877D02*
X601524Y332155D01*
G01X601036D02*
Y332877D01*
G01X601524Y332155D02*
X601036D01*
G01X584959Y582877D02*
X584471Y583599D01*
G01X585933Y582155D02*
X584959Y582877D01*
G01X586907D02*
X585933Y582155D01*
G01X587395Y583599D02*
X586907Y582877D01*
G01X587882Y585043D02*
X587395Y583599D01*
G01X587882Y587930D02*
Y585043D01*
G01X587395Y589373D02*
X587882Y587930D01*
G01X586907Y590095D02*
X587395Y589373D01*
G01X585933Y590817D02*
X586907Y590095D01*
G01X584959D02*
X585933Y590817D01*
G01X584471Y589373D02*
X584959Y590095D01*
G01X583984Y587930D02*
X584471Y589373D01*
G01Y586486D02*
X583984Y587930D01*
G01X585933Y585764D02*
X584471Y586486D01*
G01X587395D02*
X585933Y585764D01*
G01X587882Y587930D02*
X587395Y586486D01*
G01X594703Y582877D02*
X593728Y582155D01*
G01X595190Y583599D02*
X594703Y582877D01*
G01X595677Y585043D02*
X595190Y583599D01*
G01X595677Y587930D02*
Y585043D01*
G01X595190Y589373D02*
X595677Y587930D01*
G01X594703Y590095D02*
X595190Y589373D01*
G01X593728Y590817D02*
X594703Y590095D01*
G01X592754D02*
X593728Y590817D01*
G01X592267Y589373D02*
X592754Y590095D01*
G01X591780Y587930D02*
X592267Y589373D01*
G01X591780Y585043D02*
Y587930D01*
G01X592267Y583599D02*
X591780Y585043D01*
G01X592754Y582877D02*
X592267Y583599D01*
G01X593728Y582155D02*
X592754Y582877D01*
G01X601036D02*
X601524Y582155D01*
G01X601036D02*
Y582877D01*
G01X601524Y582155D02*
X601036D01*
G01X645788Y-338472D02*
Y-82566D01*
G01Y-338472D02*
X1719319D01*
G01X640815Y-354220D02*
Y-371543D01*
G01X645788Y-233082D02*
X1177015D01*
G01X1719319Y-278208D02*
X645788D01*
G01Y-187956D02*
X1719319D01*
G01X645788Y-82566D02*
X1719319Y-82686D01*
G01X645788Y-142830D02*
X1719319D01*
G01X669306Y139936D02*
X670028Y140423D01*
G01Y139936D02*
X669306D01*
G01X670028Y140423D02*
Y139936D01*
G01X662088Y147244D02*
X661366Y148218D01*
G01X662810Y146757D02*
X662088Y147244D01*
G01X664253Y146270D02*
X662810Y146757D01*
G01X667140Y146270D02*
X664253D01*
G01X668584Y146757D02*
X667140Y146270D01*
G01X669306Y147244D02*
X668584Y146757D01*
G01X670028Y148218D02*
X669306Y147244D01*
G01Y133602D02*
X670028Y132628D01*
G01X668584Y134089D02*
X669306Y133602D01*
G01X667140Y134577D02*
X668584Y134089D01*
G01X664253Y134577D02*
X667140D01*
G01X662810Y134089D02*
X664253Y134577D01*
G01X662088Y133602D02*
X662810Y134089D01*
G01X661366Y132628D02*
X662088Y133602D01*
G01Y131653D02*
X661366Y132628D01*
G01X662810Y131166D02*
X662088Y131653D01*
G01X664253Y130679D02*
X662810Y131166D01*
G01X667140Y130679D02*
X664253D01*
G01X668584Y131166D02*
X667140Y130679D01*
G01X669306Y131653D02*
X668584Y131166D01*
G01X670028Y132628D02*
X669306Y131653D01*
G01X672193Y199281D02*
X625342D01*
G01X672193D02*
Y164242D01*
G01X618089Y202169D02*
X617114Y201447D01*
G01X618576Y202890D02*
X618089Y202169D01*
G01X619063Y204334D02*
X618576Y202890D01*
G01X619063Y207221D02*
Y204334D01*
G01X618576Y208665D02*
X619063Y207221D01*
G01X618089Y209386D02*
X618576Y208665D01*
G01X617114Y210108D02*
X618089Y209386D01*
G01X616140D02*
X617114Y210108D01*
G01X615653Y208665D02*
X616140Y209386D01*
G01X615165Y207221D02*
X615653Y208665D01*
G01X615165Y204334D02*
Y207221D01*
G01X615653Y202890D02*
X615165Y204334D01*
G01X616140Y202169D02*
X615653Y202890D01*
G01X617114Y201447D02*
X616140Y202169D01*
G01X609806Y205056D02*
X610293Y207221D01*
G01X609319Y201447D02*
X609806Y205056D01*
G01X611268Y210108D02*
X607370D01*
G01X610293Y207221D02*
X611268Y210108D01*
G01X669306Y156988D02*
X670028Y156014D01*
G01X668584Y157475D02*
X669306Y156988D01*
G01X667140Y157962D02*
X668584Y157475D01*
G01X664253Y157962D02*
X667140D01*
G01X662810Y157475D02*
X664253Y157962D01*
G01X662088Y156988D02*
X662810Y157475D01*
G01X661366Y156014D02*
X662088Y156988D01*
G01Y155039D02*
X661366Y156014D01*
G01X662810Y154552D02*
X662088Y155039D01*
G01X664253Y154065D02*
X662810Y154552D01*
G01X667140Y154065D02*
X664253D01*
G01X668584Y154552D02*
X667140Y154065D01*
G01X669306Y155039D02*
X668584Y154552D01*
G01X670028Y156014D02*
X669306Y155039D01*
G01Y149193D02*
X670028Y148218D01*
G01X668584Y149680D02*
X669306Y149193D01*
G01X667140Y150167D02*
X668584Y149680D01*
G01X664253Y150167D02*
X667140D01*
G01X662810Y149680D02*
X664253Y150167D01*
G01X662088Y149193D02*
X662810Y149680D01*
G01X661366Y148218D02*
X662088Y149193D01*
G01X672193Y203218D02*
G03X676130Y199281I3937J0D01*
G01X672193Y403924D02*
Y203218D01*
G01X676130Y199281D02*
X701268D01*
G01X699299Y225659D02*
X625342D01*
G01X610293Y228546D02*
X609319Y227825D01*
G01X610780Y229268D02*
X610293Y228546D01*
G01X611268Y230712D02*
X610780Y229268D01*
G01X611268Y233599D02*
Y230712D01*
G01X610780Y235043D02*
X611268Y233599D01*
G01X610293Y235764D02*
X610780Y235043D01*
G01X609319Y236486D02*
X610293Y235764D01*
G01X608344D02*
X609319Y236486D01*
G01X607857Y235043D02*
X608344Y235764D01*
G01X607370Y233599D02*
X607857Y235043D01*
G01X607370Y230712D02*
Y233599D01*
G01X607857Y229268D02*
X607370Y230712D01*
G01X608344Y228546D02*
X607857Y229268D01*
G01X609319Y227825D02*
X608344Y228546D01*
G01X618089D02*
X617114Y227825D01*
G01X618576Y229268D02*
X618089Y228546D01*
G01X619063Y230712D02*
X618576Y229268D01*
G01X619063Y233599D02*
Y230712D01*
G01X618576Y235043D02*
X619063Y233599D01*
G01X618089Y235764D02*
X618576Y235043D01*
G01X617114Y236486D02*
X618089Y235764D01*
G01X616140D02*
X617114Y236486D01*
G01X615653Y235043D02*
X616140Y235764D01*
G01X615165Y233599D02*
X615653Y235043D01*
G01X615165Y230712D02*
Y233599D01*
G01X615653Y229268D02*
X615165Y230712D01*
G01X616140Y228546D02*
X615653Y229268D01*
G01X617114Y227825D02*
X616140Y228546D01*
G01X765950Y329990D02*
X625342D01*
G01X784594Y304399D02*
X625342D01*
G01X610293Y307287D02*
X609319Y306565D01*
G01X610780Y308008D02*
X610293Y307287D01*
G01X611268Y309452D02*
X610780Y308008D01*
G01X611268Y312339D02*
Y309452D01*
G01X610780Y313783D02*
X611268Y312339D01*
G01X610293Y314504D02*
X610780Y313783D01*
G01X609319Y315226D02*
X610293Y314504D01*
G01X608344D02*
X609319Y315226D01*
G01X607857Y313783D02*
X608344Y314504D01*
G01X607370Y312339D02*
X607857Y313783D01*
G01X607370Y309452D02*
Y312339D01*
G01X607857Y308008D02*
X607370Y309452D01*
G01X608344Y307287D02*
X607857Y308008D01*
G01X609319Y306565D02*
X608344Y307287D01*
G01X618089D02*
X617114Y306565D01*
G01X618576Y308008D02*
X618089Y307287D01*
G01X619063Y309452D02*
X618576Y308008D01*
G01X619063Y312339D02*
Y309452D01*
G01X618576Y313783D02*
X619063Y312339D01*
G01X618089Y314504D02*
X618576Y313783D01*
G01X617114Y315226D02*
X618089Y314504D01*
G01X616140D02*
X617114Y315226D01*
G01X615653Y313783D02*
X616140Y314504D01*
G01X615165Y312339D02*
X615653Y313783D01*
G01X615165Y309452D02*
Y312339D01*
G01X615653Y308008D02*
X615165Y309452D01*
G01X616140Y307287D02*
X615653Y308008D01*
G01X617114Y306565D02*
X616140Y307287D01*
G01X618089Y332877D02*
X617114Y332155D01*
G01X618576Y333599D02*
X618089Y332877D01*
G01X619063Y335043D02*
X618576Y333599D01*
G01X619063Y337930D02*
Y335043D01*
G01X618576Y339373D02*
X619063Y337930D01*
G01X618089Y340095D02*
X618576Y339373D01*
G01X617114Y340817D02*
X618089Y340095D01*
G01X616140D02*
X617114Y340817D01*
G01X615653Y339373D02*
X616140Y340095D01*
G01X615165Y337930D02*
X615653Y339373D01*
G01X615165Y335043D02*
Y337930D01*
G01X615653Y333599D02*
X615165Y335043D01*
G01X616140Y332877D02*
X615653Y333599D01*
G01X617114Y332155D02*
X616140Y332877D01*
G01X607857D02*
X607370Y333599D01*
G01X608832Y332155D02*
X607857Y332877D01*
G01X609806Y332155D02*
X608832D01*
G01X610780Y332877D02*
X609806Y332155D01*
G01X611268Y333599D02*
X610780Y332877D01*
G01X611755Y335043D02*
X611268Y333599D01*
G01Y336486D02*
X611755Y335043D01*
G01X610780Y337208D02*
X611268Y336486D01*
G01X609806Y337930D02*
X610780Y337208D01*
G01X608832Y337930D02*
X609806D01*
G01X607857Y337208D02*
X608832Y337930D01*
G01X608344Y340817D02*
X607857Y337208D01*
G01X611268Y340817D02*
X608344D01*
G01X660382Y435420D02*
Y615029D01*
G01X669501Y437360D02*
G03X672193Y441095I-1245J3735D01*
G01Y403924D02*
G03X669501Y407659I-3937J0D01*
G01X660382Y413536D02*
G03X663074Y409801I3937J0D01*
G01Y435218D02*
G03X660382Y431483I1245J-3735D01*
G01X669501Y437360D02*
G03X672193Y441095I-1245J3735D01*
G01Y403924D02*
G03X669501Y407659I-3937J0D01*
G01X663074Y435218D02*
G03X660382Y431483I1245J-3735D01*
G01Y413536D02*
G03X663074Y409801I3937J0D01*
G01X664577Y424262D02*
X664074Y424180D01*
G01X665163Y422129D02*
X665666Y422211D01*
G01X664493Y424672D02*
X664074Y424590D01*
G01X665247Y421719D02*
X665666Y421801D01*
G01X662902Y430578D02*
X666839D01*
G01X664744Y430085D02*
X662902D01*
G01X666839D02*
X665247D01*
G01Y427789D02*
X666839D01*
G01X662902D02*
X664744D01*
G01X666839Y427297D02*
X662902D01*
G01X665247Y426641D02*
X665582D01*
G01X664242D02*
X664577D01*
G01Y425328D02*
X664242D01*
G01X665582D02*
X665247D01*
G01Y424672D02*
X664493D01*
G01X665163Y424262D02*
X664577D01*
G01Y422129D02*
X665163D01*
G01X664493Y421719D02*
X665247D01*
G01X662902Y421063D02*
X665582D01*
G01X664996Y420653D02*
X662902D01*
G01X665582D02*
X665331D01*
G01X662902Y419751D02*
X664912D01*
G01Y419341D02*
X662902D01*
G01Y418438D02*
X664912D01*
G01Y418028D02*
X662902D01*
G01Y417372D02*
X665582D01*
G01X664996Y416962D02*
X662902D01*
G01X665582D02*
X665331D01*
G01X662902Y416060D02*
X664912D01*
G01Y415650D02*
X662902D01*
G01Y414748D02*
X664912D01*
G01Y414337D02*
X662902D01*
G01X665666Y424590D02*
X665247Y424672D01*
G01X664074Y421801D02*
X664493Y421719D01*
G01X665666Y424180D02*
X665163Y424262D01*
G01X664074Y422211D02*
X664577Y422129D01*
G01X665917Y424508D02*
X665666Y424590D01*
G01X663823Y421883D02*
X664074Y421801D01*
G01X666252Y424344D02*
X665917Y424508D01*
G01X663488Y422047D02*
X663823Y421883D01*
G01X665079Y419259D02*
X664912Y419341D01*
G01X663074Y409801D02*
X669501Y407659D01*
G01D02*
X663074Y409801D01*
G01X666168Y423852D02*
X665666Y424180D01*
G01X663572Y422540D02*
X664074Y422211D01*
G01X665079Y415568D02*
X664912Y415650D01*
G01X666503Y424098D02*
X666252Y424344D01*
G01X665331Y420653D02*
X665498Y420489D01*
G01X665163D02*
X664996Y420653D01*
G01X663237Y422293D02*
X663488Y422047D01*
G01X665247Y419423D02*
X665498Y419177D01*
G01X665163D02*
X665079Y419259D01*
G01X665331Y416962D02*
X665498Y416798D01*
G01X665163D02*
X664996Y416962D01*
G01X665247Y415732D02*
X665498Y415486D01*
G01X665163D02*
X665079Y415568D01*
G01X665666Y421801D02*
X665917Y421883D01*
G01X664074Y424590D02*
X663823Y424508D01*
G01X665331Y414501D02*
X664912Y414337D01*
G01X665331Y418192D02*
X664912Y418028D01*
G01X666755Y423688D02*
X666503Y424098D01*
G01X662985Y422704D02*
X663237Y422293D01*
G01X666336Y423606D02*
X666168Y423852D01*
G01X663404Y422786D02*
X663572Y422540D01*
G01X669501Y437360D02*
X663074Y435218D01*
G01X669501Y437360D02*
X663074Y435218D01*
G01X664912Y414748D02*
X665079Y414830D01*
G01X664912Y416060D02*
X665079Y416142D01*
G01X664912Y418438D02*
X665079Y418520D01*
G01X664912Y419751D02*
X665079Y419833D01*
G01X665917Y421883D02*
X666252Y422047D01*
G01X663823Y424508D02*
X663488Y424344D01*
G01X665247Y419013D02*
X665163Y419177D01*
G01X665247Y415322D02*
X665163Y415486D01*
G01X665666Y422211D02*
X666168Y422540D01*
G01X664074Y424180D02*
X663572Y423852D01*
G01X665498Y414666D02*
X665331Y414501D01*
G01X665079Y414830D02*
X665163Y414912D01*
G01X665498Y415978D02*
X665247Y415732D01*
G01X665079Y416142D02*
X665163Y416224D01*
G01X666839Y423196D02*
X666755Y423688D01*
G01X662902Y423196D02*
X662985Y422704D01*
G01X666420Y423196D02*
X666336Y423606D01*
G01X663320Y423196D02*
X663404Y422786D01*
G01X665498Y420489D02*
X665582Y420243D01*
G01X665247D02*
X665163Y420489D01*
G01X665498Y419177D02*
X665582Y418931D01*
G01X665498Y416798D02*
X665582Y416552D01*
G01X665247D02*
X665163Y416798D01*
G01X665498Y415486D02*
X665582Y415240D01*
G01X665498Y418356D02*
X665331Y418192D01*
G01X665079Y418520D02*
X665163Y418603D01*
G01X665498Y419669D02*
X665247Y419423D01*
G01X665079Y419833D02*
X665163Y419915D01*
G01X666252Y422047D02*
X666503Y422293D01*
G01X663488Y424344D02*
X663237Y424098D01*
G01X666168Y422540D02*
X666336Y422786D01*
G01X666503Y422293D02*
X666755Y422704D01*
G01X665163Y414912D02*
X665247Y415076D01*
G01X672193Y403924D02*
Y441095D01*
G01Y576053D02*
Y441095D01*
G01X666839Y427789D02*
Y427297D01*
G01Y430578D02*
Y430085D01*
G01X663572Y423852D02*
X663404Y423606D01*
G01X663237Y424098D02*
X662985Y423688D01*
G01X665163Y416224D02*
X665247Y416388D01*
G01X665163Y418603D02*
X665247Y418767D01*
G01X665163Y419915D02*
X665247Y420079D01*
G01X665582Y414912D02*
X665498Y414666D01*
G01X665582Y416224D02*
X665498Y415978D01*
G01X665582Y418603D02*
X665498Y418356D01*
G01X665582Y419915D02*
X665498Y419669D01*
G01X666336Y422786D02*
X666420Y423196D01*
G01X663404Y423606D02*
X663320Y423196D01*
G01X666755Y422704D02*
X666839Y423196D01*
G01X662985Y423688D02*
X662902Y423196D01*
G01X665582Y415240D02*
Y414912D01*
G01Y416552D02*
Y416224D01*
G01Y417372D02*
Y416962D01*
G01Y418931D02*
Y418603D01*
G01Y420243D02*
Y419915D01*
G01Y421063D02*
Y420653D01*
G01Y426641D02*
Y425328D01*
G01X665247D02*
Y426641D01*
G01Y420079D02*
Y420243D01*
G01Y418767D02*
Y419013D01*
G01Y416388D02*
Y416552D01*
G01Y415076D02*
Y415322D01*
G01Y430085D02*
Y427789D01*
G01X664744D02*
Y430085D01*
G01X664577Y426641D02*
Y425328D01*
G01X664242D02*
Y426641D01*
G01X662902Y430085D02*
Y430578D01*
G01Y427297D02*
Y427789D01*
G01Y420653D02*
Y421063D01*
G01Y419341D02*
Y419751D01*
G01Y418028D02*
Y418438D01*
G01Y416962D02*
Y417372D01*
G01Y415650D02*
Y416060D01*
G01Y414337D02*
Y414748D01*
G01X660382Y431483D02*
Y413536D01*
G01Y431483D02*
Y413536D01*
G01X672193Y579990D02*
X625342D01*
G01X610293Y582877D02*
X609319Y582155D01*
G01X610780Y583599D02*
X610293Y582877D01*
G01X611268Y585043D02*
X610780Y583599D01*
G01X611268Y587930D02*
Y585043D01*
G01X610780Y589373D02*
X611268Y587930D01*
G01X610293Y590095D02*
X610780Y589373D01*
G01X609319Y590817D02*
X610293Y590095D01*
G01X608344D02*
X609319Y590817D01*
G01X607857Y589373D02*
X608344Y590095D01*
G01X607370Y587930D02*
X607857Y589373D01*
G01X607370Y585043D02*
Y587930D01*
G01X607857Y583599D02*
X607370Y585043D01*
G01X608344Y582877D02*
X607857Y583599D01*
G01X609319Y582155D02*
X608344Y582877D01*
G01X618089D02*
X617114Y582155D01*
G01X618576Y583599D02*
X618089Y582877D01*
G01X619063Y585043D02*
X618576Y583599D01*
G01X619063Y587930D02*
Y585043D01*
G01X618576Y589373D02*
X619063Y587930D01*
G01X618089Y590095D02*
X618576Y589373D01*
G01X617114Y590817D02*
X618089Y590095D01*
G01X616140D02*
X617114Y590817D01*
G01X615653Y589373D02*
X616140Y590095D01*
G01X615165Y587930D02*
X615653Y589373D01*
G01X615165Y585043D02*
Y587930D01*
G01X615653Y583599D02*
X615165Y585043D01*
G01X616140Y582877D02*
X615653Y583599D01*
G01X617114Y582155D02*
X616140Y582877D01*
G01X676130Y579990D02*
G03X672193Y576053I0J-3937D01*
G01X732823Y579990D02*
X676130D01*
G01X657495Y647618D02*
X658217Y646644D01*
G01X656773Y648105D02*
X657495Y647618D01*
G01X655329Y648592D02*
X656773Y648105D01*
G01X652442Y648592D02*
X655329D01*
G01X650999Y648105D02*
X652442Y648592D01*
G01X650277Y647618D02*
X650999Y648105D01*
G01X649555Y646644D02*
X650277Y647618D01*
G01Y645669D02*
X649555Y646644D01*
G01X650999Y645182D02*
X650277Y645669D01*
G01X652442Y644695D02*
X650999Y645182D01*
G01X655329Y644695D02*
X652442D01*
G01X656773Y645182D02*
X655329Y644695D01*
G01X657495Y645669D02*
X656773Y645182D01*
G01X658217Y646644D02*
X657495Y645669D01*
G01Y639823D02*
X658217Y638848D01*
G01X656773Y640310D02*
X657495Y639823D01*
G01X655329Y640797D02*
X656773Y640310D01*
G01X652442Y640797D02*
X655329D01*
G01X650999Y640310D02*
X652442Y640797D01*
G01X650277Y639823D02*
X650999Y640310D01*
G01X649555Y638848D02*
X650277Y639823D01*
G01Y637874D02*
X649555Y638848D01*
G01X650999Y637387D02*
X650277Y637874D01*
G01X652442Y636899D02*
X650999Y637387D01*
G01X655329Y636899D02*
X652442D01*
G01X656773Y637387D02*
X655329Y636899D01*
G01X657495Y637874D02*
X656773Y637387D01*
G01X658217Y638848D02*
X657495Y637874D01*
G01Y621796D02*
X656773Y621309D01*
G01X658217Y622771D02*
X657495Y621796D01*
G01X658217Y623745D02*
Y622771D01*
G01X657495Y624719D02*
X658217Y623745D01*
G01X656773Y625207D02*
X657495Y624719D01*
G01X656051Y625694D02*
X656773Y625207D01*
G01X655329Y625694D02*
X656051D01*
G01X653886Y624719D02*
X655329Y625694D01*
G01X657495Y630566D02*
X658217Y631053D01*
G01Y630566D02*
X657495D01*
G01X658217Y631053D02*
Y630566D01*
G01X653164Y623745D02*
X653886Y624719D01*
G01X652442D02*
X653164Y623745D01*
G01X651720Y625207D02*
X652442Y624719D01*
G01X650999Y625207D02*
X651720D01*
G01X650277Y624719D02*
X650999Y625207D01*
G01X649555Y623745D02*
X650277Y624719D01*
G01X649555Y622771D02*
Y623745D01*
G01X650277Y621796D02*
X649555Y622771D01*
G01X653164D02*
Y623745D01*
G01X640815Y1006410D02*
Y989087D01*
G01X753017Y61520D02*
X753992Y62242D01*
G01X752530Y60798D02*
X753017Y61520D01*
G01X752043Y60076D02*
X752530Y60798D01*
G01X751556Y57911D02*
X752043Y60076D01*
G01Y55746D02*
X751556Y57911D01*
G01X753017Y54302D02*
X752043Y55746D01*
G01X748145Y61520D02*
X748632Y60798D01*
G01X747171Y62242D02*
X748145Y61520D01*
G01X746196Y62242D02*
X747171D01*
G01X745222Y61520D02*
X746196Y62242D01*
G01X744735Y60798D02*
X745222Y61520D01*
G01X744247Y60076D02*
X744735Y60798D01*
G01X743760Y57911D02*
X744247Y60076D01*
G01Y55746D02*
X743760Y57911D01*
G01X744735Y55024D02*
X744247Y55746D01*
G01X745222Y54302D02*
X744735Y55024D01*
G01X746196Y53580D02*
X745222Y54302D01*
G01X747171Y53580D02*
X746196D01*
G01X748145Y54302D02*
X747171Y53580D01*
G01X748632Y55024D02*
X748145Y54302D01*
G01X753992Y53580D02*
X753017Y54302D01*
G01X697462Y133115D02*
X695297Y133602D01*
G01X701071Y132628D02*
X697462Y133115D01*
G01X692409Y134577D02*
Y130679D01*
G01X695297Y133602D02*
X692409Y134577D01*
G01X696018Y147731D02*
Y148706D01*
G01X696740Y146757D02*
X696018Y147731D01*
G01X698184Y145782D02*
X696740Y146757D01*
G01X701071Y148706D02*
Y147731D01*
G01X700349Y139936D02*
X701071Y140423D01*
G01Y139936D02*
X700349D01*
G01X701071Y140423D02*
Y139936D01*
G01X692409Y147731D02*
Y148706D01*
G01X693131Y146757D02*
X692409Y147731D01*
G01X693853Y146270D02*
X693131Y146757D01*
G01X694575Y146270D02*
X693853D01*
G01X695297Y146757D02*
X694575Y146270D01*
G01X696018Y147731D02*
X695297Y146757D01*
G01X698905Y145782D02*
X698184D01*
G01X700349Y146757D02*
X698905Y145782D01*
G01X701071Y147731D02*
X700349Y146757D01*
G01X703236Y197313D02*
Y164242D01*
G01X700349Y155039D02*
X699627Y154552D01*
G01X701071Y156014D02*
X700349Y155039D01*
G01Y156988D02*
X701071Y156014D01*
G01X699627Y157475D02*
X700349Y156988D01*
G01X698184Y157962D02*
X699627Y157475D01*
G01X695297Y157962D02*
X698184D01*
G01X693853Y157475D02*
X695297Y157962D01*
G01X693131Y156988D02*
X693853Y157475D01*
G01X692409Y156014D02*
X693131Y156988D01*
G01Y155039D02*
X692409Y156014D01*
G01X693853Y154552D02*
X693131Y155039D01*
G01X695297Y154065D02*
X693853Y154552D01*
G01X696740D02*
X695297Y154065D01*
G01X697462Y156014D02*
X696740Y154552D01*
G01Y157475D02*
X697462Y156014D01*
G01X695297Y157962D02*
X696740Y157475D01*
G01X696018Y148706D02*
X696740Y149680D01*
G01X700349D02*
X701071Y148706D01*
G01X698905Y150654D02*
X700349Y149680D01*
G01X708712Y218574D02*
X708748Y218573D01*
G01X708677Y218577D02*
X708712Y218574D01*
G01X708641Y218583D02*
X708677Y218577D01*
G01X695297Y149680D02*
X696018Y148706D01*
G01X694575Y150167D02*
X695297Y149680D01*
G01X693853Y150167D02*
X694575D01*
G01X693131Y149680D02*
X693853Y150167D01*
G01X692409Y148706D02*
X693131Y149680D01*
G01X698184Y150654D02*
X698905D01*
G01X696740Y149680D02*
X698184Y150654D01*
G01X722724Y217392D02*
G03X721543Y218573I-1181J0D01*
G01X703866Y221919D02*
G03X703630Y222155I-236J0D01*
G01X704024Y221919D02*
G03X703630Y222313I-394J0D01*
G01Y216565D02*
G03X703866Y216801I0J236D01*
G01X703630Y216407D02*
G03X704024Y216801I0J394D01*
G01X702055Y222155D02*
G03X701819Y221919I0J-236D01*
G01X702055Y222313D02*
G03X701661Y221919I0J-394D01*
G01X692016Y219163D02*
G03X692803Y218376I787J0D01*
G01X693984Y223100D02*
G03X696346I1181J0D01*
G01X701819Y216801D02*
G03X702055Y216565I236J0D01*
G01X701661Y216801D02*
G03X702055Y216407I394J0D01*
G01X694575Y214242D02*
G03X695756Y213061I1181J0D01*
G01X701268Y199281D02*
G03X703236Y201250I0J1968D01*
G01X707572Y218583D02*
X707679Y218645D01*
G01X715322Y201328D02*
X713276Y199281D01*
G01X715323Y216525D02*
X717370Y218573D01*
G01D02*
X715323Y216525D01*
G01X698276Y216014D02*
X697488Y215226D01*
G01X707567Y201327D02*
X706386Y199281D01*
G01X708641Y218583D02*
X712140Y226053D01*
G01X711071D02*
X707567Y218573D01*
G01X751366Y224872D02*
X751229Y220935D01*
G01X746229D02*
X746366Y224872D01*
G01X751287Y220935D02*
Y224872D01*
G01X750776D02*
Y220935D01*
G01X747921D02*
Y224872D01*
G01X745776Y220935D02*
Y224872D01*
G01X744968Y208533D02*
Y224872D01*
G01X750697D02*
X750834Y220935D01*
G01X734595D02*
X734732Y224872D01*
G01X731229Y220935D02*
X731366Y224872D01*
G01X726366D02*
X726229Y220935D01*
G01X737094Y208533D02*
Y224872D01*
G01X736287D02*
Y220935D01*
G01X734142D02*
Y224872D01*
G01X731287D02*
Y220935D01*
G01X730776D02*
Y224872D01*
G01X747468Y220935D02*
X747331Y224872D01*
G01X735697D02*
X735834Y220935D01*
G01X725776Y224872D02*
Y220935D01*
G01X724417Y224872D02*
Y220935D01*
G01X723315Y224872D02*
Y220935D01*
G01X722724Y217392D02*
Y200462D01*
G01X720362Y226053D02*
Y218573D01*
G01X715323Y216525D02*
Y201328D01*
G01X730697Y224872D02*
X730834Y220935D01*
G01X723827Y224872D02*
X723964Y220935D01*
G01X722724Y224872D02*
X722862Y220935D01*
G01X708748Y199281D02*
Y218573D01*
G01X707567D02*
Y201327D01*
G01X704417Y235502D02*
Y199281D01*
G01X704024Y221919D02*
Y216801D01*
G01X703872Y221919D02*
Y216801D01*
G01X703630Y216559D02*
Y216407D01*
G01Y222313D02*
Y222162D01*
G01X703236Y201250D02*
Y224872D01*
G01X702055Y222162D02*
Y222313D01*
G01Y216559D02*
Y216407D01*
G01X701813Y221919D02*
Y216801D01*
G01X701661D02*
Y221919D01*
G01X700087Y215226D02*
Y232549D01*
G01X699299Y231762D02*
Y216014D01*
G01X698315D02*
Y231762D01*
G01X698276Y217667D02*
Y216014D01*
G01X697724Y229399D02*
Y218376D01*
G01X697488Y215226D02*
Y217667D01*
G01X696346Y224675D02*
Y223100D01*
G01X694575Y217667D02*
Y214242D01*
G01X693984Y224675D02*
Y223100D01*
G01X692016Y228612D02*
Y219163D01*
G01X707679Y218644D02*
X707914Y218665D01*
G01X722724Y200462D02*
X723905Y199281D01*
G01X708712Y218574D02*
X708677Y218577D01*
G01X707915Y218666D02*
X708248Y218644D01*
G01X702055Y222313D02*
X703630D01*
G01Y222162D02*
X702055D01*
G01X701813Y221919D02*
X701661D01*
G01X704024D02*
X703872D01*
G01X747468Y220935D02*
X756485D01*
G01X722862D02*
X734595D01*
G01X746229D02*
X735834D01*
G01X704417Y218573D02*
X872646D01*
G01X699299Y218376D02*
X692803D01*
G01X694575Y217667D02*
X699299D01*
G01X698315Y217588D02*
X699299D01*
G01X722724Y217392D02*
X758984D01*
G01X698276Y217273D02*
X699299D01*
G01X703872Y216801D02*
X704024D01*
G01X698315D02*
X699299D01*
G01X701813D02*
X701661D01*
G01X702055Y216559D02*
X703630D01*
G01X699299Y216469D02*
X698315D01*
G01Y216453D02*
X699299D01*
G01X703630Y216407D02*
X702055D01*
G01X699299Y216210D02*
X698315D01*
G01X699299Y216116D02*
X698315D01*
G01X699299Y216014D02*
X698276D01*
G01X697488Y215226D02*
X700087D01*
G01X704417Y215029D02*
X694575D01*
G01X695756Y213061D02*
X704417D01*
G01X699299Y216014D02*
X700087Y215226D01*
G01X708248Y218644D02*
X708641Y218583D01*
G01X744968Y208533D02*
X737094D01*
G01X708748Y201327D02*
X715323Y201328D01*
G01D02*
X708748Y201327D01*
G01X707567D02*
X708748D01*
G01X759378Y200462D02*
X722724D01*
G01X713276Y199281D02*
X704417D01*
G01X853157D02*
X723905D01*
G01X746799Y228612D02*
G03X747193Y228218I394J0D01*
G01X749831D02*
G03X750224Y228612I0J393D01*
G01X751799D02*
G03X752193Y228218I394J0D01*
G01X747486Y224891D02*
G03X747466Y224872I397J-438D01*
G01X747736Y225116D02*
G03X747931Y225555I-395J438D01*
G01X749558Y224872D02*
G03X749537Y224891I-406J-428D01*
G01X749092Y225555D02*
G03X749288Y225116I590J0D01*
G01X752736D02*
G03X752931Y225555I-395J438D01*
G01X752486Y224891D02*
G03X752466Y224872I397J-438D01*
G01X731799Y228612D02*
G03X732193Y228218I394J0D01*
G01X734831D02*
G03X735224Y228612I0J393D01*
G01X736799D02*
G03X737193Y228218I394J0D01*
G01X739831D02*
G03X740224Y228612I0J393D01*
G01X741799D02*
G03X742193Y228218I394J0D01*
G01X744831D02*
G03X745224Y228612I0J393D01*
G01X732736Y225116D02*
G03X732931Y225555I-395J438D01*
G01X732486Y224891D02*
G03X732466Y224872I397J-438D01*
G01X734558D02*
G03X734537Y224891I-406J-428D01*
G01X734092Y225555D02*
G03X734288Y225116I590J0D01*
G01X737736D02*
G03X737931Y225555I-395J438D01*
G01X737486Y224891D02*
G03X737466Y224872I397J-438D01*
G01X739558D02*
G03X739537Y224891I-406J-428D01*
G01X739092Y225555D02*
G03X739288Y225116I590J0D01*
G01X742736D02*
G03X742931Y225555I-395J438D01*
G01X742486Y224891D02*
G03X742466Y224872I397J-438D01*
G01X744092Y225555D02*
G03X744288Y225116I590J0D01*
G01X744558Y224872D02*
G03X744537Y224891I-406J-428D01*
G01X724831Y228218D02*
G03X725224Y228612I0J393D01*
G01X726799D02*
G03X727193Y228218I394J0D01*
G01X729831D02*
G03X730224Y228612I0J393D01*
G01X724092Y225555D02*
G03X724288Y225116I590J0D01*
G01X727736D02*
G03X727931Y225555I-395J438D01*
G01X729092D02*
G03X729288Y225116I590J0D01*
G01X718787Y226840D02*
G03X719378Y227431I0J591D01*
G01X717213D02*
G03X717803Y226840I591J0D01*
G01Y233533D02*
G03X717213Y232943I0J-590D01*
G01X719378D02*
G03X718787Y233533I-590J0D01*
G01X724558Y224872D02*
G03X724537Y224891I-406J-428D01*
G01X727486D02*
G03X727466Y224872I397J-438D01*
G01X729558D02*
G03X729537Y224891I-406J-428D01*
G01X703630Y226407D02*
G03X703866Y226644I0J236D01*
G01Y231762D02*
G03X703630Y231998I-236J0D01*
G01X704024Y231762D02*
G03X703630Y232155I-393J0D01*
G01Y226250D02*
G03X704024Y226644I0J394D01*
G01X706976Y233533D02*
G03X706386Y232943I0J-590D01*
G01X710717D02*
G03X710126Y233533I-590J0D01*
G01Y226840D02*
G03X710717Y227431I0J591D01*
G01X706386D02*
G03X706976Y226840I591J0D01*
G01X715520Y230777D02*
G03I-1575J0D01*
G01X716307D02*
G03I-2362J0D01*
G01X716583D02*
G03I-2658J0D01*
G01X716898D02*
G03I-2953J0D01*
G01X705205Y226840D02*
G03X703236Y224872I0J-1969D01*
G01X701819Y226644D02*
G03X702055Y226407I237J0D01*
G01Y231998D02*
G03X701819Y231762I0J-236D01*
G01X701661Y226644D02*
G03X702055Y226250I394J0D01*
G01Y232155D02*
G03X701661Y231762I0J-394D01*
G01X692803Y229399D02*
G03X692016Y228612I0J-787D01*
G01X696346Y224675D02*
G03X693984I-1181J0D01*
G01X695756Y234714D02*
G03X694575Y233533I0J-1181D01*
G01X752736Y225116D02*
X752486Y224891D01*
G01X747736Y225116D02*
X747486Y224891D01*
G01X742736Y225116D02*
X742486Y224891D01*
G01X737736Y225116D02*
X737486Y224891D01*
G01X732736Y225116D02*
X732486Y224891D01*
G01X727736Y225116D02*
X727486Y224891D01*
G01X700087Y232549D02*
X699299Y231762D01*
G01X752931Y228218D02*
Y225555D01*
G01X751799Y234132D02*
Y228612D01*
G01X750224Y234132D02*
Y228612D01*
G01X749092Y228218D02*
Y225555D01*
G01X747931Y228218D02*
Y225555D01*
G01X746799Y228612D02*
Y234132D01*
G01X745224D02*
Y228612D01*
G01X744092Y228218D02*
Y225555D01*
G01X742931Y228218D02*
Y225555D01*
G01X741799Y234132D02*
Y228612D01*
G01X740224Y234132D02*
Y228612D01*
G01X739092Y228218D02*
Y225555D01*
G01X737931Y228218D02*
Y225555D01*
G01X736799Y234132D02*
Y228612D01*
G01X735224Y234132D02*
Y228612D01*
G01X734092Y228218D02*
Y225555D01*
G01X732931Y228218D02*
Y225555D01*
G01X731799Y234132D02*
Y228612D01*
G01X730224Y234132D02*
Y228612D01*
G01X729092Y228218D02*
Y225555D01*
G01X727931Y228218D02*
Y225555D01*
G01X718384Y229596D02*
X718591Y235502D01*
G01X715835D02*
X715628Y229596D01*
G01X726799Y234132D02*
Y228612D01*
G01X725224Y234132D02*
Y228612D01*
G01X724092Y228218D02*
Y225555D01*
G01X721346Y235502D02*
Y224872D01*
G01X719378Y235502D02*
Y224872D01*
G01X717803Y229596D02*
Y235502D01*
G01X717213Y232943D02*
Y227431D01*
G01X716622Y229596D02*
Y235502D01*
G01X715244Y229596D02*
Y235502D01*
G01X712488D02*
Y229596D01*
G01X711110D02*
Y235502D01*
G01X710717Y232943D02*
Y227431D01*
G01X707567Y229596D02*
Y235502D01*
G01X706386Y224872D02*
Y235502D01*
G01X704024Y231762D02*
Y226644D01*
G01X703872D02*
Y231762D01*
G01X703630Y232004D02*
Y232155D01*
G01Y226401D02*
Y226250D01*
G01X702055Y226401D02*
Y226250D01*
G01Y232155D02*
Y232004D01*
G01X701813Y231762D02*
Y226644D01*
G01X701661D02*
Y231762D01*
G01X698276D02*
Y230108D01*
G01X697488D02*
Y232549D01*
G01X711898Y235502D02*
X712104Y229596D01*
G01X706986D02*
X706780Y235502D01*
G01X694575Y230108D02*
Y233533D01*
G01X749288Y225116D02*
X749537Y224891D01*
G01X744288Y225116D02*
X744537Y224891D01*
G01X739288Y225116D02*
X739537Y224891D01*
G01X734288Y225116D02*
X734537Y224891D01*
G01X729288Y225116D02*
X729537Y224891D01*
G01X724288Y225116D02*
X724537Y224891D01*
G01X721346Y235502D02*
X704417D01*
G01X695756Y234714D02*
X704417D01*
G01X726799Y234132D02*
X725224D01*
G01X731799D02*
X730224D01*
G01X736799D02*
X735224D01*
G01X741799D02*
X740224D01*
G01X746799D02*
X745224D01*
G01X751799D02*
X750224D01*
G01X710126Y233533D02*
X706976D01*
G01X718787D02*
X717803D01*
G01X704417Y232746D02*
X694575D01*
G01X697488Y232549D02*
X700087D01*
G01X702055Y232155D02*
X703630D01*
G01X702055Y232004D02*
X703630D01*
G01X726799Y231769D02*
X725224D01*
G01X731799D02*
X730224D01*
G01X736799D02*
X735224D01*
G01X741799D02*
X740224D01*
G01X746799D02*
X745224D01*
G01X751799D02*
X750224D01*
G01X703872Y231762D02*
X704024D01*
G01X701661D02*
X701813D01*
G01X699299D02*
X698276D01*
G01X698315Y231658D02*
X699299D01*
G01Y231565D02*
X698315D01*
G01X699299Y231322D02*
X698315D01*
G01X699299Y231306D02*
X698315D01*
G01X750224Y231025D02*
X751799D01*
G01X740224D02*
X741799D01*
G01X735224D02*
X736799D01*
G01X730224D02*
X731799D01*
G01X725224D02*
X726799D01*
G01X746799D02*
X745224D01*
G01X698315Y230974D02*
X699299D01*
G01Y230502D02*
X698276D01*
G01X745224Y230280D02*
X746799D01*
G01X726799D02*
X725224D01*
G01X731799D02*
X730224D01*
G01X736799D02*
X735224D01*
G01X741799D02*
X740224D01*
G01X751799D02*
X750224D01*
G01Y230206D02*
X751799D01*
G01X740224D02*
X741799D01*
G01X735224D02*
X736799D01*
G01X730224D02*
X731799D01*
G01X725224D02*
X726799D01*
G01X746799D02*
X745224D01*
G01X698315Y230187D02*
X699299D01*
G01Y230108D02*
X694575D01*
G01X706986Y229596D02*
X718384D01*
G01X745224Y229462D02*
X746799D01*
G01X726799D02*
X725224D01*
G01X731799D02*
X730224D01*
G01X736799D02*
X735224D01*
G01X741799D02*
X740224D01*
G01X751799D02*
X750224D01*
G01X692803Y229399D02*
X699299D01*
G01X726799Y228717D02*
X725224D01*
G01X731799D02*
X730224D01*
G01X736799D02*
X735224D01*
G01X741799D02*
X740224D01*
G01X746799D02*
X745224D01*
G01X751799D02*
X750224D01*
G01X724831Y228218D02*
X724092D01*
G01X727931D02*
X727193D01*
G01X729831D02*
X729092D01*
G01X732931D02*
X732193D01*
G01X734831D02*
X734092D01*
G01X737931D02*
X737193D01*
G01X739831D02*
X739092D01*
G01X742931D02*
X742193D01*
G01X744831D02*
X744092D01*
G01X747931D02*
X747193D01*
G01X749831D02*
X749092D01*
G01X752931D02*
X752193D01*
G01X705205Y226840D02*
X871858D01*
G01X703872Y226644D02*
X704024D01*
G01X701813D02*
X701661D01*
G01X702055Y226401D02*
X703630D01*
G01Y226250D02*
X702055D01*
G01X720362Y226053D02*
X711071D01*
G01X872646Y224872D02*
X704417D01*
G01X697488Y232549D02*
X698276Y231762D01*
G01X695857Y354522D02*
X696012Y354498D01*
G01X695721Y354592D02*
X695857Y354522D01*
G01X695610Y354706D02*
X695721Y354592D01*
G01X695540Y354845D02*
X695610Y354706D01*
G01X695520Y354990D02*
X695540Y354845D01*
G01X695857Y371451D02*
X696012Y371427D01*
G01X695721Y371521D02*
X695857Y371451D01*
G01X695610Y371635D02*
X695721Y371521D01*
G01X695540Y371774D02*
X695610Y371635D01*
G01X695520Y371919D02*
X695540Y371774D01*
G01X696487Y371790D02*
X696467Y371728D01*
G01X696499Y371854D02*
X696487Y371790D01*
G01X696504Y371919D02*
X696499Y371854D01*
G01X696487Y354861D02*
X696467Y354799D01*
G01X696499Y354925D02*
X696487Y354861D01*
G01X696504Y354990D02*
X696499Y354925D01*
G01X696256Y371492D02*
X696199Y371462D01*
G01X696305Y371524D02*
X696256Y371492D01*
G01X696348Y371560D02*
X696305Y371524D01*
G01X696384Y371597D02*
X696348Y371560D01*
G01X696410Y371629D02*
X696384Y371597D01*
G01X696439Y371672D02*
X696410Y371629D01*
G01X696456Y371703D02*
X696439Y371672D01*
G01X696467Y371728D02*
X696456Y371703D01*
G01X712786Y354522D02*
X712941Y354498D01*
G01X712650Y354592D02*
X712786Y354522D01*
G01X712540Y354706D02*
X712650Y354592D01*
G01X712470Y354845D02*
X712540Y354706D01*
G01X712449Y354990D02*
X712470Y354845D01*
G01X712786Y371451D02*
X712941Y371427D01*
G01X712650Y371521D02*
X712786Y371451D01*
G01X712540Y371635D02*
X712650Y371521D01*
G01X712470Y371774D02*
X712540Y371635D01*
G01X712449Y371919D02*
X712470Y371774D01*
G01X713416Y371790D02*
X713396Y371728D01*
G01X713429Y371854D02*
X713416Y371790D01*
G01X713433Y371919D02*
X713429Y371854D01*
G01X713416Y354861D02*
X713396Y354799D01*
G01X713429Y354925D02*
X713416Y354861D01*
G01X713433Y354990D02*
X713429Y354925D01*
G01X696256Y354562D02*
X696199Y354533D01*
G01X696305Y354595D02*
X696256Y354562D01*
G01X696348Y354631D02*
X696305Y354595D01*
G01X696384Y354667D02*
X696348Y354631D01*
G01X696410Y354700D02*
X696384Y354667D01*
G01X696439Y354743D02*
X696410Y354700D01*
G01X696456Y354774D02*
X696439Y354743D01*
G01X696467Y354799D02*
X696456Y354774D01*
G01X713185Y371492D02*
X713128Y371462D01*
G01X713234Y371524D02*
X713185Y371492D01*
G01X713278Y371560D02*
X713234Y371524D01*
G01X713313Y371597D02*
X713278Y371560D01*
G01X713339Y371629D02*
X713313Y371597D01*
G01X713368Y371672D02*
X713339Y371629D01*
G01X713385Y371703D02*
X713368Y371672D01*
G01X713396Y371728D02*
X713385Y371703D01*
G01X695527Y354897D02*
X695520Y354990D01*
G01X695550Y354817D02*
X695527Y354897D01*
G01X695583Y354749D02*
X695550Y354817D01*
G01X695620Y354693D02*
X695583Y354749D01*
G01X695661Y354645D02*
X695620Y354693D01*
G01X695702Y354607D02*
X695661Y354645D01*
G01X695744Y354576D02*
X695702Y354607D01*
G01X695788Y354550D02*
X695744Y354576D01*
G01X695821Y354535D02*
X695788Y354550D01*
G01X712457Y354897D02*
X712449Y354990D01*
G01X712479Y354817D02*
X712457Y354897D01*
G01X712512Y354749D02*
X712479Y354817D01*
G01X712549Y354693D02*
X712512Y354749D01*
G01X712590Y354645D02*
X712549Y354693D01*
G01X712631Y354607D02*
X712590Y354645D01*
G01X712673Y354576D02*
X712631Y354607D01*
G01X712717Y354550D02*
X712673Y354576D01*
G01X712750Y354535D02*
X712717Y354550D01*
G01X713185Y354562D02*
X713128Y354533D01*
G01X713234Y354595D02*
X713185Y354562D01*
G01X713278Y354631D02*
X713234Y354595D01*
G01X713313Y354667D02*
X713278Y354631D01*
G01X713339Y354700D02*
X713313Y354667D01*
G01X713368Y354743D02*
X713339Y354700D01*
G01X713385Y354774D02*
X713368Y354743D01*
G01X713396Y354799D02*
X713385Y354774D01*
G01X695527Y371826D02*
X695520Y371919D01*
G01X695550Y371746D02*
X695527Y371826D01*
G01X695583Y371679D02*
X695550Y371746D01*
G01X695620Y371622D02*
X695583Y371679D01*
G01X695661Y371574D02*
X695620Y371622D01*
G01X695702Y371536D02*
X695661Y371574D01*
G01X695744Y371505D02*
X695702Y371536D01*
G01X695788Y371479D02*
X695744Y371505D01*
G01X695821Y371464D02*
X695788Y371479D01*
G01X712457Y371826D02*
X712449Y371919D01*
G01X712479Y371746D02*
X712457Y371826D01*
G01X712512Y371679D02*
X712479Y371746D01*
G01X712549Y371622D02*
X712512Y371679D01*
G01X712590Y371574D02*
X712549Y371622D01*
G01X712631Y371536D02*
X712590Y371574D01*
G01X712673Y371505D02*
X712631Y371536D01*
G01X712717Y371479D02*
X712673Y371505D01*
G01X712750Y371464D02*
X712717Y371479D01*
G01X695883Y354515D02*
X695821Y354535D01*
G01X695947Y354502D02*
X695883Y354515D01*
G01X696012Y354498D02*
X695947Y354502D01*
G01X712812Y354515D02*
X712750Y354535D01*
G01X712876Y354502D02*
X712812Y354515D01*
G01X712941Y354498D02*
X712876Y354502D01*
G01X696042Y371428D02*
X696012Y371427D01*
G01X696070Y371430D02*
X696042Y371428D01*
G01X696097Y371434D02*
X696070Y371430D01*
G01X696120Y371438D02*
X696097Y371434D01*
G01X696144Y371444D02*
X696120Y371438D01*
G01X696164Y371450D02*
X696144Y371444D01*
G01X696184Y371457D02*
X696164Y371450D01*
G01X696199Y371462D02*
X696184Y371457D01*
G01X713409Y354834D02*
X713433Y354990D01*
G01X713341Y354702D02*
X713409Y354834D01*
G01X713228Y354590D02*
X713341Y354702D01*
G01X713094Y354521D02*
X713228Y354590D01*
G01X712941Y354498D02*
X713094Y354521D01*
G01X696480Y354834D02*
X696504Y354990D01*
G01X696412Y354702D02*
X696480Y354834D01*
G01X696299Y354590D02*
X696412Y354702D01*
G01X696165Y354521D02*
X696299Y354590D01*
G01X696012Y354498D02*
X696165Y354521D01*
G01X695883Y371444D02*
X695821Y371464D01*
G01X695947Y371432D02*
X695883Y371444D01*
G01X696012Y371427D02*
X695947Y371432D01*
G01X712812Y371444D02*
X712750Y371464D01*
G01X712876Y371432D02*
X712812Y371444D01*
G01X712941Y371427D02*
X712876Y371432D01*
G01X712972Y371428D02*
X712941Y371427D01*
G01X712999Y371430D02*
X712972Y371428D01*
G01X713026Y371434D02*
X712999Y371430D01*
G01X713050Y371438D02*
X713026Y371434D01*
G01X713073Y371444D02*
X713050Y371438D01*
G01X713093Y371450D02*
X713073Y371444D01*
G01X713114Y371457D02*
X713093Y371450D01*
G01X713128Y371462D02*
X713114Y371457D01*
G01X696042Y354499D02*
X696012Y354498D01*
G01X696070Y354501D02*
X696042Y354499D01*
G01X696097Y354505D02*
X696070Y354501D01*
G01X696120Y354509D02*
X696097Y354505D01*
G01X696144Y354515D02*
X696120Y354509D01*
G01X696164Y354521D02*
X696144Y354515D01*
G01X696184Y354528D02*
X696164Y354521D01*
G01X696199Y354533D02*
X696184Y354528D01*
G01X713409Y371764D02*
X713433Y371919D01*
G01X713341Y371631D02*
X713409Y371764D01*
G01X713228Y371519D02*
X713341Y371631D01*
G01X713094Y371450D02*
X713228Y371519D01*
G01X712941Y371427D02*
X713094Y371450D01*
G01X696480Y371764D02*
X696504Y371919D01*
G01X696412Y371631D02*
X696480Y371764D01*
G01X696299Y371519D02*
X696412Y371631D01*
G01X696165Y371450D02*
X696299Y371519D01*
G01X696012Y371427D02*
X696165Y371450D01*
G01X712972Y354499D02*
X712941Y354498D01*
G01X712999Y354501D02*
X712972Y354499D01*
G01X713026Y354505D02*
X712999Y354501D01*
G01X713050Y354509D02*
X713026Y354505D01*
G01X713073Y354515D02*
X713050Y354509D01*
G01X713093Y354521D02*
X713073Y354515D01*
G01X713114Y354528D02*
X713093Y354521D01*
G01X713128Y354533D02*
X713114Y354528D01*
G01X736760Y363117D02*
G03X737913Y360333I3938J0D01*
G01X713413Y371919D02*
G03X712468I-472J0D01*
G01X716681Y374085D02*
G03X715106Y375659I-1574J0D01*
G01X714614Y371919D02*
G03I-1673J0D01*
G01X714713D02*
G03I-1772J0D01*
G01X710383Y363455D02*
G03I-5907J0D01*
G01X711366D02*
G03I-6890J0D01*
G01X711668D02*
G03I-7192J0D01*
G01X711760D02*
G03I-7284J0D01*
G01X709142Y354610D02*
G03X713321Y358789I-4666J8845D01*
G01Y368120D02*
G03X709142Y372300I-8846J-4664D01*
G01X699811D02*
G03X695631Y368120I4665J-8845D01*
G01Y358789D02*
G03X699811Y354610I8844J4667D01*
G01X714713Y363455D02*
G03I-10237J0D01*
G01X713413Y354990D02*
G03X712468I-472J0D01*
G01X715106Y351250D02*
G03X716681Y352825I0J1575D01*
G01X714614Y354990D02*
G03I-1673J0D01*
G01X714713D02*
G03I-1772J0D01*
G01X696484Y371919D02*
G03X695539I-473J0D01*
G01X693846Y375659D02*
G03X692272Y374085I0J-1574D01*
G01X697685Y371919D02*
G03I-1673J0D01*
G01X697783D02*
G03I-1771J0D01*
G01X696484Y354990D02*
G03X695539I-473J0D01*
G01X692272Y352825D02*
G03X693846Y351250I1575J0D01*
G01X697685Y354990D02*
G03I-1673J0D01*
G01X697783D02*
G03I-1771J0D01*
G01X685936Y372130D02*
X685854Y372113D01*
G01X723371Y372690D02*
X723486Y372707D01*
G01X723469Y372623D02*
X723387Y372606D01*
G01X722944Y372288D02*
X722862Y372271D01*
G01X716091Y369360D02*
X715500Y369202D01*
G01X692862Y357549D02*
X693453Y357707D01*
G01X722879Y372371D02*
X722928Y372388D01*
G01X723551Y372707D02*
X723650Y372690D01*
G01X707094Y374675D02*
X701858D01*
G01X701855Y374478D02*
X698729D01*
G01X710224D02*
X707098D01*
G01X709142Y374085D02*
X699811D01*
G01X686760Y373691D02*
X722193D01*
G01X723486Y372707D02*
X723551D01*
G01X722468D02*
X722862D01*
G01X722879Y372623D02*
X722567D01*
G01X723535D02*
X723469D01*
G01X686297Y372549D02*
X686396D01*
G01X685461D02*
X685854D01*
G01X723305Y372522D02*
X723223D01*
G01X685871Y372465D02*
X685559D01*
G01X722567Y372371D02*
X722879D01*
G01X722862Y372271D02*
X722567D01*
G01X685559Y372214D02*
X685871D01*
G01X685854Y372113D02*
X685559D01*
G01X723338Y372003D02*
X723797D01*
G01X722567Y371919D02*
X722468D01*
G01X723797D02*
X723207D01*
G01X685559Y371762D02*
X685461D01*
G01X686396D02*
X686297D01*
G01X722193Y370935D02*
X686760D01*
G01X695631Y368120D02*
X693846D01*
G01X715106D02*
X713321D01*
G01X685871Y372214D02*
X685920Y372231D01*
G01X723305Y372656D02*
X723371Y372690D01*
G01X723387Y372606D02*
X723338Y372573D01*
G01X723010Y372338D02*
X722944Y372288D01*
G01X722928Y372606D02*
X722879Y372623D01*
G01X723617Y372606D02*
X723535Y372623D01*
G01X722862Y372707D02*
X722944Y372690D01*
G01X685854Y372549D02*
X685936Y372532D01*
G01X713321Y358789D02*
X715106D01*
G01X693846D02*
X695631D01*
G01X722193Y355974D02*
X686760D01*
G01X722193Y353218D02*
X686760D01*
G01X699811Y352825D02*
X709142D01*
G01X710224Y352431D02*
X698729D01*
G01X698571Y351840D02*
X692862D01*
G01X716091D02*
X710382D01*
G01X715106Y351250D02*
X693846D01*
G01X723748Y372371D02*
X723338Y372003D01*
G01X723207D02*
X723666Y372422D01*
G01X723239Y372589D02*
X723305Y372656D01*
G01X722928Y372388D02*
X722961Y372422D01*
G01X723059Y372405D02*
X723010Y372338D01*
G01X723781Y372422D02*
X723748Y372371D01*
G01X723338Y372573D02*
X723305Y372522D01*
G01X723715Y372656D02*
X723781Y372589D01*
G01X722961Y372573D02*
X722928Y372606D01*
G01X737913Y360333D02*
X767103Y331143D01*
G01X722944Y372690D02*
X723010Y372640D01*
G01X723666Y372573D02*
X723617Y372606D01*
G01X723650Y372690D02*
X723715Y372656D01*
G01X685920Y372449D02*
X685871Y372465D01*
G01X693453Y369202D02*
X692862Y369360D01*
G01X715500Y357707D02*
X716091Y357549D01*
G01X686002Y372181D02*
X685936Y372130D01*
G01X723666Y372422D02*
X723699Y372489D01*
G01X723075Y372455D02*
X723059Y372405D01*
G01X722961Y372422D02*
X722977Y372472D01*
G01X723797Y372489D02*
X723781Y372422D01*
G01X723223Y372522D02*
X723239Y372589D01*
G01X736760Y363117D02*
Y474790D01*
G01X723781Y372589D02*
X723797Y372522D01*
G01X723059Y372573D02*
X723075Y372522D01*
G01X722977D02*
X722961Y372573D01*
G01X723699Y372522D02*
X723666Y372573D01*
G01X723010Y372640D02*
X723059Y372573D01*
G01X685920Y372231D02*
X685953Y372264D01*
G01X686297Y372415D02*
X686199Y372298D01*
G01Y372432D02*
X686297Y372549D01*
G01X686051Y372248D02*
X686002Y372181D01*
G01X710224Y374478D02*
X710382Y375069D01*
G01X723797Y372003D02*
Y371919D01*
G01Y372522D02*
Y372489D01*
G01X723699D02*
Y372522D01*
G01X723207Y371919D02*
Y372003D01*
G01X723075Y372522D02*
Y372455D01*
G01X722977Y372472D02*
Y372522D01*
G01X722567Y372623D02*
Y372371D01*
G01Y372271D02*
Y371919D01*
G01X722468D02*
Y372707D01*
G01X722193Y355974D02*
Y353218D01*
G01Y373691D02*
Y370935D01*
G01X719295Y355974D02*
Y353218D01*
G01Y373691D02*
Y370935D01*
G01X718523D02*
Y373691D01*
G01Y353218D02*
Y355974D01*
G01X718179Y370935D02*
Y373691D01*
G01Y353218D02*
Y355974D01*
G01X717365Y370935D02*
Y373691D01*
G01Y353218D02*
Y355974D01*
G01X717021Y370935D02*
Y373691D01*
G01Y353218D02*
Y355974D01*
G01X716681Y374085D02*
Y352825D01*
G01X716248Y355974D02*
Y353218D01*
G01Y373691D02*
Y370935D01*
G01X716091Y357549D02*
Y351840D01*
G01Y375069D02*
Y369360D01*
G01X715500Y369202D02*
Y357707D01*
G01X715106Y358789D02*
Y368120D01*
G01X710382Y351840D02*
X710224Y352431D01*
G01X698571Y375069D02*
X698729Y374478D01*
G01X685953Y372415D02*
X685920Y372449D01*
G01X685936Y372532D02*
X686002Y372482D01*
G01X698729Y352431D02*
X698571Y351840D01*
G01X701858Y374675D02*
X701855Y374478D01*
G01X709142Y372300D02*
Y374085D01*
G01Y352825D02*
Y354610D01*
G01X699811D02*
Y352825D01*
G01Y374085D02*
Y372300D01*
G01X707094Y374675D02*
X707098Y374478D01*
G01X686051Y372415D02*
X686068Y372365D01*
G01X685969D02*
X685953Y372415D01*
G01X686002Y372482D02*
X686051Y372415D01*
G01X686068Y372298D02*
X686051Y372248D01*
G01X685953Y372264D02*
X685969Y372315D01*
G01X693846Y368120D02*
Y358789D01*
G01X693453Y369202D02*
Y357707D01*
G01X692862Y357549D02*
Y351840D01*
G01Y375069D02*
Y369360D01*
G01X692514Y370935D02*
Y373691D01*
G01Y353218D02*
Y355974D01*
G01X692272Y352825D02*
Y374085D01*
G01X691766Y355974D02*
Y353218D01*
G01Y373691D02*
Y370935D01*
G01X691091Y355974D02*
Y353218D01*
G01Y373691D02*
Y370935D01*
G01X690644Y355974D02*
Y353218D01*
G01Y373691D02*
Y370935D01*
G01X689970Y355974D02*
Y353218D01*
G01Y373691D02*
Y370935D01*
G01X689222D02*
Y373691D01*
G01Y353218D02*
Y355974D01*
G01X686760Y370935D02*
Y373691D01*
G01Y355974D02*
Y353218D01*
G01X686396Y372549D02*
Y371762D01*
G01X686297D02*
Y372415D01*
G01X686199Y372298D02*
Y372432D01*
G01X686068Y372365D02*
Y372298D01*
G01X685969Y372315D02*
Y372365D01*
G01X685559Y372465D02*
Y372214D01*
G01Y372113D02*
Y371762D01*
G01X685461D02*
Y372549D01*
G01X693264Y446827D02*
X693323Y446839D01*
G01X693228Y446814D02*
X693264Y446827D01*
G01X693217Y446802D02*
X693228Y446814D01*
G01X704086Y446800D02*
X703928Y446730D01*
G01X704215Y446935D02*
X704086Y446800D01*
G01X704297Y447115D02*
X704215Y446935D01*
G01X704324Y447313D02*
X704297Y447115D01*
G01X706342Y437294D02*
X706112Y437273D01*
G01X706552Y437356D02*
X706342Y437294D01*
G01X706724Y437451D02*
X706552Y437356D01*
G01X706842Y437574D02*
X706724Y437451D01*
G01X706898Y437712D02*
X706842Y437574D01*
G01X714735Y447534D02*
X714640Y447486D01*
G01X714822Y447650D02*
X714735Y447534D01*
G01X714891Y447825D02*
X714822Y447650D01*
G01X714934Y448040D02*
X714891Y447825D01*
G01X714949Y448272D02*
X714934Y448040D01*
G01X704235Y449449D02*
X704383Y449478D01*
G01X704102Y449362D02*
X704235Y449449D01*
G01X703998Y449228D02*
X704102Y449362D01*
G01X703933Y449063D02*
X703998Y449228D01*
G01X703911Y448888D02*
X703933Y449063D01*
G01X707174Y437860D02*
X707200Y437851D01*
G01X707148Y437807D02*
X707174Y437860D01*
G01X707126Y437698D02*
X707148Y437807D01*
G01X710452Y399021D02*
X710382Y399273D01*
G01X710452Y398756D02*
Y399021D01*
G01X710382Y398502D02*
X710452Y398756D01*
G01X709759Y397945D02*
X709476Y397903D01*
G01X710019Y398066D02*
X709759Y397945D01*
G01X710233Y398258D02*
X710019Y398066D01*
G01X710382Y398502D02*
X710233Y398258D01*
G01X701804Y437807D02*
X701827Y437698D01*
G01X701778Y437860D02*
X701804Y437807D01*
G01X701752Y437851D02*
X701778Y437860D01*
G01X702524Y436362D02*
X702754Y436341D01*
G01X702314Y436423D02*
X702524Y436362D01*
G01X702142Y436519D02*
X702314Y436423D01*
G01X702024Y436641D02*
X702142Y436519D01*
G01X701968Y436780D02*
X702024Y436641D01*
G01X701792Y439036D02*
X701727Y439013D01*
G01X701857Y438903D02*
X701792Y439036D01*
G01X701914Y438630D02*
X701857Y438903D01*
G01X714539Y446810D02*
X714520Y446814D01*
G01X714551Y446806D02*
X714539Y446810D01*
G01X714555Y446802D02*
X714551Y446806D01*
G01X710233Y399517D02*
X710382Y399273D01*
G01X710020Y399708D02*
X710233Y399517D01*
G01X709760Y399830D02*
X710020Y399708D01*
G01X709476Y399872D02*
X709760Y399830D01*
G01X694018Y448041D02*
X694004Y448272D01*
G01X694062Y447825D02*
X694018Y448041D01*
G01X694130Y447651D02*
X694062Y447825D01*
G01X694217Y447534D02*
X694130Y447651D01*
G01X694312Y447486D02*
X694217Y447534D01*
G01X709778Y399824D02*
X709476Y399872D01*
G01X710053Y399685D02*
X709778Y399824D01*
G01X710272Y399467D02*
X710053Y399685D01*
G01X710412Y399193D02*
X710272Y399467D01*
G01X710461Y398889D02*
X710412Y399193D01*
G01X710413Y398584D02*
X710461Y398889D01*
G01X710273Y398310D02*
X710413Y398584D01*
G01X710055Y398092D02*
X710273Y398310D01*
G01X709780Y397951D02*
X710055Y398092D01*
G01X709476Y397903D02*
X709780Y397951D01*
G01X693231Y447457D02*
X693238Y447455D01*
G01X693224Y447458D02*
X693231Y447457D01*
G01X693217Y447460D02*
X693224Y447458D01*
G01X707096Y438902D02*
X707039Y438630D01*
G01X707160Y439036D02*
X707096Y438902D01*
G01X707226Y439013D02*
X707160Y439036D01*
G01X702110Y437574D02*
X702055Y437712D01*
G01X702229Y437452D02*
X702110Y437574D01*
G01X702400Y437356D02*
X702229Y437452D01*
G01X702610Y437295D02*
X702400Y437356D01*
G01X702841Y437273D02*
X702610Y437295D01*
G01X715724Y446814D02*
X715736Y446802D01*
G01X715688Y446827D02*
X715724Y446814D01*
G01X715629Y446839D02*
X715688Y446827D01*
G01X696331Y447063D02*
X695973Y447045D01*
G01X696597Y447087D02*
X696331Y447063D01*
G01X696739Y447115D02*
X696597Y447087D01*
G01X696745Y447144D02*
X696739Y447115D01*
G01X696618Y447171D02*
X696745Y447144D01*
G01X706930Y436643D02*
X706985Y436780D01*
G01X706811Y436520D02*
X706930Y436643D01*
G01X706638Y436423D02*
X706811Y436520D01*
G01X706426Y436362D02*
X706638Y436423D01*
G01X706199Y436341D02*
X706426Y436362D01*
G01X695578Y447132D02*
X695543Y447141D01*
G01X695560Y447123D02*
X695578Y447132D01*
G01X695490Y447115D02*
X695560Y447123D01*
G01X695382Y447109D02*
X695490Y447115D01*
G01X695724Y447033D02*
X695683Y447028D01*
G01X695784Y447038D02*
X695724Y447033D01*
G01X695857Y447041D02*
X695784Y447038D01*
G01X714216Y447074D02*
X714379Y447054D01*
G01X713979Y447092D02*
X714216Y447074D01*
G01X713687Y447105D02*
X713979Y447092D01*
G01X712208Y447144D02*
X712335Y447171D01*
G01X712213Y447115D02*
X712208Y447144D01*
G01X712355Y447087D02*
X712213Y447115D01*
G01X712622Y447063D02*
X712355Y447087D01*
G01X712980Y447045D02*
X712622Y447063D01*
G01X713169Y447038D02*
X713096Y447041D01*
G01X713228Y447033D02*
X713169Y447038D01*
G01X713269Y447028D02*
X713228Y447033D01*
G01X713463Y447115D02*
X713571Y447109D01*
G01X713393Y447123D02*
X713463Y447115D01*
G01X713375Y447132D02*
X713393Y447123D01*
G01X713410Y447141D02*
X713375Y447132D01*
G01X694402Y446806D02*
X694398Y446802D01*
G01X694414Y446810D02*
X694402Y446806D01*
G01X694433Y446814D02*
X694414Y446810D01*
G01X703889Y447135D02*
X703911Y447313D01*
G01X703825Y446972D02*
X703889Y447135D01*
G01X703722Y446839D02*
X703825Y446972D01*
G01X703589Y446753D02*
X703722Y446839D01*
G01X703440Y446722D02*
X703589Y446753D01*
G01X704345Y449063D02*
X704324Y448888D01*
G01X704410Y449228D02*
X704345Y449063D01*
G01X704514Y449362D02*
X704410Y449228D01*
G01X704648Y449449D02*
X704514Y449362D01*
G01X704795Y449478D02*
X704648Y449449D01*
G01X703879Y446723D02*
X703854Y446722D01*
G01X703903Y446726D02*
X703879Y446723D01*
G01X703928Y446730D02*
X703903Y446726D01*
G01X715729Y447458D02*
X715736Y447460D01*
G01X715722Y447457D02*
X715729Y447458D01*
G01X715715Y447455D02*
X715722Y447457D01*
G01X694974Y447092D02*
X695266Y447105D01*
G01X694737Y447074D02*
X694974Y447092D01*
G01X694574Y447054D02*
X694737Y447074D01*
G01X709201Y440029D02*
G03X711720Y442549I0J2519D01*
G01X712508Y438651D02*
G03X713295Y439439I0J787D01*
G01X710461Y398888D02*
G03I-985J0D01*
G01X713295Y437273D02*
G03X714555Y438533I0J1260D01*
G01X712508Y437470D02*
G03X714476Y439439I0J1968D01*
G01X709988Y432746D02*
G03X711957Y434714I0J1969D01*
G01X717075Y439833D02*
G03X719043Y441801I0J1968D01*
G01X713295Y436092D02*
G03X715736Y438533I0J2441D01*
G01X710382Y398888D02*
G03I-5906J0D01*
G01X712350D02*
G03I-7874J0D01*
G01X695657Y439439D02*
G03X696445Y438651I788J0D01*
G01X700461Y398888D02*
G03I-985J0D01*
G01X694398Y438533D02*
G03X695657Y437273I1260J0D01*
G01X694476Y439439D02*
G03X696445Y437470I1969J0D01*
G01X689909Y441801D02*
G03X691878Y439833I1968J0D01*
G01X696996Y434714D02*
G03X698965Y432746I1968J0D01*
G01X693217Y438533D02*
G03X695657Y436092I2441J0D01*
G01X712335Y447171D02*
X714640Y447486D01*
G01X715715Y447455D02*
X713410Y447141D01*
G01X693323Y446839D02*
X694574Y447054D01*
G01X695683Y447028D02*
X694433Y446814D01*
G01X713571Y447109D02*
X713687Y447105D01*
G01X713096Y447041D02*
X712980Y447045D01*
G01X714640Y447486D02*
X715715Y447455D01*
G01X705461Y450730D02*
X704476D01*
G01X702311Y450659D02*
X707508D01*
G01X705461Y450561D02*
X704476D01*
G01X698669Y450266D02*
X706937D01*
G01X705461Y450069D02*
X700047D01*
G01X707508Y449478D02*
X704383D01*
G01X707705Y449281D02*
X705539D01*
G01X711720Y449183D02*
X705539D01*
G01X709457Y449163D02*
X710244D01*
G01X709457Y449085D02*
X710244D01*
G01Y449010D02*
X709457D01*
G01Y448986D02*
X710244D01*
G01Y448950D02*
X709457D01*
G01X703911Y448888D02*
X704324D01*
G01X701031D02*
X700047D01*
G01X710244Y448862D02*
X709457D01*
G01X710244Y448838D02*
X709457D01*
G01Y448809D02*
X710244D01*
G01X709457Y448691D02*
X710244D01*
G01X701031D02*
X700047D01*
G01X710342Y448612D02*
X705264D01*
G01X705579Y448592D02*
X710244D01*
G01X714949Y448261D02*
X715736D01*
G01X696366Y448100D02*
X693217D01*
G01X715736D02*
X712587D01*
G01X708610Y447903D02*
X710972D01*
G01X696602Y447707D02*
X694476D01*
G01X710776D02*
X709457D01*
G01X714476D02*
X712350D01*
G01X701031Y447510D02*
X700047D01*
G01X703911Y447313D02*
X704324D01*
G01X701031D02*
X700047D01*
G01X711720D02*
X706510D01*
G01X710776Y446919D02*
X709988D01*
G01Y446722D02*
X710776D01*
G01X705461D02*
X702311D01*
G01X694398Y446565D02*
X693217D01*
G01X715736D02*
X714555D01*
G01X704476Y446549D02*
X705461D01*
G01X714555Y446537D02*
X715736D01*
G01X693217D02*
X694398D01*
G01X714555Y446525D02*
X715736D01*
G01X694398D02*
X693217D01*
G01X700047Y446132D02*
X705461D01*
G01X698669Y445935D02*
X706937D01*
G01X694398Y445751D02*
X693217D01*
G01X715736D02*
X714555D01*
G01X705539Y445738D02*
X699949D01*
G01X705461Y445640D02*
X704476D01*
G01X709988Y445541D02*
X710776D01*
G01X705461D02*
X704476D01*
G01Y445470D02*
X705461D01*
G01Y445423D02*
X704476D01*
G01Y445374D02*
X705461D01*
G01X710776Y445344D02*
X709988D01*
G01X704476Y445281D02*
X705461D01*
G01X705539Y445108D02*
X704476D01*
G01X711720Y444951D02*
X706510D01*
G01X714555Y444754D02*
X715736D01*
G01X694398D02*
X693217D01*
G01X709457Y444557D02*
X710776D01*
G01X708610Y444360D02*
X710972D01*
G01X694398Y443966D02*
X693217D01*
G01X715736D02*
X714555D01*
G01X710244Y443671D02*
X705579D01*
G01X710342Y443651D02*
X705264D01*
G01X709457Y443573D02*
X710244D01*
G01Y443455D02*
X709457D01*
G01Y443425D02*
X710244D01*
G01X709457Y443401D02*
X710244D01*
G01X704476Y443376D02*
X700539D01*
G01X709457Y443313D02*
X710244D01*
G01Y443277D02*
X709457D01*
G01Y443254D02*
X710244D01*
G01Y443179D02*
X709457D01*
G01X710244Y443100D02*
X709457D01*
G01X710342Y443081D02*
X709358D01*
G01X694398Y441998D02*
X693217D01*
G01X712350D02*
X696602D01*
G01X715736D02*
X714555D01*
G01X715657Y441801D02*
X693295D01*
G01X694398Y441210D02*
X693217D01*
G01X704083D02*
X700933D01*
G01X715736D02*
X714555D01*
G01X694476Y440620D02*
X693295D01*
G01X704476D02*
X700539D01*
G01X715657D02*
X714476D01*
G01X709201Y440029D02*
X704476D01*
G01X714555Y439833D02*
X717075D01*
G01X694398D02*
X691878D01*
G01X713295Y439439D02*
X714476D01*
G01X694476D02*
X695657D01*
G01X714555Y439045D02*
X715736D01*
G01X693217D02*
X694398D01*
G01X707183D02*
X701769D01*
G01X707226Y439013D02*
X701727D01*
G01X712508Y438651D02*
X696445D01*
G01X701914Y438630D02*
X707039D01*
G01X707183Y437864D02*
X701769D01*
G01X707200Y437851D02*
X701752D01*
G01X701827Y437698D02*
X707126D01*
G01X715657Y437470D02*
X693295D01*
G01X693217Y448250D02*
X694004Y448272D01*
G01X693238Y447455D02*
X694312Y447486D01*
G01X695266Y447105D02*
X695382Y447109D01*
G01X695973Y447045D02*
X695857Y447041D01*
G01X714379Y447054D02*
X715629Y446839D01*
G01X714520Y446814D02*
X713269Y447028D01*
G01X694312Y447486D02*
X696618Y447171D01*
G01X695543Y447141D02*
X693238Y447455D01*
G01X691721Y437273D02*
X717231D01*
G01X706199Y436341D02*
X702754D01*
G01X691721Y436092D02*
X717231D01*
G01X711957Y435305D02*
X696996D01*
G01X709988Y432746D02*
X698965D01*
G01X720618Y428514D02*
X732823D01*
G01X727570Y426968D02*
X727905D01*
G01X724756Y425918D02*
X727570D01*
G01Y425525D02*
X724756D01*
G01X727905Y424475D02*
X727570D01*
G01X724756Y423950D02*
X727905D01*
G01X726163Y423556D02*
X724756D01*
G01X727570D02*
X726565D01*
G01X726967Y421916D02*
X727168D01*
G01Y421522D02*
X726900D01*
G01X724756Y420997D02*
X727905D01*
G01X727235Y420603D02*
X724756D01*
G01Y418241D02*
X727235D01*
G01X727905Y417848D02*
X724756D01*
G01X727570Y417323D02*
X727905D01*
G01Y414960D02*
X727570D01*
G01X727905Y414435D02*
X726163D01*
G01X726498Y414107D02*
X727570D01*
G01X725828Y412401D02*
X725694D01*
G01X727570Y412204D02*
X727905D01*
G01X725627Y412073D02*
X725895D01*
G01X732823Y408632D02*
X720618D01*
G01X717434Y399453D02*
X717606Y399478D01*
G01X699476Y399872D02*
X699173Y399824D01*
G01X709476Y399872D02*
X709173Y399824D01*
G01X699476Y397903D02*
X699780Y397951D01*
G01X691450Y398850D02*
X691327Y398825D01*
G01X714088Y398850D02*
X713965Y398825D01*
G01X717582Y399353D02*
X717459Y399327D01*
G01X727235Y418241D02*
X724756Y419160D01*
G01X725091Y419422D02*
X727905Y418438D01*
G01X726766Y421981D02*
X726967Y421916D01*
G01X726900Y421522D02*
X726699Y421588D01*
G01X725694Y412401D02*
X725493Y412467D01*
G01X718271Y399478D02*
X718418D01*
G01X718960D02*
X719156D01*
G01X717606D02*
X717705D01*
G01X714826D02*
X715047D01*
G01X715662D02*
X715810D01*
G01X714481D02*
X714629D01*
G01X713374D02*
X713965D01*
G01X695436D02*
X695633D01*
G01X694698D02*
X694845D01*
G01X693025D02*
X693172D01*
G01X692188D02*
X692409D01*
G01X691843D02*
X691991D01*
G01X690736D02*
X691327D01*
G01X691351Y399353D02*
X690884D01*
G01X713989D02*
X713522D01*
G01X717680D02*
X717582D01*
G01X717336Y399202D02*
X717213D01*
G01X713522Y398976D02*
X713989D01*
G01X690884D02*
X691351D01*
G01X691327Y398825D02*
X690884D01*
G01X713965D02*
X713522D01*
G01X695756Y398699D02*
X695313D01*
G01X695780Y398599D02*
X695288D01*
G01X717385Y398423D02*
X718074D01*
G01X690884Y398297D02*
X690736D01*
G01X692336D02*
X692188D01*
G01X691991D02*
X691843D01*
G01X693172D02*
X692951D01*
G01X696027D02*
X695879D01*
G01X695190D02*
X695042D01*
G01X694845D02*
X694698D01*
G01X713522D02*
X713374D01*
G01X714973D02*
X714826D01*
G01X715810D02*
X715589D01*
G01X714629D02*
X714481D01*
G01X718074D02*
X717188D01*
G01X718418D02*
X718271D01*
G01X719156D02*
X718960D01*
G01X726699Y421588D02*
X726431Y421785D01*
G01X724756Y416666D02*
X727570Y415354D01*
G01Y414960D02*
X724756Y416273D01*
G01X725292Y412204D02*
X725627Y412073D01*
G01X717803Y399327D02*
X717680Y399353D01*
G01X713965Y399478D02*
X714088Y399453D01*
G01X691327Y399478D02*
X691450Y399453D01*
G01X717705Y399478D02*
X717852Y399453D01*
G01X699476Y399872D02*
X699780Y399824D01*
G01X709476Y397903D02*
X709173Y397951D01*
G01X699476Y397903D02*
X699173Y397951D01*
G01X726431Y421785D02*
X726230Y422047D01*
G01X711203Y441019D02*
X710224Y441998D01*
G01X726632Y422113D02*
X726766Y421981D01*
G01X725024Y412401D02*
X725292Y412204D01*
G01X725493Y412467D02*
X725292Y412598D01*
G01X717852Y399453D02*
X717951Y399403D01*
G01X709174Y397951D02*
X708897Y398092D01*
G01X714063Y399327D02*
X713989Y399353D01*
G01X691425Y399327D02*
X691351Y399353D01*
G01X693846Y375659D02*
X715106D01*
G01X698571Y375069D02*
X692862D01*
G01X716091D02*
X710382D01*
G01X726699Y413779D02*
X726498Y414107D01*
G01X724823Y412729D02*
X725024Y412401D01*
G01X708359Y437273D02*
X707226Y439013D01*
G01X707200Y437851D02*
X708346Y436092D01*
G01X725292Y412598D02*
X725158Y412795D01*
G01X705264Y448612D02*
X704476Y449714D01*
G01X726163Y413976D02*
X726364Y413714D01*
G01X717951Y399403D02*
X718049Y399302D01*
G01X714088Y399453D02*
X714186Y399378D01*
G01X717877Y399277D02*
X717803Y399327D01*
G01X699778Y399824D02*
X700055Y399683D01*
G01X699174Y397951D02*
X698897Y398092D01*
G01X726029Y412467D02*
X725828Y412401D01*
G01X713989Y398976D02*
X714063Y399001D01*
G01X691351Y398976D02*
X691425Y399001D01*
G01X725895Y412073D02*
X726230Y412204D01*
G01X717336Y399403D02*
X717434Y399453D01*
G01X726230Y422047D02*
X726163Y422375D01*
G01X726766Y413451D02*
X726699Y413779D01*
G01X724756Y413057D02*
X724823Y412729D01*
G01X726364Y413714D02*
X726431Y413451D01*
G01X725158Y412795D02*
X725091Y413057D01*
G01X726565Y422309D02*
X726632Y422113D01*
G01X715589Y398297D02*
X714973Y399327D01*
G01X715047Y399478D02*
X715662Y398473D01*
G01X718714Y399001D02*
X719156Y398297D01*
G01X718960D02*
X718591Y398875D01*
G01X717926Y399202D02*
X717877Y399277D01*
G01X714186Y399378D02*
X714260Y399277D01*
G01X714112D02*
X714063Y399327D01*
G01X708900Y398090D02*
X708680Y398310D01*
G01X700053Y399685D02*
X700273Y399465D01*
G01X698900Y398090D02*
X698680Y398310D01*
G01X691450Y399453D02*
X691548Y399378D01*
G01X727369Y421588D02*
X727168Y421522D01*
G01Y421916D02*
X727369Y421981D01*
G01X727905Y420407D02*
X725091Y419422D01*
G01X724756Y419685D02*
X727235Y420603D01*
G01X725292Y413911D02*
X725560Y414042D01*
G01Y414435D02*
X725292Y414304D01*
G01X708897Y399683D02*
X709174Y399824D01*
G01X700055Y398092D02*
X699778Y397951D01*
G01X698897Y399683D02*
X699174Y399824D01*
G01X726230Y412598D02*
X726029Y412467D01*
G01X717459Y399327D02*
X717385Y399277D01*
G01X726230Y412204D02*
X726498Y412401D01*
G01X725292Y414304D02*
X725024Y414107D01*
G01X714186Y398925D02*
X714088Y398850D01*
G01X718000Y398976D02*
X717385Y398423D01*
G01X717188D02*
X717877Y399051D01*
G01X718591Y398875D02*
X718418Y398699D01*
G01X717237Y399302D02*
X717336Y399403D01*
G01X714063Y399001D02*
X714112Y399051D01*
G01X718418Y398900D02*
X718960Y399478D01*
G01X719156D02*
X718714Y399001D01*
G01X732823Y428514D02*
Y408632D01*
G01X727905Y412204D02*
Y414435D01*
G01Y417323D02*
Y414960D01*
G01Y418438D02*
Y417848D01*
G01Y420997D02*
Y420407D01*
G01Y423950D02*
Y422375D01*
G01Y426968D02*
Y424475D01*
G01X718049Y399302D02*
X718074Y399202D01*
G01X714260Y399277D02*
X714284Y399202D01*
G01X714137D02*
X714112Y399277D01*
G01X708681Y398308D02*
X708540Y398584D01*
G01X700272Y399467D02*
X700413Y399191D01*
G01X691548Y399378D02*
X691622Y399277D01*
G01X691474D02*
X691425Y399327D01*
G01X727637Y421785D02*
X727369Y421588D01*
G01X691548Y398925D02*
X691450Y398850D01*
G01X727369Y421981D02*
X727503Y422113D01*
G01X708680Y399465D02*
X708900Y399685D01*
G01X700273Y398310D02*
X700053Y398090D01*
G01X698680Y399465D02*
X698900Y399685D01*
G01X727838Y422047D02*
X727637Y421785D01*
G01X714260Y399026D02*
X714186Y398925D01*
G01X726364Y412795D02*
X726230Y412598D01*
G01X725158Y413714D02*
X725292Y413911D01*
G01X718049Y399051D02*
X718000Y398976D01*
G01X717385Y399277D02*
X717336Y399202D01*
G01X726498Y412401D02*
X726699Y412729D01*
G01X725024Y414107D02*
X724823Y413779D01*
G01X708540Y399191D02*
X708681Y399467D01*
G01X717877Y399051D02*
X717926Y399152D01*
G01X727503Y422113D02*
X727570Y422309D01*
G01X714284Y399101D02*
X714260Y399026D01*
G01X714112Y399051D02*
X714137Y399126D01*
G01X726431Y413057D02*
X726364Y412795D01*
G01X725091Y413451D02*
X725158Y413714D01*
G01X718074Y399152D02*
X718049Y399051D01*
G01X717213Y399202D02*
X717237Y399302D01*
G01X726699Y412729D02*
X726766Y413057D01*
G01X727905Y422375D02*
X727838Y422047D01*
G01X724823Y413779D02*
X724756Y413451D01*
G01X727570Y425918D02*
Y426968D01*
G01Y424475D02*
Y425525D01*
G01Y422309D02*
Y423556D01*
G01Y415354D02*
Y417323D01*
G01Y414107D02*
Y412204D01*
G01X726766Y413057D02*
Y413451D01*
G01X726565Y423556D02*
Y422309D01*
G01X726431Y413451D02*
Y413057D01*
G01X726163Y422375D02*
Y423556D01*
G01Y414435D02*
Y413976D01*
G01X725560Y414042D02*
Y414435D01*
G01X725091Y413057D02*
Y413451D01*
G01X724756Y425525D02*
Y425918D01*
G01Y423556D02*
Y423950D01*
G01Y420603D02*
Y420997D01*
G01Y419160D02*
Y419685D01*
G01Y416273D02*
Y416666D01*
G01Y417848D02*
Y418241D01*
G01Y413451D02*
Y413057D01*
G01X720618Y408632D02*
Y428514D01*
G01X719043Y481959D02*
Y441801D01*
G01X718418Y399478D02*
Y398900D01*
G01Y398699D02*
Y398297D01*
G01X718271D02*
Y399478D01*
G01X718074Y398423D02*
Y398297D01*
G01Y399202D02*
Y399152D01*
G01X717926D02*
Y399202D01*
G01X717232Y437273D02*
Y436092D01*
G01X717194D02*
Y437273D01*
G01X717188Y398297D02*
Y398423D01*
G01X717166Y437273D02*
Y436092D01*
G01X716524Y483927D02*
Y439833D01*
G01X715833Y436092D02*
Y437273D01*
G01X715810Y399478D02*
Y398297D01*
G01X715736Y438533D02*
Y485226D01*
G01Y437273D02*
Y436092D01*
G01X715662Y398473D02*
Y399478D01*
G01X715657Y437470D02*
Y441801D01*
G01X715629Y446839D02*
Y453298D01*
G01X715613Y448100D02*
Y452037D01*
G01X715433Y436092D02*
Y437273D01*
G01X714973Y399327D02*
Y398297D01*
G01X714949Y448261D02*
Y451865D01*
G01Y436092D02*
Y437273D01*
G01X714826Y398297D02*
Y399478D01*
G01X714629D02*
Y398297D01*
G01X714555Y438533D02*
Y485226D01*
G01X714520Y446814D02*
Y453323D01*
G01X714481Y398297D02*
Y399478D01*
G01X714476Y439439D02*
Y484321D01*
G01X714379Y453084D02*
Y447054D01*
G01X714284Y399202D02*
Y399101D01*
G01X714137Y399126D02*
Y399202D01*
G01X713926Y437273D02*
Y436092D01*
G01X713718Y452037D02*
Y448100D01*
G01X713687Y447105D02*
Y453032D01*
G01X713571Y447109D02*
Y453028D01*
G01X713531Y437273D02*
Y436092D01*
G01X713522Y399353D02*
Y398976D01*
G01Y398825D02*
Y398297D01*
G01X713410Y452997D02*
Y447141D01*
G01X713374Y436092D02*
Y437276D01*
G01Y398297D02*
Y399478D01*
G01Y453007D02*
Y447131D01*
G01X713295Y484321D02*
Y439439D01*
G01X713269Y453109D02*
Y447028D01*
G01X713096Y447041D02*
Y453096D01*
G01X712980Y447045D02*
Y453092D01*
G01X712744Y436092D02*
Y437273D01*
G01X712587D02*
Y436092D01*
G01Y452037D02*
Y448100D01*
G01X712508Y437470D02*
Y438651D01*
G01X702055Y437712D02*
X701914Y438630D01*
G01X701827Y437698D02*
X701968Y436780D01*
G01X708541Y398582D02*
X708492Y398889D01*
G01X700412Y399193D02*
X700461Y398886D01*
G01X698541Y398582D02*
X698492Y398889D01*
G01X695534Y399378D02*
X695756Y398699D01*
G01X695879Y398297D02*
X695780Y398599D01*
G01X691622Y399277D02*
X691647Y399202D01*
G01X691499D02*
X691474Y399277D01*
G01X695633Y399478D02*
X696027Y398297D01*
G01X698681Y398308D02*
X698540Y398584D01*
G01X692951Y398297D02*
X692336Y399327D01*
G01X692409Y399478D02*
X693025Y398473D01*
G01X691425Y399001D02*
X691474Y399051D01*
G01X694698Y399277D02*
X694550Y399101D01*
G01Y399302D02*
X694698Y399478D01*
G01X691622Y399026D02*
X691548Y398925D01*
G01X700413Y398584D02*
X700272Y398308D01*
G01X698540Y399191D02*
X698681Y399467D01*
G01X708492Y398886D02*
X708541Y399193D01*
G01X700461Y398889D02*
X700412Y398582D01*
G01X698492Y398886D02*
X698541Y399193D01*
G01X706985Y436780D02*
X707126Y437698D01*
G01X707039Y438630D02*
X706898Y437712D01*
G01X702754Y436341D02*
X702841Y437273D01*
G01X701968Y436780D02*
X702055Y437712D01*
G01X712350Y441998D02*
Y441801D01*
G01Y452431D02*
Y447707D01*
G01X712335Y452966D02*
Y447171D01*
G01X712193Y453007D02*
Y447131D01*
G01X711957Y437273D02*
Y434714D01*
G01X711720Y481210D02*
Y442549D01*
G01X711588Y447313D02*
Y444951D01*
G01X711169Y437273D02*
Y436092D01*
G01X710972Y447903D02*
Y444360D01*
G01X710776Y447707D02*
Y444557D01*
G01X710775Y436092D02*
Y437273D01*
G01X710512Y444557D02*
Y447707D01*
G01X710471Y444557D02*
Y447707D01*
G01X710382Y404096D02*
Y393679D01*
G01Y437273D02*
Y436092D01*
G01X710375Y437273D02*
Y436092D01*
G01X710342Y443081D02*
Y449183D01*
G01X710244D02*
Y443081D01*
G01X710224Y481762D02*
Y441998D01*
G01X710137Y443671D02*
Y448592D01*
G01X709988Y447707D02*
Y444557D01*
G01X709830D02*
Y447707D01*
G01X709791Y447903D02*
Y444360D01*
G01X709720Y444557D02*
Y447707D01*
G01X709457Y443081D02*
Y449183D01*
G01X709403Y443671D02*
Y448592D01*
G01X709358Y443651D02*
Y443081D01*
G01Y449183D02*
Y448612D01*
G01X709267Y437273D02*
Y436092D01*
G01X708965Y437273D02*
Y436092D01*
G01X708868Y437273D02*
Y436092D01*
G01X708807Y444951D02*
Y443651D01*
G01Y448612D02*
Y447313D01*
G01X708610Y444360D02*
Y447903D01*
G01X708496Y436092D02*
Y437273D01*
G01X708420Y436092D02*
Y437273D01*
G01X708177Y436092D02*
Y437273D01*
G01X707714D02*
Y436092D01*
G01X707705Y450856D02*
Y449281D01*
G01X707535Y436092D02*
Y437273D01*
G01X707508Y450659D02*
Y449478D01*
G01X707507Y437273D02*
Y436092D01*
G01X707468Y437273D02*
Y436092D01*
G01X707404Y443671D02*
Y448592D01*
G01X707350D02*
Y443671D01*
G01X706937Y450266D02*
Y445935D01*
G01X706875Y450659D02*
Y449478D01*
G01X706670Y443671D02*
Y448592D01*
G01X706563D02*
Y443671D01*
G01X706524Y450659D02*
Y449478D01*
G01X706510Y444951D02*
Y447313D01*
G01X706445Y448612D02*
Y443651D01*
G01X706366Y448592D02*
Y443671D01*
G01X706327Y448612D02*
Y443651D01*
G01X706242Y450659D02*
Y449478D01*
G01X706169Y443671D02*
Y448592D01*
G01X705972Y441998D02*
Y481762D01*
G01X705756Y450266D02*
Y445935D01*
G01X705657Y450955D02*
Y449183D01*
G01X705579Y448612D02*
Y443651D01*
G01X705539Y449281D02*
Y445108D01*
G01X705461D02*
Y451092D01*
G01X705418Y446722D02*
Y450659D01*
G01X705264Y448612D02*
Y443651D01*
G01X704476Y440029D02*
Y483730D01*
G01X704449Y446722D02*
Y450659D01*
G01X704324Y448888D02*
Y447313D01*
G01X704083Y441998D02*
Y441210D01*
G01X703928Y450659D02*
Y446730D01*
G01X703911Y447313D02*
Y448888D01*
G01X703323Y446722D02*
Y450659D01*
G01X703295D02*
Y446132D01*
G01X702353Y446722D02*
Y450659D01*
G01X702311D02*
Y446722D01*
G01X702213Y450069D02*
Y446132D01*
G01X702016Y450266D02*
Y445935D01*
G01X701484Y437273D02*
Y436092D01*
G01X701446D02*
Y437273D01*
G01X701418D02*
Y436092D01*
G01X701238D02*
Y437273D01*
G01X701228Y450266D02*
Y445935D01*
G01X701031Y446132D02*
Y450069D01*
G01X700933Y441210D02*
Y441998D01*
G01X700776Y437273D02*
Y436092D01*
G01X700539Y443376D02*
Y440620D01*
G01X700532Y437273D02*
Y436092D01*
G01X700456Y437273D02*
Y436092D01*
G01X700085D02*
Y437273D01*
G01X700047Y450069D02*
Y446132D01*
G01X699988Y437273D02*
Y436092D01*
G01X699949Y450856D02*
Y445738D01*
G01X699850Y450266D02*
Y445935D01*
G01X699685Y436092D02*
Y437273D01*
G01X698669Y450266D02*
Y445935D01*
G01X698578Y436092D02*
Y437273D01*
G01X698571D02*
Y436092D01*
G01X698178Y437273D02*
Y436092D01*
G01X697783Y437273D02*
Y436092D01*
G01X706898Y437712D02*
X706985Y436780D01*
G01X706112Y437273D02*
X706199Y436341D01*
G01X705972Y441998D02*
X704476Y440502D01*
G01Y442549D02*
X705264Y443651D01*
G01X704476Y450423D02*
X705264Y451525D01*
G01X700606Y436092D02*
X701752Y437851D01*
G01X701727Y439013D02*
X700593Y437273D01*
G01X695042Y398297D02*
X695436Y399478D01*
G01X695288Y398599D02*
X695190Y398297D01*
G01X695313Y398699D02*
X695534Y399378D01*
G01X691647Y399101D02*
X691622Y399026D01*
G01X691474Y399051D02*
X691499Y399126D01*
G01X696996Y437273D02*
Y434714D01*
G01X696760Y453007D02*
Y447131D01*
G01X696618Y447171D02*
Y452966D01*
G01X696602Y447707D02*
Y452431D01*
G01Y441801D02*
Y441998D01*
G01X696445Y438651D02*
Y437470D01*
G01X696366Y448100D02*
Y452037D01*
G01Y436092D02*
Y437273D01*
G01X696209D02*
Y436092D01*
G01X695973Y453092D02*
Y447045D01*
G01X695857Y453096D02*
Y447041D01*
G01X695683Y447028D02*
Y453109D01*
G01X695657Y439439D02*
Y484321D01*
G01X695579Y436092D02*
Y437276D01*
G01Y453007D02*
Y447131D01*
G01X695543Y447141D02*
Y452997D01*
G01X695420Y437273D02*
Y436092D01*
G01X695382Y453028D02*
Y447109D01*
G01X695266Y453032D02*
Y447105D01*
G01X695235Y448100D02*
Y452037D01*
G01X695027Y436092D02*
Y437273D01*
G01X694845Y399478D02*
Y398297D01*
G01X694698D02*
Y399277D01*
G01X694574Y447054D02*
Y453084D01*
G01X694550Y399101D02*
Y399302D01*
G01X694476Y484321D02*
Y439439D01*
G01X694433Y453323D02*
Y446814D01*
G01X694398Y485226D02*
Y438533D01*
G01X694004Y437273D02*
Y436092D01*
G01Y451865D02*
Y448272D01*
G01X693519Y437273D02*
Y436092D01*
G01X693340Y452037D02*
Y448100D01*
G01X693323Y453298D02*
Y446839D01*
G01X693295Y437470D02*
Y441801D01*
G01X693217Y437273D02*
Y436092D01*
G01Y485226D02*
Y438533D01*
G01X693172Y399478D02*
Y398297D01*
G01X693120Y437273D02*
Y436092D01*
G01X693025Y398473D02*
Y399478D01*
G01X692429Y439833D02*
Y461860D01*
G01X692336Y399327D02*
Y398297D01*
G01X692188D02*
Y399478D01*
G01X691991D02*
Y398297D01*
G01X691843D02*
Y399478D01*
G01X691787Y436092D02*
Y437273D01*
G01X691759D02*
Y436092D01*
G01X691720Y437273D02*
Y436092D01*
G01X691647Y399202D02*
Y399101D01*
G01X691499Y399126D02*
Y399202D01*
G01X690884Y399353D02*
Y398976D01*
G01Y398825D02*
Y398297D01*
G01X690736D02*
Y399478D01*
G01X689909Y461860D02*
Y441801D01*
G01X748571Y506286D02*
Y615029D01*
G01X693264Y470449D02*
X693323Y470461D01*
G01X693228Y470436D02*
X693264Y470449D01*
G01X693217Y470424D02*
X693228Y470436D01*
G01X702611Y486465D02*
X702841Y486486D01*
G01X702401Y486404D02*
X702611Y486465D01*
G01X702229Y486308D02*
X702401Y486404D01*
G01X702110Y486186D02*
X702229Y486308D01*
G01X702055Y486048D02*
X702110Y486186D01*
G01X715688Y476933D02*
X715629Y476920D01*
G01X715724Y476945D02*
X715688Y476933D01*
G01X715736Y476958D02*
X715724Y476945D01*
G01X714934Y471660D02*
X714949Y471894D01*
G01X714891Y471446D02*
X714934Y471660D01*
G01X714823Y471273D02*
X714891Y471446D01*
G01X714737Y471157D02*
X714823Y471273D01*
G01X714640Y471108D02*
X714737Y471157D01*
G01X694018Y475719D02*
X694004Y475487D01*
G01X694062Y475934D02*
X694018Y475719D01*
G01X694130Y476109D02*
X694062Y475934D01*
G01X694217Y476225D02*
X694130Y476109D01*
G01X694312Y476274D02*
X694217Y476225D01*
G01X707148Y485953D02*
X707126Y486061D01*
G01X707174Y485899D02*
X707148Y485953D01*
G01X707200Y485908D02*
X707174Y485899D01*
G01X694217Y452604D02*
X694312Y452651D01*
G01X694130Y452487D02*
X694217Y452604D01*
G01X694062Y452313D02*
X694130Y452487D01*
G01X694018Y452097D02*
X694062Y452313D01*
G01X694004Y451865D02*
X694018Y452097D01*
G01X704235Y465197D02*
X704383Y465226D01*
G01X704102Y465110D02*
X704235Y465197D01*
G01X703998Y464976D02*
X704102Y465110D01*
G01X703933Y464811D02*
X703998Y464976D01*
G01X703911Y464636D02*
X703933Y464811D01*
G01X704235Y457323D02*
X704383Y457352D01*
G01X704102Y457236D02*
X704235Y457323D01*
G01X703998Y457102D02*
X704102Y457236D01*
G01X703933Y456937D02*
X703998Y457102D01*
G01X703911Y456762D02*
X703933Y456937D01*
G01X704086Y463926D02*
X703928Y463856D01*
G01X704215Y464061D02*
X704086Y463926D01*
G01X704297Y464241D02*
X704215Y464061D01*
G01X704324Y464439D02*
X704297Y464241D01*
G01X704086Y456052D02*
X703928Y455982D01*
G01X704215Y456187D02*
X704086Y456052D01*
G01X704297Y456367D02*
X704215Y456187D01*
G01X704324Y456565D02*
X704297Y456367D01*
G01X701778Y485899D02*
X701752Y485908D01*
G01X701804Y485952D02*
X701778Y485899D01*
G01X701827Y486061D02*
X701804Y485952D01*
G01X714534Y465194D02*
X714508Y465185D01*
G01X714550Y465203D02*
X714534Y465194D01*
G01X714555Y465212D02*
X714550Y465203D01*
G01X715703Y465183D02*
X715661Y465169D01*
G01X715728Y465198D02*
X715703Y465183D01*
G01X715736Y465212D02*
X715728Y465198D01*
G01X715688Y453310D02*
X715629Y453298D01*
G01X715724Y453323D02*
X715688Y453310D01*
G01X715736Y453336D02*
X715724Y453323D01*
G01X714518Y459983D02*
X714529Y460214D01*
G01X714487Y459768D02*
X714518Y459983D01*
G01X714438Y459593D02*
X714487Y459768D01*
G01X714375Y459476D02*
X714438Y459593D01*
G01X714307Y459428D02*
X714375Y459476D01*
G01X712210Y464509D02*
X712283Y464488D01*
G01X712195Y464530D02*
X712210Y464509D01*
G01X712240Y464551D02*
X712195Y464530D01*
G01X703548Y459900D02*
X703459Y459911D01*
G01X703633Y459866D02*
X703548Y459900D01*
G01X703711Y459811D02*
X703633Y459866D01*
G01X703779Y459738D02*
X703711Y459811D01*
G01X703836Y459648D02*
X703779Y459738D01*
G01X703877Y459546D02*
X703836Y459648D01*
G01X703903Y459435D02*
X703877Y459546D01*
G01X703911Y459321D02*
X703903Y459435D01*
G01X703548Y467774D02*
X703459Y467785D01*
G01X703633Y467740D02*
X703548Y467774D01*
G01X703711Y467685D02*
X703633Y467740D01*
G01X703779Y467612D02*
X703711Y467685D01*
G01X703836Y467522D02*
X703779Y467612D01*
G01X703877Y467420D02*
X703836Y467522D01*
G01X703903Y467309D02*
X703877Y467420D01*
G01X703911Y467195D02*
X703903Y467309D01*
G01X704907Y458545D02*
X704996Y458533D01*
G01X704823Y458579D02*
X704907Y458545D01*
G01X704745Y458633D02*
X704823Y458579D01*
G01X704677Y458706D02*
X704745Y458633D01*
G01X704620Y458797D02*
X704677Y458706D01*
G01X704578Y458899D02*
X704620Y458797D01*
G01X704553Y459009D02*
X704578Y458899D01*
G01X704544Y459124D02*
X704553Y459009D01*
G01X704907Y466419D02*
X704996Y466407D01*
G01X704823Y466453D02*
X704907Y466419D01*
G01X704745Y466507D02*
X704823Y466453D01*
G01X704677Y466580D02*
X704745Y466507D01*
G01X704620Y466671D02*
X704677Y466580D01*
G01X704578Y466773D02*
X704620Y466671D01*
G01X704553Y466883D02*
X704578Y466773D01*
G01X704544Y466998D02*
X704553Y466883D01*
G01X703427Y477022D02*
X703308Y477037D01*
G01X703540Y476977D02*
X703427Y477022D01*
G01X703644Y476904D02*
X703540Y476977D01*
G01X703735Y476807D02*
X703644Y476904D01*
G01X703811Y476686D02*
X703735Y476807D01*
G01X703866Y476550D02*
X703811Y476686D01*
G01X703900Y476403D02*
X703866Y476550D01*
G01X703911Y476250D02*
X703900Y476403D01*
G01X705028Y474297D02*
X705147Y474281D01*
G01X704915Y474342D02*
X705028Y474297D01*
G01X704812Y474414D02*
X704915Y474342D01*
G01X704721Y474512D02*
X704812Y474414D01*
G01X704645Y474633D02*
X704721Y474512D01*
G01X704590Y474769D02*
X704645Y474633D01*
G01X704556Y474916D02*
X704590Y474769D01*
G01X704544Y475069D02*
X704556Y474916D01*
G01X694217Y471156D02*
X694312Y471108D01*
G01X694130Y471272D02*
X694217Y471156D01*
G01X694062Y471447D02*
X694130Y471272D01*
G01X694018Y471662D02*
X694062Y471447D01*
G01X694004Y471894D02*
X694018Y471662D01*
G01X713249Y459499D02*
X713180Y459450D01*
G01X713311Y459616D02*
X713249Y459499D01*
G01X713360Y459788D02*
X713311Y459616D01*
G01X713391Y460001D02*
X713360Y459788D01*
G01X713402Y460236D02*
X713391Y460001D01*
G01X714737Y452602D02*
X714640Y452651D01*
G01X714823Y452486D02*
X714737Y452602D01*
G01X714891Y452314D02*
X714823Y452486D01*
G01X714934Y452100D02*
X714891Y452314D01*
G01X714949Y451865D02*
X714934Y452100D01*
G01X714737Y476225D02*
X714640Y476274D01*
G01X714823Y476108D02*
X714737Y476225D01*
G01X714891Y475936D02*
X714823Y476108D01*
G01X714934Y475722D02*
X714891Y475936D01*
G01X714949Y475487D02*
X714934Y475722D01*
G01X714375Y464283D02*
X714307Y464332D01*
G01X714438Y464167D02*
X714375Y464283D01*
G01X714487Y463993D02*
X714438Y464167D01*
G01X714518Y463777D02*
X714487Y463993D01*
G01X714529Y463545D02*
X714518Y463777D01*
G01X707161Y484724D02*
X707226Y484747D01*
G01X707096Y484857D02*
X707161Y484724D01*
G01X707039Y485129D02*
X707096Y484857D01*
G01X706429Y487397D02*
X706199Y487418D01*
G01X706639Y487336D02*
X706429Y487397D01*
G01X706810Y487240D02*
X706639Y487336D01*
G01X706929Y487118D02*
X706810Y487240D01*
G01X706985Y486980D02*
X706929Y487118D01*
G01X693264Y453310D02*
X693323Y453298D01*
G01X693228Y453323D02*
X693264Y453310D01*
G01X693217Y453336D02*
X693228Y453323D01*
G01X694414Y453327D02*
X694433Y453323D01*
G01X694402Y453332D02*
X694414Y453327D01*
G01X694398Y453336D02*
X694402Y453332D01*
G01X694414Y476950D02*
X694433Y476945D01*
G01X694402Y476954D02*
X694414Y476950D01*
G01X694398Y476958D02*
X694402Y476954D01*
G01X714539Y470432D02*
X714520Y470436D01*
G01X714551Y470428D02*
X714539Y470432D01*
G01X714555Y470424D02*
X714551Y470428D01*
G01X713381Y459241D02*
X713410Y459250D01*
G01X713375Y459233D02*
X713381Y459241D01*
G01X713393Y459224D02*
X713375Y459233D01*
G01X713391Y463758D02*
X713402Y463534D01*
G01X713360Y463971D02*
X713391Y463758D01*
G01X713311Y464144D02*
X713360Y463971D01*
G01X713249Y464260D02*
X713311Y464144D01*
G01X713180Y464310D02*
X713249Y464260D01*
G01X712622Y453074D02*
X712980Y453092D01*
G01X712356Y453051D02*
X712622Y453074D01*
G01X712213Y453023D02*
X712356Y453051D01*
G01X712208Y452994D02*
X712213Y453023D01*
G01X712335Y452966D02*
X712208Y452994D01*
G01X715722Y452681D02*
X715715Y452682D01*
G01X715729Y452679D02*
X715722Y452681D01*
G01X715736Y452677D02*
X715729Y452679D01*
G01X714550Y458557D02*
X714555Y458548D01*
G01X714534Y458566D02*
X714550Y458557D01*
G01X714508Y458574D02*
X714534Y458566D01*
G01X715728Y458562D02*
X715736Y458548D01*
G01X715703Y458576D02*
X715728Y458562D01*
G01X715661Y458590D02*
X715703Y458576D01*
G01X696745Y452994D02*
X696618Y452966D01*
G01X696740Y453023D02*
X696745Y452994D01*
G01X696597Y453050D02*
X696740Y453023D01*
G01X696331Y453074D02*
X696597Y453050D01*
G01X695973Y453092D02*
X696331Y453074D01*
G01X694973Y453046D02*
X695266Y453032D01*
G01X694738Y453064D02*
X694973Y453046D01*
G01X694574Y453084D02*
X694738Y453064D01*
G01X695784Y453100D02*
X695857Y453096D01*
G01X695724Y453104D02*
X695784Y453100D01*
G01X695683Y453109D02*
X695724Y453104D01*
G01X703920Y459007D02*
X703911Y459124D01*
G01X703946Y458897D02*
X703920Y459007D01*
G01X703988Y458795D02*
X703946Y458897D01*
G01X704044Y458706D02*
X703988Y458795D01*
G01X704113Y458632D02*
X704044Y458706D01*
G01X704191Y458578D02*
X704113Y458632D01*
G01X704276Y458545D02*
X704191Y458578D01*
G01X704364Y458533D02*
X704276Y458545D01*
G01X704535Y459437D02*
X704544Y459321D01*
G01X704509Y459548D02*
X704535Y459437D01*
G01X704468Y459649D02*
X704509Y459548D01*
G01X704412Y459738D02*
X704468Y459649D01*
G01X704342Y459813D02*
X704412Y459738D01*
G01X704264Y459867D02*
X704342Y459813D01*
G01X704180Y459900D02*
X704264Y459867D01*
G01X704092Y459911D02*
X704180Y459900D01*
G01X713375Y464527D02*
X713393Y464535D01*
G01X713381Y464518D02*
X713375Y464527D01*
G01X713410Y464510D02*
X713381Y464518D01*
G01X701857Y484857D02*
X701914Y485129D01*
G01X701792Y484724D02*
X701857Y484857D01*
G01X701727Y484747D02*
X701792Y484724D01*
G01X714551Y453332D02*
X714555Y453336D01*
G01X714539Y453327D02*
X714551Y453332D01*
G01X714520Y453323D02*
X714539Y453327D01*
G01X693224Y452679D02*
X693217Y452677D01*
G01X693231Y452681D02*
X693224Y452679D01*
G01X693238Y452682D02*
X693231Y452681D01*
G01X713978Y453046D02*
X713687Y453032D01*
G01X714216Y453064D02*
X713978Y453046D01*
G01X714379Y453084D02*
X714216Y453064D01*
G01X713375Y453005D02*
X713410Y452997D01*
G01X713393Y453014D02*
X713375Y453005D01*
G01X713463Y453023D02*
X713393Y453014D01*
G01X713571Y453028D02*
X713463Y453023D01*
G01X713229Y453104D02*
X713269Y453109D01*
G01X713169Y453100D02*
X713229Y453104D01*
G01X713096Y453096D02*
X713169Y453100D01*
G01X714216Y470696D02*
X714379Y470676D01*
G01X713979Y470714D02*
X714216Y470696D01*
G01X713687Y470727D02*
X713979Y470714D01*
G01X712208Y470766D02*
X712335Y470793D01*
G01X712213Y470737D02*
X712208Y470766D01*
G01X712355Y470709D02*
X712213Y470737D01*
G01X712622Y470685D02*
X712355Y470709D01*
G01X712980Y470668D02*
X712622Y470685D01*
G01X713169Y470660D02*
X713096Y470663D01*
G01X713228Y470656D02*
X713169Y470660D01*
G01X713269Y470650D02*
X713228Y470656D01*
G01X695784Y476722D02*
X695857Y476718D01*
G01X695724Y476726D02*
X695784Y476722D01*
G01X695683Y476731D02*
X695724Y476726D01*
G01X703920Y466881D02*
X703911Y466998D01*
G01X703946Y466771D02*
X703920Y466881D01*
G01X703988Y466669D02*
X703946Y466771D01*
G01X704044Y466580D02*
X703988Y466669D01*
G01X704113Y466506D02*
X704044Y466580D01*
G01X704191Y466452D02*
X704113Y466506D01*
G01X704276Y466419D02*
X704191Y466452D01*
G01X704364Y466407D02*
X704276Y466419D01*
G01X704535Y467311D02*
X704544Y467195D01*
G01X704509Y467422D02*
X704535Y467311D01*
G01X704468Y467523D02*
X704509Y467422D01*
G01X704412Y467612D02*
X704468Y467523D01*
G01X704342Y467687D02*
X704412Y467612D01*
G01X704264Y467741D02*
X704342Y467687D01*
G01X704180Y467774D02*
X704264Y467741D01*
G01X704092Y467785D02*
X704180Y467774D01*
G01X703923Y474913D02*
X703911Y475069D01*
G01X703958Y474766D02*
X703923Y474913D01*
G01X704013Y474631D02*
X703958Y474766D01*
G01X704088Y474512D02*
X704013Y474631D01*
G01X704181Y474413D02*
X704088Y474512D01*
G01X704285Y474341D02*
X704181Y474413D01*
G01X704397Y474296D02*
X704285Y474341D01*
G01X704515Y474281D02*
X704397Y474296D01*
G01X704532Y476405D02*
X704544Y476250D01*
G01X704498Y476552D02*
X704532Y476405D01*
G01X704442Y476688D02*
X704498Y476552D01*
G01X704367Y476807D02*
X704442Y476688D01*
G01X704275Y476906D02*
X704367Y476807D01*
G01X704171Y476978D02*
X704275Y476906D01*
G01X704058Y477022D02*
X704171Y476978D01*
G01X703941Y477037D02*
X704058Y477022D01*
G01X693224Y471080D02*
X693217Y471082D01*
G01X693231Y471079D02*
X693224Y471080D01*
G01X693238Y471078D02*
X693231Y471079D01*
G01X715729Y476301D02*
X715736Y476299D01*
G01X715722Y476303D02*
X715729Y476301D01*
G01X715715Y476304D02*
X715722Y476303D01*
G01X715724Y470436D02*
X715736Y470424D01*
G01X715688Y470449D02*
X715724Y470436D01*
G01X715629Y470461D02*
X715688Y470449D01*
G01X693228Y476945D02*
X693217Y476958D01*
G01X693264Y476933D02*
X693228Y476945D01*
G01X693323Y476920D02*
X693264Y476933D01*
G01X712622Y476696D02*
X712980Y476714D01*
G01X712356Y476673D02*
X712622Y476696D01*
G01X712213Y476645D02*
X712356Y476673D01*
G01X712208Y476616D02*
X712213Y476645D01*
G01X712335Y476588D02*
X712208Y476616D01*
G01X712195Y459229D02*
X712240Y459208D01*
G01X712210Y459251D02*
X712195Y459229D01*
G01X712283Y459272D02*
X712210Y459251D01*
G01X695491Y453022D02*
X695382Y453028D01*
G01X695560Y453015D02*
X695491Y453022D01*
G01X695578Y453006D02*
X695560Y453015D01*
G01X695543Y452997D02*
X695578Y453006D01*
G01X703889Y456387D02*
X703911Y456565D01*
G01X703825Y456224D02*
X703889Y456387D01*
G01X703722Y456091D02*
X703825Y456224D01*
G01X703589Y456005D02*
X703722Y456091D01*
G01X703440Y455974D02*
X703589Y456005D01*
G01X703889Y464261D02*
X703911Y464439D01*
G01X703825Y464098D02*
X703889Y464261D01*
G01X703722Y463965D02*
X703825Y464098D01*
G01X703589Y463879D02*
X703722Y463965D01*
G01X703440Y463848D02*
X703589Y463879D01*
G01X704345Y456937D02*
X704324Y456762D01*
G01X704410Y457102D02*
X704345Y456937D01*
G01X704514Y457236D02*
X704410Y457102D01*
G01X704648Y457323D02*
X704514Y457236D01*
G01X704795Y457352D02*
X704648Y457323D01*
G01X704345Y464811D02*
X704324Y464636D01*
G01X704410Y464976D02*
X704345Y464811D01*
G01X704514Y465110D02*
X704410Y464976D01*
G01X704648Y465197D02*
X704514Y465110D01*
G01X704795Y465226D02*
X704648Y465197D01*
G01X703879Y455975D02*
X703854Y455974D01*
G01X703903Y455978D02*
X703879Y455975D01*
G01X703928Y455982D02*
X703903Y455978D01*
G01X703879Y463849D02*
X703854Y463848D01*
G01X703903Y463852D02*
X703879Y463849D01*
G01X703928Y463856D02*
X703903Y463852D01*
G01X694974Y470714D02*
X695266Y470727D01*
G01X694737Y470696D02*
X694974Y470714D01*
G01X694574Y470676D02*
X694737Y470696D01*
G01X695578Y470754D02*
X695543Y470763D01*
G01X695560Y470745D02*
X695578Y470754D01*
G01X695490Y470737D02*
X695560Y470745D01*
G01X695382Y470731D02*
X695490Y470737D01*
G01X713375Y476627D02*
X713410Y476619D01*
G01X713393Y476637D02*
X713375Y476627D01*
G01X713463Y476645D02*
X713393Y476637D01*
G01X713571Y476650D02*
X713463Y476645D01*
G01X696746Y470766D02*
X696618Y470793D01*
G01X696739Y470737D02*
X696746Y470766D01*
G01X696598Y470709D02*
X696739Y470737D01*
G01X696335Y470685D02*
X696598Y470709D01*
G01X695973Y470668D02*
X696335Y470685D01*
G01X695725Y470656D02*
X695683Y470650D01*
G01X695783Y470660D02*
X695725Y470656D01*
G01X695857Y470663D02*
X695783Y470660D01*
G01X713229Y476726D02*
X713269Y476731D01*
G01X713169Y476722D02*
X713229Y476726D01*
G01X713096Y476718D02*
X713169Y476722D01*
G01X694736Y476686D02*
X694574Y476706D01*
G01X694974Y476668D02*
X694736Y476686D01*
G01X695266Y476655D02*
X694974Y476668D01*
G01X696745Y476616D02*
X696618Y476588D01*
G01X696740Y476645D02*
X696745Y476616D01*
G01X696597Y476672D02*
X696740Y476645D01*
G01X696331Y476696D02*
X696597Y476672D01*
G01X695973Y476714D02*
X696331Y476696D01*
G01X706843Y486186D02*
X706898Y486048D01*
G01X706724Y486308D02*
X706843Y486186D01*
G01X706552Y486404D02*
X706724Y486308D01*
G01X706342Y486465D02*
X706552Y486404D01*
G01X706112Y486486D02*
X706342Y486465D01*
G01X715722Y471079D02*
X715715Y471078D01*
G01X715729Y471080D02*
X715722Y471079D01*
G01X715736Y471082D02*
X715729Y471080D01*
G01X693231Y476303D02*
X693238Y476304D01*
G01X693224Y476301D02*
X693231Y476303D01*
G01X693217Y476299D02*
X693224Y476301D01*
G01X713463Y470737D02*
X713571Y470731D01*
G01X713393Y470745D02*
X713463Y470737D01*
G01X713375Y470754D02*
X713393Y470745D01*
G01X713410Y470763D02*
X713375Y470754D01*
G01X695490Y476645D02*
X695382Y476650D01*
G01X695560Y476637D02*
X695490Y476645D01*
G01X695578Y476627D02*
X695560Y476637D01*
G01X695543Y476619D02*
X695578Y476627D01*
G01X694402Y470428D02*
X694398Y470424D01*
G01X694414Y470432D02*
X694402Y470428D01*
G01X694433Y470436D02*
X694414Y470432D01*
G01X714551Y476954D02*
X714555Y476958D01*
G01X714539Y476950D02*
X714551Y476954D01*
G01X714520Y476945D02*
X714539Y476950D01*
G01X713978Y476668D02*
X713687Y476655D01*
G01X714216Y476686D02*
X713978Y476668D01*
G01X714379Y476706D02*
X714216Y476686D01*
G01X702022Y487116D02*
X701968Y486980D01*
G01X702141Y487240D02*
X702022Y487116D01*
G01X702315Y487336D02*
X702141Y487240D01*
G01X702527Y487398D02*
X702315Y487336D01*
G01X702754Y487418D02*
X702527Y487398D01*
G01X748571Y502349D02*
G03X745879Y506084I-3937J0D01*
G01X736760Y511962D02*
G03X739452Y508226I3937J-1D01*
G01X736760Y511962D02*
G03X739452Y508226I3937J-1D01*
G01X748571Y502349D02*
G03X745879Y506084I-3937J0D01*
G01X717272Y538651D02*
G03I-12796J0D01*
G01X717862D02*
G03I-13386J0D01*
G01X718059D02*
G03I-13583J0D01*
G01X696602Y526867D02*
G03X712351I7875J11784D01*
G01X719240Y538651D02*
G03I-14764J0D01*
G01X720028D02*
G03I-15552J0D01*
G01X722471D02*
G03I-17995J0D01*
G01X723253D02*
G03I-18777J0D01*
G01X724161D02*
G03I-19685J0D01*
G01X711957Y489045D02*
G03X709988Y491014I-1969J0D01*
G01X745879Y480667D02*
G03X748571Y484402I-1245J3735D01*
G01X739452Y478525D02*
G03X736760Y474790I1245J-3735D01*
G01X739452Y478525D02*
G03X736760Y474790I1245J-3735D01*
G01X745879Y480667D02*
G03X748571Y484402I-1245J3735D01*
G01X713295Y484321D02*
G03X712508Y485108I-787J0D01*
G01X714555Y485226D02*
G03X713295Y486486I-1260J0D01*
G01X714476Y484321D02*
G03X712508Y486289I-1968J0D01*
G01X719043Y481959D02*
G03X717075Y483927I-1968J0D01*
G01X715736Y485226D02*
G03X713295Y487667I-2441J0D01*
G01X711720Y481210D02*
G03X709201Y483730I-2520J0D01*
G01X698965Y491014D02*
G03X696996Y489045I0J-1969D01*
G01X696445Y485108D02*
G03X695657Y484321I0J-788D01*
G01Y486486D02*
G03X694398Y485226I0J-1259D01*
G01X696445Y486289D02*
G03X694476Y484321I0J-1969D01*
G01X691878Y483927D02*
G03X689909Y481959I0J-1969D01*
G01X695657Y487667D02*
G03X693217Y485226I0J-2440D01*
G01X689713Y526447D02*
X686957D01*
G01X721996D02*
X719240D01*
G01X716878Y526250D02*
X692075D01*
G01X687350Y523888D02*
X721602D01*
G01X686957Y523494D02*
X721996D01*
G01X686957Y520935D02*
X721996D01*
G01X740421Y501168D02*
X744358D01*
G01X742264Y500676D02*
X740421D01*
G01X744358D02*
X742767D01*
G01Y498379D02*
X744358D01*
G01X740421D02*
X742264D01*
G01X742097Y494853D02*
X741594Y494770D01*
G01X742683Y492720D02*
X743186Y492802D01*
G01X742013Y495263D02*
X741594Y495181D01*
G01X742767Y492310D02*
X743186Y492392D01*
G01X745879Y506084D02*
X739452Y508227D01*
G01X745879Y506084D02*
X739452Y508227D01*
G01X743186Y495181D02*
X742767Y495263D01*
G01X743186Y494770D02*
X742683Y494853D01*
G01X741594Y492802D02*
X742097Y492720D01*
G01X744358Y497887D02*
X740421D01*
G01X742767Y497231D02*
X743102D01*
G01X741761D02*
X742097D01*
G01Y495919D02*
X741761D01*
G01X743102D02*
X742767D01*
G01Y495263D02*
X742013D01*
G01X742683Y494853D02*
X742097D01*
G01Y492720D02*
X742683D01*
G01X742013Y492310D02*
X742767D01*
G01X740421Y491654D02*
X743102D01*
G01X742515Y491244D02*
X740421D01*
G01X743102D02*
X742850D01*
G01X709988Y491014D02*
X698965D01*
G01X740421Y490341D02*
X742432D01*
G01Y489931D02*
X740421D01*
G01Y489029D02*
X742432D01*
G01Y488619D02*
X740421D01*
G01X696996Y488455D02*
X711957D01*
G01X740421Y487963D02*
X743102D01*
G01X691721Y487667D02*
X717231D01*
G01X742515Y487553D02*
X740421D01*
G01X743102D02*
X742850D01*
G01X702754Y487418D02*
X706199D01*
G01X740421Y486650D02*
X742432D01*
G01X691721Y486486D02*
X717231D01*
G01X715657Y486289D02*
X693295D01*
G01X742432Y486240D02*
X740421D01*
G01X707126Y486061D02*
X701827D01*
G01X701752Y485908D02*
X707200D01*
G01X707183Y485896D02*
X701769D01*
G01X740421Y485338D02*
X742432D01*
G01X707039Y485129D02*
X701914D01*
G01X696445Y485108D02*
X712508D01*
G01X742432Y484928D02*
X740421D01*
G01X701727Y484747D02*
X707226D01*
G01X694398Y484714D02*
X693217D01*
G01X707183D02*
X701769D01*
G01X715736D02*
X714555D01*
G01X695657Y484321D02*
X694476D01*
G01X714476D02*
X713295D01*
G01X694398Y483927D02*
X691878D01*
G01X717075D02*
X714555D01*
G01X704476Y483730D02*
X709201D01*
G01X714476Y483140D02*
X715657D01*
G01X693295D02*
X694476D01*
G01X704476D02*
X700539D01*
G01X693238Y476304D02*
X695543Y476619D01*
G01X696618Y476588D02*
X694312Y476274D01*
G01X713269Y476731D02*
X714520Y476945D01*
G01X715629Y476920D02*
X714379Y476706D01*
G01X693323Y470461D02*
X694574Y470676D01*
G01X695683Y470650D02*
X694433Y470436D01*
G01X743437Y495099D02*
X743186Y495181D01*
G01X741343Y492474D02*
X741594Y492392D01*
G01D02*
X742013Y492310D01*
G01X695857Y476718D02*
X695973Y476714D01*
G01X695382Y476650D02*
X695266Y476655D01*
G01X713571Y470731D02*
X713687Y470727D01*
G01X713096Y470663D02*
X712980Y470668D01*
G01X694312Y476274D02*
X693238Y476304D01*
G01X693217Y475510D02*
X694004Y475487D01*
G01X715736Y471872D02*
X714949Y471894D01*
G01X714640Y471108D02*
X715715Y471078D01*
G01X714555Y482549D02*
X715736D01*
G01X693217D02*
X694398D01*
G01X704083D02*
X700933D01*
G01X693295Y481959D02*
X715657D01*
G01X696602Y481762D02*
X712350D01*
G01X694398D02*
X693217D01*
G01X715736D02*
X714555D01*
G01X710342Y480679D02*
X709358D01*
G01X709457Y480659D02*
X710244D01*
G01X709457Y480581D02*
X710244D01*
G01Y480506D02*
X709457D01*
G01Y480482D02*
X710244D01*
G01Y480446D02*
X709457D01*
G01X704476Y480384D02*
X700539D01*
G01X710244Y480358D02*
X709457D01*
G01X710244Y480335D02*
X709457D01*
G01Y480305D02*
X710244D01*
G01X709457Y480187D02*
X710244D01*
G01X705264Y480108D02*
X710342D01*
G01X705579Y480088D02*
X710244D01*
G01X697350Y480079D02*
X704476D01*
G01X714555Y479793D02*
X715736D01*
G01X693217D02*
X694398D01*
G01X708610Y479399D02*
X710972D01*
G01X710776Y479203D02*
X709457D01*
G01X704476Y479188D02*
X698563D01*
G01X694398Y479006D02*
X693217D01*
G01X715736D02*
X714555D01*
G01X711720Y478809D02*
X706510D01*
G01X705539Y478651D02*
X704476D01*
G01X705461Y478478D02*
X704476D01*
G01X710776Y478415D02*
X709988D01*
G01X705461Y478386D02*
X704476D01*
G01Y478336D02*
X705461D01*
G01X699625Y478297D02*
X698412D01*
G01X705461Y478289D02*
X704476D01*
G01X709988Y478218D02*
X710776D01*
G01X705461D02*
X704476D01*
G01X705461Y478120D02*
X704476D01*
G01X699949Y478022D02*
X705539D01*
G01X714555Y478008D02*
X715736D01*
G01X693217D02*
X694398D01*
G01X698669Y477825D02*
X706937D01*
G01X705461Y477628D02*
X700047D01*
G01X705461Y477268D02*
X704476D01*
G01X694398Y477234D02*
X693217D01*
G01X715736D02*
X714555D01*
G01X694398Y477223D02*
X693217D01*
G01X715736D02*
X714555D01*
G01Y477195D02*
X715736D01*
G01X693217D02*
X694398D01*
G01X709988Y477037D02*
X710776D01*
G01X702311D02*
X705461D01*
G01X710776Y476840D02*
X709988D01*
G01X701031Y476447D02*
X700047D01*
G01X711720D02*
X706510D01*
G01X700047Y476250D02*
X701031D01*
G01X704544D02*
X703911D01*
G01X709457Y476053D02*
X710776D01*
G01X696602D02*
X694476D01*
G01X714476D02*
X712350D01*
G01X708610Y475856D02*
X710972D01*
G01X712587Y475659D02*
X715736D01*
G01X696366D02*
X693217D01*
G01X710244Y475167D02*
X705579D01*
G01X710342Y475147D02*
X705264D01*
G01X709457Y475069D02*
X710244D01*
G01X700047D02*
X701031D01*
G01X704544D02*
X703911D01*
G01X710244Y474951D02*
X709457D01*
G01Y474921D02*
X710244D01*
G01X709457Y474898D02*
X710244D01*
G01X701031Y474872D02*
X700047D01*
G01X709457Y474809D02*
X710244D01*
G01Y474773D02*
X709457D01*
G01Y474750D02*
X710244D01*
G01Y474675D02*
X709457D01*
G01X710244Y474596D02*
X709457D01*
G01X711720Y474577D02*
X705539D01*
G01X707705Y474478D02*
X705539D01*
G01X707508Y474281D02*
X704515D01*
G01X700047Y473691D02*
X705461D01*
G01X698669Y473494D02*
X706937D01*
G01X705461Y473199D02*
X704476D01*
G01X707508Y473100D02*
X702311D01*
G01X704476Y473029D02*
X705461D01*
G01Y472982D02*
X704476D01*
G01Y472933D02*
X705461D01*
G01X707705Y472903D02*
X699949D01*
G01X704476Y472870D02*
X705461D01*
G01X704476Y472840D02*
X705461D01*
G01X711720Y472805D02*
X705657D01*
G01X709457Y472785D02*
X710244D01*
G01X709457Y472707D02*
X710244D01*
G01X705539Y472667D02*
X704476D01*
G01X710244Y472632D02*
X709457D01*
G01Y472608D02*
X710244D01*
G01Y472572D02*
X709457D01*
G01X710244Y472484D02*
X709457D01*
G01X710244Y472460D02*
X709457D01*
G01Y472431D02*
X710244D01*
G01X709457Y472313D02*
X710244D01*
G01X705264Y472234D02*
X710342D01*
G01X705579Y472214D02*
X710244D01*
G01X696366Y471722D02*
X693217D01*
G01X715736D02*
X712587D01*
G01X708610Y471525D02*
X710972D01*
G01X696602Y471329D02*
X694476D01*
G01X710776D02*
X709457D01*
G01X714476D02*
X712350D01*
G01X711720Y470935D02*
X706510D01*
G01X710776Y470541D02*
X709988D01*
G01Y470344D02*
X710776D01*
G01X694398Y470187D02*
X693217D01*
G01X715736D02*
X714555D01*
G01Y470159D02*
X715736D01*
G01X693217D02*
X694398D01*
G01X714555Y470147D02*
X715736D01*
G01X693217D02*
X694398D01*
G01Y469373D02*
X693217D01*
G01X715736D02*
X714555D01*
G01X709988Y469163D02*
X710776D01*
G01Y468966D02*
X709988D01*
G01X705539Y468809D02*
X704476D01*
G01X705461Y468636D02*
X704476D01*
G01X711720Y468573D02*
X706510D01*
G01X715736D02*
X714555D01*
G01X705461Y468543D02*
X704476D01*
G01Y468494D02*
X705461D01*
G01Y468447D02*
X704476D01*
G01X714555Y468376D02*
X715736D01*
G01X694398D02*
X693217D01*
G01X705461D02*
X704476D01*
G01X705461Y468277D02*
X704476D01*
G01X709457Y468179D02*
X710776D01*
G01X705539D02*
X699949D01*
G01X708610Y467982D02*
X710972D01*
G01X698669D02*
X706937D01*
G01X705461Y467958D02*
X704476D01*
G01X715715Y476304D02*
X714640Y476274D01*
G01X714949Y475487D02*
X715736Y475510D01*
G01X694004Y471894D02*
X693217Y471872D01*
G01X693238Y471078D02*
X694312Y471108D01*
G01X712980Y476714D02*
X713096Y476718D01*
G01X713687Y476655D02*
X713571Y476650D01*
G01X695266Y470727D02*
X695382Y470731D01*
G01X695973Y470668D02*
X695857Y470663D01*
G01X712335Y470793D02*
X714640Y471108D01*
G01X715715Y471078D02*
X713410Y470763D01*
G01X713180Y459450D02*
X712283Y459272D01*
G01X713410Y459250D02*
X714307Y459428D01*
G01X714508Y465185D02*
X712240Y464551D01*
G01X713393Y464535D02*
X715661Y465169D01*
G01X743688Y494442D02*
X743186Y494770D01*
G01X743772Y494935D02*
X743437Y495099D01*
G01X741008Y492638D02*
X741343Y492474D01*
G01X742599Y489849D02*
X742432Y489931D01*
G01X742599Y486158D02*
X742432Y486240D01*
G01X694433Y476945D02*
X695683Y476731D01*
G01X694574Y476706D02*
X693323Y476920D01*
G01X714379Y470676D02*
X715629Y470461D01*
G01X714520Y470436D02*
X713269Y470650D01*
G01X713410Y476619D02*
X715715Y476304D01*
G01X714640Y476274D02*
X712335Y476588D01*
G01X694312Y471108D02*
X696618Y470793D01*
G01X695543Y470763D02*
X693238Y471078D01*
G01X713402Y460236D02*
X714529Y460214D01*
G01X714307Y459428D02*
X713180Y459450D01*
G01X705461Y467785D02*
X700047D01*
G01X715736D02*
X714555D01*
G01X715657Y467588D02*
X714476D01*
G01X710244Y467293D02*
X705579D01*
G01X710342Y467273D02*
X705264D01*
G01X709457Y467195D02*
X710244D01*
G01X704544D02*
X703911D01*
G01X710244Y467077D02*
X709457D01*
G01Y467047D02*
X710244D01*
G01X709457Y467024D02*
X710244D01*
G01X704544Y466998D02*
X703911D01*
G01X715736D02*
X714555D01*
G01X709457Y466935D02*
X710244D01*
G01Y466899D02*
X709457D01*
G01Y466876D02*
X710244D01*
G01X714555Y466812D02*
X715736D01*
G01X714555Y466810D02*
X715736D01*
G01X710244Y466801D02*
X709457D01*
G01X710244Y466722D02*
X709457D01*
G01X705539Y466703D02*
X711720D01*
G01X701031Y466604D02*
X700047D01*
G01X707705D02*
X705539D01*
G01X704364Y466407D02*
X707508D01*
G01X701031D02*
X700047D01*
G01X715657D02*
X714476D01*
G01X715736Y465693D02*
X714555D01*
G01X715736Y465238D02*
X714555D01*
G01X701031Y465226D02*
X700047D01*
G01X707508D02*
X704383D01*
G01X701031Y465029D02*
X700047D01*
G01X707705D02*
X705539D01*
G01X711720Y464931D02*
X705539D01*
G01X709457Y464911D02*
X710244D01*
G01X714555Y464907D02*
X715736D01*
G01X709457Y464833D02*
X710244D01*
G01Y464758D02*
X709457D01*
G01Y464734D02*
X710244D01*
G01Y464698D02*
X709457D01*
G01X703911Y464636D02*
X704324D01*
G01X710244Y464610D02*
X709457D01*
G01X710244Y464586D02*
X709457D01*
G01Y464557D02*
X710244D01*
G01X709457Y464439D02*
X710244D01*
G01X703911D02*
X704324D01*
G01X705264Y464360D02*
X710342D01*
G01X705579Y464340D02*
X710244D01*
G01X700047Y463848D02*
X705461D01*
G01X704476Y463675D02*
X705461D01*
G01X708610Y463651D02*
X710972D01*
G01X698669D02*
X706937D01*
G01X713402Y463534D02*
X714529D01*
G01X705539Y463455D02*
X699949D01*
G01X710776D02*
X709457D01*
G01X705461Y463356D02*
X704476D01*
G01X705461Y463258D02*
X704476D01*
G01Y463187D02*
X705461D01*
G01Y463140D02*
X704476D01*
G01Y463090D02*
X705461D01*
G01X711720Y463061D02*
X706510D01*
G01X704476Y462998D02*
X705461D01*
G01X705539Y462825D02*
X704476D01*
G01X710776Y462667D02*
X709988D01*
G01Y462470D02*
X710776D01*
G01X694398Y461899D02*
X689909D01*
G01X694398Y461860D02*
X689909D01*
G01X709988Y461289D02*
X710776D01*
G01Y461092D02*
X709988D01*
G01X705539Y460935D02*
X704476D01*
G01X705461Y460762D02*
X704476D01*
G01X711720Y460699D02*
X706510D01*
G01X705461Y460669D02*
X704476D01*
G01Y460620D02*
X705461D01*
G01Y460573D02*
X704476D01*
G01X694398Y460515D02*
X693217D01*
G01X705461Y460502D02*
X704476D01*
G01X694398Y460489D02*
X693217D01*
G01X705461Y460403D02*
X704476D01*
G01X709457Y460305D02*
X710776D01*
G01X705539D02*
X699949D01*
G01X708610Y460108D02*
X710972D01*
G01X698669D02*
X706937D01*
G01X705461Y460084D02*
X704476D01*
G01X705461Y459911D02*
X700047D01*
G01X694398Y459465D02*
X693217D01*
G01X694398Y459439D02*
X693217D01*
G01X710244Y459419D02*
X705579D01*
G01X710342Y459399D02*
X705264D01*
G01X709457Y459321D02*
X710244D01*
G01X704544D02*
X703911D01*
G01X710244Y459203D02*
X709457D01*
G01Y459173D02*
X710244D01*
G01X709457Y459150D02*
X710244D01*
G01X704544Y459124D02*
X703911D01*
G01X709457Y459061D02*
X710244D01*
G01Y459025D02*
X709457D01*
G01Y459002D02*
X710244D01*
G01Y458927D02*
X709457D01*
G01X715736Y458852D02*
X714555D01*
G01X710244Y458848D02*
X709457D01*
G01X711720Y458829D02*
X705539D01*
G01X701031Y458730D02*
X700047D01*
G01X707705D02*
X705539D01*
G01X704364Y458533D02*
X707508D01*
G01X701031D02*
X700047D01*
G01X714555Y458515D02*
X715736D01*
G01X714555Y458067D02*
X715736D01*
G01X694398Y457962D02*
X693217D01*
G01X694398Y457923D02*
X693217D01*
G01X701031Y457352D02*
X700047D01*
G01X707508D02*
X704383D01*
G01X715657D02*
X714476D01*
G01X701031Y457155D02*
X700047D01*
G01X707705D02*
X705539D01*
G01X711720Y457057D02*
X705539D01*
G01X709457Y457037D02*
X710244D01*
G01X709457Y456959D02*
X710244D01*
G01X715736Y456943D02*
X714555D01*
G01Y456942D02*
X715736D01*
G01X710244Y456884D02*
X709457D01*
G01Y456860D02*
X710244D01*
G01Y456824D02*
X709457D01*
G01X714555Y456762D02*
X715736D01*
G01X703911D02*
X704324D01*
G01X710244Y456736D02*
X709457D01*
G01X710244Y456712D02*
X709457D01*
G01Y456683D02*
X710244D01*
G01X709457Y456565D02*
X710244D01*
G01X703911D02*
X704324D01*
G01X710342Y456486D02*
X705264D01*
G01X705579Y456466D02*
X710244D01*
G01X715657Y456171D02*
X714476D01*
G01X700047Y455974D02*
X705461D01*
G01X715736D02*
X714555D01*
G01X704476Y455801D02*
X705461D01*
G01X708610Y455777D02*
X710972D01*
G01X698669D02*
X706937D01*
G01X705539Y455581D02*
X699949D01*
G01X710776D02*
X709457D01*
G01X705461Y455482D02*
X704476D01*
G01X694398Y455384D02*
X693217D01*
G01X705461D02*
X704476D01*
G01X715736D02*
X714555D01*
G01X704476Y455313D02*
X705461D01*
G01Y455266D02*
X704476D01*
G01Y455216D02*
X705461D01*
G01X714555Y455187D02*
X715736D01*
G01X711720D02*
X706510D01*
G01X704476Y455124D02*
X705461D01*
G01X705539Y454951D02*
X704476D01*
G01X710776Y454793D02*
X709988D01*
G01Y454596D02*
X710776D01*
G01X714555Y454386D02*
X715736D01*
G01X693217D02*
X694398D01*
G01Y453612D02*
X693217D01*
G01X715736D02*
X714555D01*
G01X694398Y453601D02*
X693217D01*
G01X715736D02*
X714555D01*
G01X694398Y453573D02*
X693217D01*
G01X715736D02*
X714555D01*
G01X709988Y453415D02*
X710776D01*
G01Y453218D02*
X709988D01*
G01X711720Y452825D02*
X706510D01*
G01X713180Y464310D02*
X714307Y464332D01*
G01X715715Y452682D02*
X714640Y452651D01*
G01X715736Y451887D02*
X714949Y451865D01*
G01X712980Y453092D02*
X713096Y453096D01*
G01X713687Y453032D02*
X713571Y453028D01*
G01X695543Y452997D02*
X693238Y452682D01*
G01X694312Y452651D02*
X696618Y452966D01*
G01X713269Y453109D02*
X714520Y453323D01*
G01X715629Y453298D02*
X714379Y453084D01*
G01X741091Y493130D02*
X741594Y492802D01*
G01X714307Y464332D02*
X713410Y464510D01*
G01X712283Y464488D02*
X713180Y464310D01*
G01X713410Y452997D02*
X715715Y452682D01*
G01X714640Y452651D02*
X712335Y452966D01*
G01X695857Y453096D02*
X695973Y453092D01*
G01X695382Y453028D02*
X695266Y453032D01*
G01X694312Y452651D02*
X693238Y452682D01*
G01X694004Y451865D02*
X693217Y451887D01*
G01X709457Y452431D02*
X710776D01*
G01X696602D02*
X694476D01*
G01X714476D02*
X712350D01*
G01X708610Y452234D02*
X710972D01*
G01X712587Y452037D02*
X715736D01*
G01X696366D02*
X693217D01*
G01X710244Y451545D02*
X705579D01*
G01X710342Y451525D02*
X705264D01*
G01X709457Y451447D02*
X710244D01*
G01Y451329D02*
X709457D01*
G01Y451299D02*
X710244D01*
G01X709457Y451275D02*
X710244D01*
G01X709457Y451187D02*
X710244D01*
G01Y451151D02*
X709457D01*
G01Y451128D02*
X710244D01*
G01X705539Y451092D02*
X704476D01*
G01X710244Y451053D02*
X709457D01*
G01X710244Y450974D02*
X709457D01*
G01X711720Y450955D02*
X705657D01*
G01X705461Y450919D02*
X704476D01*
G01X699949Y450856D02*
X707705D01*
G01X705461Y450832D02*
X704476D01*
G01X705461Y450827D02*
X704476D01*
G01Y450777D02*
X705461D01*
G01X744023Y494688D02*
X743772Y494935D01*
G01X742850Y491244D02*
X743018Y491080D01*
G01X742683D02*
X742515Y491244D01*
G01X740756Y492884D02*
X741008Y492638D01*
G01X742767Y490013D02*
X743018Y489767D01*
G01X742683D02*
X742599Y489849D01*
G01X742850Y487553D02*
X743018Y487389D01*
G01X742683D02*
X742515Y487553D01*
G01X742767Y486322D02*
X743018Y486076D01*
G01X742683D02*
X742599Y486158D01*
G01X715661Y458590D02*
X713393Y459224D01*
G01X712240Y459208D02*
X714508Y458574D01*
G01X694433Y453323D02*
X695683Y453109D01*
G01X693323Y453298D02*
X694574Y453084D01*
G01X744274Y494278D02*
X744023Y494688D01*
G01X743856Y494196D02*
X743688Y494442D01*
G01X740924Y493376D02*
X741091Y493130D01*
G01X742767Y489603D02*
X742683Y489767D01*
G01X742767Y485912D02*
X742683Y486076D01*
G01X740505Y493294D02*
X740756Y492884D01*
G01X711957Y526613D02*
X712268Y526111D01*
G01X712350Y526867D02*
X712678Y526376D01*
G01X705972Y481762D02*
X704476Y483258D01*
G01X698563Y479188D02*
X699625Y478297D01*
G01X698412D02*
X697350Y479188D01*
G01X743018Y491080D02*
X743102Y490833D01*
G01X742767D02*
X742683Y491080D01*
G01X743018Y489767D02*
X743102Y489521D01*
G01X743018Y487389D02*
X743102Y487143D01*
G01X742767D02*
X742683Y487389D01*
G01X743018Y486076D02*
X743102Y485830D01*
G01X744358Y493786D02*
X744274Y494278D01*
G01X740421Y493786D02*
X740505Y493294D01*
G01X743939Y493786D02*
X743856Y494196D01*
G01X740840Y493786D02*
X740924Y493376D01*
G01X701752Y485908D02*
X700606Y487667D01*
G01X700593Y486486D02*
X701727Y484747D01*
G01X704476Y481210D02*
X705264Y480108D01*
G01Y472234D02*
X704476Y473336D01*
G01X705264Y464360D02*
X704476Y465462D01*
G01X705264Y456486D02*
X704476Y457588D01*
G01X748571Y484402D02*
Y502349D01*
G01Y484402D02*
Y502349D01*
G01X744358Y498379D02*
Y497887D01*
G01Y501168D02*
Y500676D01*
G01X743102Y485830D02*
Y485502D01*
G01Y487143D02*
Y486814D01*
G01Y487963D02*
Y487553D01*
G01Y489521D02*
Y489193D01*
G01Y490833D02*
Y490505D01*
G01Y491654D02*
Y491244D01*
G01Y497231D02*
Y495919D01*
G01X742767D02*
Y497231D01*
G01Y490669D02*
Y490833D01*
G01Y489357D02*
Y489603D01*
G01Y486978D02*
Y487143D01*
G01Y485666D02*
Y485912D01*
G01Y500676D02*
Y498379D01*
G01X742264D02*
Y500676D01*
G01X742097Y497231D02*
Y495919D01*
G01X741761D02*
Y497231D01*
G01X740421Y500676D02*
Y501168D01*
G01Y497887D02*
Y498379D01*
G01Y491244D02*
Y491654D01*
G01Y489931D02*
Y490341D01*
G01Y487553D02*
Y487963D01*
G01Y488619D02*
Y489029D01*
G01Y486240D02*
Y486650D01*
G01Y484928D02*
Y485338D01*
G01X736760Y511962D02*
Y576053D01*
G01Y511962D02*
Y474790D01*
G01X707126Y486061D02*
X706985Y486980D01*
G01X706898Y486048D02*
X707039Y485129D01*
G01X743102Y485502D02*
X743018Y485256D01*
G01X743102Y486814D02*
X743018Y486568D01*
G01X743102Y489193D02*
X743018Y488947D01*
G01X743102Y490505D02*
X743018Y490259D01*
G01X743856Y493376D02*
X743939Y493786D01*
G01X740924Y494196D02*
X740840Y493786D01*
G01X744274Y493294D02*
X744358Y493786D01*
G01X740505Y494278D02*
X740421Y493786D01*
G01X721996Y520935D02*
Y556368D01*
G01X721602Y529695D02*
Y523888D01*
G01X719240Y520935D02*
Y556368D01*
G01X717232Y486486D02*
Y487667D01*
G01X717194Y486486D02*
Y487667D01*
G01X717166D02*
Y486486D01*
G01X716878Y535699D02*
Y523888D01*
G01X716091Y526250D02*
Y523888D01*
G01X715833Y486486D02*
Y487667D01*
G01X715736D02*
Y486486D01*
G01X715661Y465169D02*
Y458590D01*
G01X715657Y481959D02*
Y486289D01*
G01Y467588D02*
Y456171D01*
G01X715629Y470461D02*
Y476920D01*
G01X715613Y471722D02*
Y475659D01*
G01X715433Y486486D02*
Y487667D01*
G01X714949Y486486D02*
Y487667D01*
G01Y475487D02*
Y471894D01*
G01X714529Y463534D02*
Y460214D01*
G01X714520Y470436D02*
Y476945D01*
G01X714508Y465185D02*
Y458574D01*
G01X714379Y476706D02*
Y470676D01*
G01X713926Y487667D02*
Y486486D01*
G01X713718Y475659D02*
Y471722D01*
G01X713687Y470727D02*
Y476655D01*
G01X713571Y470731D02*
Y476650D01*
G01X713531Y487667D02*
Y486486D01*
G01X713410Y459250D02*
Y464510D01*
G01Y476619D02*
Y470763D01*
G01X713402Y463523D02*
Y460236D01*
G01X713393Y464535D02*
Y459224D01*
G01X713374Y486484D02*
Y487667D01*
G01Y464524D02*
Y459235D01*
G01Y476629D02*
Y470753D01*
G01X713269Y476731D02*
Y470650D01*
G01X713096Y470663D02*
Y476718D01*
G01X712980Y470668D02*
Y476714D01*
G01X712744Y486486D02*
Y487667D01*
G01X712587Y475659D02*
Y471722D01*
G01Y487667D02*
Y486486D01*
G01X712508Y485108D02*
Y486289D01*
G01X742683Y485502D02*
X742767Y485666D01*
G01X742683Y486814D02*
X742767Y486978D01*
G01X742683Y489193D02*
X742767Y489357D01*
G01X742683Y490505D02*
X742767Y490669D01*
G01X706985Y486980D02*
X706898Y486048D01*
G01X706199Y487418D02*
X706112Y486486D01*
G01X712350Y476053D02*
Y471329D01*
G01Y481959D02*
Y481762D01*
G01X712335Y476588D02*
Y470793D01*
G01X712283Y459272D02*
Y464488D01*
G01X712240Y464551D02*
Y459208D01*
G01X712193Y464524D02*
Y459235D01*
G01Y476629D02*
Y470753D01*
G01X711957Y489045D02*
Y486486D01*
G01X711588Y455187D02*
Y452825D01*
G01Y463061D02*
Y460699D01*
G01Y470935D02*
Y468573D01*
G01Y478809D02*
Y476447D01*
G01X711169Y487667D02*
Y486486D01*
G01X710972Y455777D02*
Y452234D01*
G01Y463651D02*
Y460108D01*
G01Y471525D02*
Y467982D01*
G01Y479399D02*
Y475856D01*
G01X710776Y455581D02*
Y452431D01*
G01Y463455D02*
Y460305D01*
G01Y471329D02*
Y468179D01*
G01Y479203D02*
Y476053D01*
G01X710775Y486486D02*
Y487667D01*
G01X710512Y476053D02*
Y479203D01*
G01Y468179D02*
Y471329D01*
G01Y460305D02*
Y463455D01*
G01Y452431D02*
Y455581D01*
G01X710471Y476053D02*
Y479203D01*
G01Y468179D02*
Y471329D01*
G01Y460305D02*
Y463455D01*
G01Y452431D02*
Y455581D01*
G01X710382Y487667D02*
Y486486D01*
G01X710375Y487667D02*
Y486486D01*
G01X710342Y474577D02*
Y480679D01*
G01Y466703D02*
Y472805D01*
G01Y458829D02*
Y464931D01*
G01Y450955D02*
Y457057D01*
G01X710244D02*
Y450955D01*
G01Y464931D02*
Y458829D01*
G01Y472805D02*
Y466703D01*
G01Y480679D02*
Y474577D01*
G01X710137Y475167D02*
Y480088D01*
G01Y467293D02*
Y472214D01*
G01Y459419D02*
Y464340D01*
G01Y451545D02*
Y456466D01*
G01X709988Y455581D02*
Y452431D01*
G01Y463455D02*
Y460305D01*
G01Y471329D02*
Y468179D01*
G01Y479203D02*
Y476053D01*
G01X709830D02*
Y479203D01*
G01Y468179D02*
Y471329D01*
G01Y460305D02*
Y463455D01*
G01Y452431D02*
Y455581D01*
G01X709791Y455777D02*
Y452234D01*
G01Y463651D02*
Y460108D01*
G01Y471525D02*
Y467982D01*
G01Y479399D02*
Y475856D01*
G01X709720Y476053D02*
Y479203D01*
G01Y468179D02*
Y471329D01*
G01Y460305D02*
Y463455D01*
G01Y452431D02*
Y455581D01*
G01X709457Y474577D02*
Y480679D01*
G01Y466703D02*
Y472805D01*
G01Y458829D02*
Y464931D01*
G01Y450955D02*
Y457057D01*
G01X709403Y475167D02*
Y480088D01*
G01Y467293D02*
Y472214D01*
G01Y459419D02*
Y464340D01*
G01Y451545D02*
Y456466D01*
G01X709358Y451525D02*
Y450955D01*
G01Y457057D02*
Y456486D01*
G01Y459399D02*
Y458829D01*
G01Y464931D02*
Y464360D01*
G01Y467273D02*
Y466703D01*
G01Y472805D02*
Y472234D01*
G01Y475147D02*
Y474577D01*
G01Y480679D02*
Y480108D01*
G01X709267Y487667D02*
Y486486D01*
G01X708965Y487667D02*
Y486486D01*
G01X708868Y487667D02*
Y486486D01*
G01X708807Y525156D02*
Y526611D01*
G01Y452825D02*
Y451525D01*
G01Y456486D02*
Y455187D01*
G01Y460699D02*
Y459399D01*
G01Y464360D02*
Y463061D01*
G01Y468573D02*
Y467273D01*
G01Y472234D02*
Y470935D01*
G01Y476447D02*
Y475147D01*
G01Y480108D02*
Y478809D01*
G01X708610Y475856D02*
Y479399D01*
G01Y467982D02*
Y471525D01*
G01Y460108D02*
Y463651D01*
G01Y452234D02*
Y455777D01*
G01X708496Y486486D02*
Y487667D01*
G01X708420Y486486D02*
Y487667D01*
G01X708177Y486486D02*
Y487667D01*
G01X707714D02*
Y486486D01*
G01X707705Y458730D02*
Y457155D01*
G01Y466604D02*
Y465029D01*
G01Y474478D02*
Y472903D01*
G01X707535Y486486D02*
Y487667D01*
G01X707508Y458533D02*
Y457352D01*
G01Y466407D02*
Y465226D01*
G01Y474281D02*
Y473100D01*
G01X707507Y487667D02*
Y486486D01*
G01X707468D02*
Y487667D01*
G01X707404Y475167D02*
Y480088D01*
G01Y467293D02*
Y472214D01*
G01Y459419D02*
Y464340D01*
G01Y451545D02*
Y456466D01*
G01X707350D02*
Y451545D01*
G01Y464340D02*
Y459419D01*
G01Y472214D02*
Y467293D01*
G01Y480088D02*
Y475167D01*
G01X706937Y460108D02*
Y455777D01*
G01Y467982D02*
Y463651D01*
G01Y477825D02*
Y473494D01*
G01X706875Y458533D02*
Y457352D01*
G01Y466407D02*
Y465226D01*
G01Y474281D02*
Y473100D01*
G01X706670Y475167D02*
Y480088D01*
G01Y467293D02*
Y472214D01*
G01Y459419D02*
Y464340D01*
G01Y451545D02*
Y456466D01*
G01X706563D02*
Y451545D01*
G01Y464340D02*
Y459419D01*
G01Y472214D02*
Y467293D01*
G01Y480088D02*
Y475167D01*
G01X706524Y458533D02*
Y457352D01*
G01Y466407D02*
Y465226D01*
G01Y474281D02*
Y473100D01*
G01X706510Y476447D02*
Y478809D01*
G01Y468573D02*
Y470935D01*
G01Y460699D02*
Y463061D01*
G01Y452825D02*
Y455187D01*
G01X706445Y456486D02*
Y451525D01*
G01Y464360D02*
Y459399D01*
G01Y472234D02*
Y467273D01*
G01Y480108D02*
Y475147D01*
G01X706366Y456466D02*
Y451545D01*
G01Y464340D02*
Y459419D01*
G01Y472214D02*
Y467293D01*
G01Y480088D02*
Y475167D01*
G01X706327Y456486D02*
Y451525D01*
G01Y464360D02*
Y459399D01*
G01Y472234D02*
Y467273D01*
G01Y480108D02*
Y475147D01*
G01X706242Y458533D02*
Y457352D01*
G01Y466407D02*
Y465226D01*
G01Y474281D02*
Y473100D01*
G01X706169Y475167D02*
Y480088D01*
G01Y467293D02*
Y472214D01*
G01Y459419D02*
Y464340D01*
G01Y451545D02*
Y456466D01*
G01X705756Y460108D02*
Y455777D01*
G01Y467982D02*
Y463651D01*
G01Y477825D02*
Y473494D01*
G01X705657Y458829D02*
Y457057D01*
G01Y466703D02*
Y464931D01*
G01Y474577D02*
Y472805D01*
G01X705579Y456486D02*
Y451525D01*
G01Y464360D02*
Y459399D01*
G01Y472234D02*
Y467273D01*
G01Y480108D02*
Y475147D01*
G01X705539Y451092D02*
Y450856D01*
G01Y457155D02*
Y454951D01*
G01Y460935D02*
Y458730D01*
G01Y465029D02*
Y462825D01*
G01Y468809D02*
Y466604D01*
G01Y472903D02*
Y472667D01*
G01Y478651D02*
Y474478D01*
G01X705461Y472667D02*
Y478651D01*
G01Y462825D02*
Y468809D01*
G01Y454951D02*
Y460935D01*
G01X705418Y473100D02*
Y477037D01*
G01Y463848D02*
Y467785D01*
G01Y455974D02*
Y459911D01*
G01X705264Y459399D02*
Y464360D01*
G01Y456486D02*
Y451525D01*
G01Y472234D02*
Y467273D01*
G01Y480108D02*
Y475147D01*
G01X704544Y459321D02*
Y459124D01*
G01Y467195D02*
Y466998D01*
G01Y476250D02*
Y475069D01*
G01X704476Y480079D02*
Y479188D01*
G01X704449Y473100D02*
Y477037D01*
G01Y463848D02*
Y467785D01*
G01Y455974D02*
Y459911D01*
G01X704324Y456762D02*
Y456565D01*
G01Y464636D02*
Y464439D01*
G01X704083Y482549D02*
Y481762D01*
G01X703928Y459911D02*
Y455982D01*
G01Y467785D02*
Y463856D01*
G01Y477037D02*
Y473100D01*
G01X703911Y475069D02*
Y476250D01*
G01Y466998D02*
Y467195D01*
G01Y464439D02*
Y464636D01*
G01Y459124D02*
Y459321D01*
G01Y456565D02*
Y456762D01*
G01X703323Y473100D02*
Y477037D01*
G01Y463848D02*
Y467785D01*
G01Y455974D02*
Y459911D01*
G01X703295D02*
Y455974D01*
G01Y467785D02*
Y463848D01*
G01Y477628D02*
Y473100D01*
G01X702353D02*
Y477037D01*
G01Y463848D02*
Y467785D01*
G01Y455974D02*
Y459911D01*
G01X702311D02*
Y455974D01*
G01Y467785D02*
Y463848D01*
G01Y477037D02*
Y473100D01*
G01X702213Y459911D02*
Y455974D01*
G01Y467785D02*
Y463848D01*
G01Y477628D02*
Y473691D01*
G01X702016Y473494D02*
Y477825D01*
G01Y460108D02*
Y455777D01*
G01Y467982D02*
Y463651D01*
G01X701484Y486486D02*
Y487667D01*
G01X701446Y486486D02*
Y487667D01*
G01X701418D02*
Y486486D01*
G01X701238D02*
Y487667D01*
G01X701228Y460108D02*
Y455777D01*
G01Y467982D02*
Y463651D01*
G01Y477825D02*
Y473494D01*
G01X701031Y473691D02*
Y477628D01*
G01Y463848D02*
Y467785D01*
G01Y455974D02*
Y459911D01*
G01X700933Y481762D02*
Y482549D01*
G01X700776Y487667D02*
Y486486D01*
G01X700539Y483140D02*
Y480384D01*
G01X700532Y487667D02*
Y486486D01*
G01X700456Y487667D02*
Y486486D01*
G01X700146Y526611D02*
Y525156D01*
G01X700085Y486486D02*
Y487667D01*
G01X700047Y459911D02*
Y455974D01*
G01Y467785D02*
Y463848D01*
G01Y477628D02*
Y473691D01*
G01X699988Y487667D02*
Y486486D01*
G01X699949Y460305D02*
Y455581D01*
G01Y468179D02*
Y463455D01*
G01Y478022D02*
Y472903D01*
G01X699850Y460108D02*
Y455777D01*
G01Y467982D02*
Y463651D01*
G01Y477825D02*
Y473494D01*
G01X699685Y486486D02*
Y487667D01*
G01X698669Y460108D02*
Y455777D01*
G01Y467982D02*
Y463651D01*
G01Y477825D02*
Y473494D01*
G01X698578Y486486D02*
Y487667D01*
G01X698571D02*
Y486486D01*
G01X698178Y487667D02*
Y486486D01*
G01X697783Y487667D02*
Y486486D01*
G01X697350Y479188D02*
Y480079D01*
G01X702841Y486486D02*
X702754Y487418D01*
G01X702055Y486048D02*
X701968Y486980D01*
G01X745879Y480667D02*
X739452Y478525D01*
G01X745879Y480667D02*
X739452Y478525D01*
G01X743018Y485256D02*
X742850Y485092D01*
G01X742599Y485420D02*
X742683Y485502D01*
G01X743018Y486568D02*
X742767Y486322D01*
G01X742599Y486732D02*
X742683Y486814D01*
G01X743018Y488947D02*
X742850Y488783D01*
G01X742599Y489111D02*
X742683Y489193D01*
G01X743018Y490259D02*
X742767Y490013D01*
G01X742599Y490423D02*
X742683Y490505D01*
G01X743772Y492638D02*
X744023Y492884D01*
G01X743688Y493130D02*
X743856Y493376D01*
G01X741091Y494442D02*
X740924Y494196D01*
G01X744023Y492884D02*
X744274Y493294D01*
G01X740756Y494688D02*
X740505Y494278D01*
G01X701914Y485129D02*
X702055Y486048D01*
G01X701968Y486980D02*
X701827Y486061D01*
G01X696996Y489045D02*
Y486486D01*
G01X696760Y476629D02*
Y470753D01*
G01X696618Y470793D02*
Y476588D01*
G01X696602Y481762D02*
Y481959D01*
G01Y471329D02*
Y476053D01*
G01X696445Y486289D02*
Y485108D01*
G01X696366Y486486D02*
Y487667D01*
G01Y471722D02*
Y475659D01*
G01X696209Y487667D02*
Y486486D01*
G01X695973Y476714D02*
Y470668D01*
G01X695857Y476718D02*
Y470663D01*
G01X695683Y470650D02*
Y476731D01*
G01X695579Y486484D02*
Y487667D01*
G01Y476629D02*
Y470753D01*
G01X695543Y470763D02*
Y476619D01*
G01X695420Y487667D02*
Y486486D01*
G01X695382Y476650D02*
Y470731D01*
G01X695266Y476655D02*
Y470727D01*
G01X695235Y475659D02*
Y471722D01*
G01X695027Y486486D02*
Y487667D01*
G01X694574Y470676D02*
Y476706D01*
G01X694433Y476945D02*
Y470436D01*
G01X694004Y471894D02*
Y475487D01*
G01Y487667D02*
Y486486D01*
G01X693519Y487667D02*
Y486486D01*
G01X693340Y475659D02*
Y471722D01*
G01X693323Y476920D02*
Y470461D01*
G01X693295Y481959D02*
Y486289D01*
G01X693217Y487667D02*
Y486486D01*
G01X693120Y487667D02*
Y486486D01*
G01X692862Y526250D02*
Y523888D01*
G01X692429Y461899D02*
Y483927D01*
G01X692075Y523888D02*
Y535699D01*
G01X691787Y486486D02*
Y487667D01*
G01X691759D02*
Y486486D01*
G01X691720D02*
Y487667D01*
G01X689909Y481959D02*
Y461899D01*
G01X689713Y520935D02*
Y556368D01*
G01X687350Y553415D02*
Y523888D01*
G01X686957Y556368D02*
Y520935D01*
G01X743186Y492392D02*
X743437Y492474D01*
G01X741594Y495181D02*
X741343Y495099D01*
G01X742850Y485092D02*
X742432Y484928D01*
G01X742850Y488783D02*
X742432Y488619D01*
G01Y485338D02*
X742599Y485420D01*
G01X742432Y486650D02*
X742599Y486732D01*
G01X742432Y489029D02*
X742599Y489111D01*
G01X742432Y490341D02*
X742599Y490423D01*
G01X743437Y492474D02*
X743772Y492638D01*
G01X741343Y495099D02*
X741008Y494935D01*
G01X743186Y492802D02*
X743688Y493130D01*
G01X741594Y494770D02*
X741091Y494442D01*
G01X741008Y494935D02*
X740756Y494688D01*
G01X710224Y481762D02*
X711203Y482740D01*
G01X705264Y459399D02*
X704476Y458297D01*
G01Y466171D02*
X705264Y467273D01*
G01X704476Y474045D02*
X705264Y475147D01*
G01X707226Y484747D02*
X708359Y486486D01*
G01X708346Y487667D02*
X707200Y485908D01*
G01X719240Y523888D02*
X721602Y529793D01*
G01X696996Y526613D02*
X696684Y526111D01*
G01X696602Y526867D02*
X696274Y526376D01*
G01X688882Y546546D02*
X688531Y546525D01*
G01X689206Y546607D02*
X688882Y546546D01*
G01X689473Y546705D02*
X689206Y546607D01*
G01X689650Y546834D02*
X689473Y546705D01*
G01X689713Y546980D02*
X689650Y546834D01*
G01X720071Y531741D02*
X720421Y531762D01*
G01X719747Y531680D02*
X720071Y531741D01*
G01X719480Y531582D02*
X719747Y531680D01*
G01X719303Y531453D02*
X719480Y531582D01*
G01X719240Y531307D02*
X719303Y531453D01*
G01X689650Y530469D02*
X689713Y530323D01*
G01X689473Y530597D02*
X689650Y530469D01*
G01X689207Y530696D02*
X689473Y530597D01*
G01X688882Y530757D02*
X689207Y530696D01*
G01X688531Y530777D02*
X688882Y530757D01*
G01X719303Y545850D02*
X719240Y545995D01*
G01X719480Y545721D02*
X719303Y545850D01*
G01X719746Y545623D02*
X719480Y545721D01*
G01X720070Y545562D02*
X719746Y545623D01*
G01X720421Y545541D02*
X720070Y545562D01*
G01X736760Y576053D02*
G03X732823Y579990I-3937J0D01*
G01X709290Y544783D02*
G03X708804Y544951I-486J-619D01*
G01X709726Y544520D02*
G03X708413Y543053I-657J-734D01*
G01X708804Y532352D02*
G03X709290Y532520I0J787D01*
G01X705461Y546919D02*
G03X703492I-984J0D01*
G01Y538455D02*
G03X705461I985J0D01*
G01X700539Y543053D02*
G03X708413I3937J-4402D01*
G01X709291Y532520D02*
G03X711905Y536289I-4815J6130D01*
G01X697048D02*
G03X699662Y532520I7429J2361D01*
G01X711905Y541014D02*
G03X709291Y544782I-7429J-2363D01*
G01X699661D02*
G03X697048Y541014I4816J-6130D01*
G01X699227Y544520D02*
G03X709726I5250J-5869D01*
G01X695816Y536289D02*
G03X699229Y531368I8660J2362D01*
G01X709723D02*
G03X713136Y536289I-5247J7283D01*
G01X699229Y545935D02*
G03X695816Y541014I5247J-7283D01*
G01X713136D02*
G03X709723Y545935I-8660J-2362D01*
G01X695438Y535516D02*
G03X698258Y531381I9038J3135D01*
G01X710695D02*
G03X713515Y535516I-6219J7270D01*
G01Y541787D02*
G03X710695Y545922I-9039J-3135D01*
G01X698258D02*
G03X695438Y541787I6219J-7270D01*
G01X695436Y535404D02*
G03X698199Y531380I9040J3247D01*
G01X710753D02*
G03X713517Y535404I-6276J7272D01*
G01Y541899D02*
G03X710753Y545923I-9040J-3248D01*
G01X698199D02*
G03X695436Y541899I6278J-7271D01*
G01X712351Y550436D02*
G03X696602I-7874J-11785D01*
G01X699662Y532520D02*
G03X700149Y532352I486J620D01*
G01Y544951D02*
G03X699661Y544782I0J-789D01*
G01X700539Y543053D02*
G03X699227Y544520I-656J733D01*
G01X713965Y562290D02*
X715933D01*
G01Y562044D02*
X714300D01*
G01X714593Y561798D02*
X714258D01*
G01X715137Y561470D02*
X715933D01*
G01Y561265D02*
X715137D01*
G01X714593Y560526D02*
X714802D01*
G01X714970D02*
X715933D01*
G01Y560321D02*
X714593D01*
G01Y559993D02*
X715933D01*
G01X713965D02*
X714174D01*
G01Y559788D02*
X713965D01*
G01X715933D02*
X714593D01*
G01X715095Y559460D02*
X715430D01*
G01X715137Y559255D02*
X715389D01*
G01X714928Y561429D02*
X715137Y561470D01*
G01Y561265D02*
X714928Y561224D01*
G01Y559419D02*
X715095Y559460D01*
G01X714593Y558353D02*
X714844D01*
G01X715682D02*
X716603D01*
G01X715472D02*
X715054D01*
G01X716603Y558148D02*
X714593D01*
G01X721996Y556368D02*
X686957D01*
G01X721996Y553809D02*
X686957D01*
G01X721602Y553415D02*
X687350D01*
G01X716878Y551053D02*
X692075D01*
G01X689713Y550856D02*
X686957D01*
G01X721996D02*
X719240D01*
G01X695815Y550266D02*
X693453D01*
G01X705657D02*
X703295D01*
G01X715500D02*
X713138D01*
G01X695815Y550133D02*
X693453D01*
G01X705657D02*
X703295D01*
G01X715500D02*
X713138D01*
G01X716484Y549970D02*
X692468D01*
G01X695815Y549168D02*
X693453D01*
G01X705657D02*
X703295D01*
G01X715500D02*
X713138D01*
G01X695815Y549137D02*
X693453D01*
G01X705657D02*
X703295D01*
G01X715500D02*
X713138D01*
G01X695815Y549085D02*
X693453D01*
G01X705657D02*
X703295D01*
G01X715500D02*
X713138D01*
G01X695815Y549053D02*
X693453D01*
G01X705657D02*
X703295D01*
G01X715500D02*
X713138D01*
G01X689713Y548592D02*
X687350D01*
G01X689713Y548494D02*
X687350D01*
G01X695815Y548036D02*
X693453D01*
G01X705657D02*
X703295D01*
G01X715500D02*
X713138D01*
G01X695815Y547903D02*
X693453D01*
G01X705657D02*
X703295D01*
G01X715500D02*
X713138D01*
G01X721602Y547608D02*
X719240D01*
G01Y547510D02*
X721602D01*
G01X713728Y547116D02*
X709988D01*
G01X692468Y547018D02*
X716484D01*
G01X687350Y546525D02*
X688531D01*
G01X709988Y546132D02*
X695224D01*
G01X713531Y545935D02*
X695421D01*
G01X720421Y545541D02*
X721602D01*
G01X708804Y544951D02*
X700149D01*
G01X715389Y559255D02*
X715514Y559214D01*
G01X715430Y559460D02*
X715598Y559419D01*
G01X689713Y542982D02*
X687350D01*
G01X721602D02*
X719240D01*
G01X689713Y542785D02*
X687350D01*
G01X721602D02*
X719240D01*
G01X716878Y542392D02*
X719240D01*
G01X689713D02*
X692075D01*
G01X719240Y541604D02*
X689713D01*
G01X695421Y541014D02*
X713531D01*
G01X718059Y540226D02*
X721602D01*
G01X690894D02*
X687350D01*
G01X684299Y539439D02*
X724654D01*
G01X684299Y537864D02*
X724654D01*
G01X718059Y537077D02*
X721602D01*
G01X687350D02*
X690894D01*
G01X713531Y536289D02*
X695421D01*
G01X719240Y535699D02*
X689713D01*
G01X716878Y534911D02*
X719240D01*
G01X692075D02*
X689713D01*
G01Y534518D02*
X687350D01*
G01X721602D02*
X719240D01*
G01X689713Y534321D02*
X687350D01*
G01X721602D02*
X719240D01*
G01X708804Y532352D02*
X700149D01*
G01X720421Y531762D02*
X721602D01*
G01X695421Y531368D02*
X713531D01*
G01X709988Y531171D02*
X695224D01*
G01X687350Y530777D02*
X688531D01*
G01X716484Y530285D02*
X692468D01*
G01X713728Y530187D02*
X709988D01*
G01X721602Y529793D02*
X719240D01*
G01Y529695D02*
X721602D01*
G01X695815Y529399D02*
X693453D01*
G01X705657D02*
X703295D01*
G01X715500D02*
X713138D01*
G01X695815Y529267D02*
X693453D01*
G01X705657D02*
X703295D01*
G01X715500D02*
X713138D01*
G01X689713Y528809D02*
X687350D01*
G01X689713Y528710D02*
X687350D01*
G01X695815Y528249D02*
X693453D01*
G01X705657D02*
X703295D01*
G01X715500D02*
X713138D01*
G01X695815Y528218D02*
X693453D01*
G01X705657D02*
X703295D01*
G01X715500D02*
X713138D01*
G01Y528166D02*
X715500D01*
G01X703295D02*
X705657D01*
G01X693453D02*
X695815D01*
G01Y528135D02*
X693453D01*
G01X705657D02*
X703295D01*
G01X715500D02*
X713138D01*
G01X692468Y527333D02*
X716484D01*
G01X695815Y527170D02*
X693453D01*
G01X705657D02*
X703295D01*
G01X715500D02*
X713138D01*
G01Y527037D02*
X715500D01*
G01X703295D02*
X705657D01*
G01X693453D02*
X695815D01*
G01X715514Y559214D02*
X715598Y559173D01*
G01X714844Y558353D02*
X714760Y558394D01*
G01X715054Y558353D02*
X714928Y558435D01*
G01X719240Y541604D02*
X721602Y540226D01*
G01X714300Y562044D02*
X714593Y561798D01*
G01X714258D02*
X713965Y562044D01*
G01X715598Y559419D02*
X715807Y559255D01*
G01X714886Y560608D02*
X714970Y560526D01*
G01X714802D02*
X714718Y560608D01*
G01X714760Y558394D02*
X714677Y558476D01*
G01X689713Y535699D02*
X687350Y537077D01*
G01X714220Y549970D02*
X714909Y549281D01*
G01X714220Y530285D02*
X714909Y529596D01*
G01X715807Y559255D02*
X715891Y559132D01*
G01X714802Y560731D02*
X714886Y560608D01*
G01X714718D02*
X714635Y560731D01*
G01X715598Y559173D02*
X715682Y559050D01*
G01X714928Y558435D02*
X714844Y558558D01*
G01X714677Y558476D02*
X714635Y558558D01*
G01X696684Y551192D02*
X696996Y550690D01*
G01X696274Y550927D02*
X696602Y550436D01*
G01X721602Y547510D02*
X719240Y553415D01*
G01X715891Y559132D02*
X715933Y558968D01*
G01X715682Y559050D02*
X715724Y558886D01*
G01X714760Y560895D02*
X714802Y560731D01*
G01X714635D02*
X714593Y560895D01*
G01X714844Y558558D02*
X714802Y558722D01*
G01X714635Y558558D02*
X714593Y558722D01*
G01X724654Y539439D02*
Y537864D01*
G01X723669Y539439D02*
Y537864D01*
G01X723472D02*
Y539439D01*
G01X721602Y529793D02*
Y547510D01*
G01Y553415D02*
Y547608D01*
G01X720421Y531762D02*
Y545541D01*
G01X720224Y539439D02*
Y537864D01*
G01X720157D02*
Y539439D01*
G01X719043Y537864D02*
Y539439D01*
G01X718059Y540226D02*
Y537077D01*
G01X716878Y541604D02*
Y553415D01*
G01X716603Y558353D02*
Y558148D01*
G01X716484Y547018D02*
Y549970D01*
G01Y527333D02*
Y530285D01*
G01X716091D02*
Y527333D01*
G01Y549970D02*
Y547018D01*
G01Y553415D02*
Y551053D01*
G01X715933Y559993D02*
Y559788D01*
G01Y558968D02*
Y558722D01*
G01Y560526D02*
Y560321D01*
G01Y561470D02*
Y561265D01*
G01Y562290D02*
Y562044D01*
G01X715724Y558886D02*
Y558722D01*
G01X715500Y547903D02*
Y550266D01*
G01Y529399D02*
Y527037D01*
G01X714909Y529596D02*
Y528022D01*
G01Y549281D02*
Y547707D01*
G01X714802Y558722D02*
Y558968D01*
G01X714593Y560321D02*
Y560526D01*
G01Y560895D02*
Y561059D01*
G01Y559788D02*
Y559993D01*
G01Y558722D02*
Y558968D01*
G01Y558148D02*
Y558353D01*
G01X714174Y559993D02*
Y559788D01*
G01X713965Y562044D02*
Y562290D01*
G01Y559788D02*
Y559993D01*
G01X713728Y529399D02*
Y528218D01*
G01Y547116D02*
Y530187D01*
G01Y549085D02*
Y547903D01*
G01X713531Y531368D02*
Y545935D01*
G01X713138Y547903D02*
Y550266D01*
G01Y529399D02*
Y527037D01*
G01X709988Y531171D02*
Y530187D01*
G01Y547116D02*
Y546132D01*
G01X709201Y532459D02*
Y531368D01*
G01Y545935D02*
Y544843D01*
G01X708807Y550692D02*
Y552147D01*
G01X705657Y547903D02*
Y550266D01*
G01Y529399D02*
Y527037D01*
G01X705461Y546919D02*
Y538455D01*
G01X705067Y547903D02*
Y549085D01*
G01Y528218D02*
Y529399D01*
G01X703886D02*
Y528218D01*
G01Y549085D02*
Y547903D01*
G01X703492Y546919D02*
Y538455D01*
G01X703295Y547903D02*
Y550266D01*
G01Y529399D02*
Y527037D01*
G01X700146Y552147D02*
Y550692D01*
G01X699752Y544843D02*
Y545935D01*
G01Y532459D02*
Y531368D01*
G01X695815Y547903D02*
Y550266D01*
G01Y529399D02*
Y527037D01*
G01X695421Y545935D02*
Y531368D01*
G01X695224Y547903D02*
Y549085D01*
G01Y528218D02*
Y529399D01*
G01Y546132D02*
Y531171D01*
G01X694043Y529399D02*
Y528218D01*
G01Y549085D02*
Y547903D01*
G01X693453D02*
Y550266D01*
G01Y529399D02*
Y527037D01*
G01X692862Y553415D02*
Y551053D01*
G01X692468Y530285D02*
Y527333D01*
G01Y549970D02*
Y547018D01*
G01X692075Y541604D02*
Y553415D01*
G01X690894Y537077D02*
Y540226D01*
G01X689909Y539439D02*
Y537864D01*
G01X688796Y539439D02*
Y537864D01*
G01X688728D02*
Y539439D01*
G01X688531Y530777D02*
Y546525D01*
G01X685480Y539439D02*
Y537864D01*
G01X685283D02*
Y539439D01*
G01X684299Y537864D02*
Y539439D01*
G01X715933Y558722D02*
X715891Y558558D01*
G01X715724Y558722D02*
X715682Y558558D01*
G01X714593Y558968D02*
X714635Y559132D01*
G01X714802Y561059D02*
X714760Y560895D01*
G01X714593Y561059D02*
X714635Y561183D01*
G01X714909Y528022D02*
X714220Y527333D01*
G01X711957Y550690D02*
X712268Y551192D01*
G01X715891Y558558D02*
X715849Y558476D01*
G01X714802Y558968D02*
X714886Y559132D01*
G01X714844Y561142D02*
X714802Y561059D01*
G01X721602Y537077D02*
X719240Y535699D01*
G01X714909Y547707D02*
X714220Y547018D01*
G01X715682Y558558D02*
X715598Y558435D01*
G01X714635Y559132D02*
X714718Y559255D01*
G01X714635Y561183D02*
X714718Y561306D01*
G01X712678Y550927D02*
X712350Y550436D01*
G01X689713Y541604D02*
X687350Y540226D01*
G01X715598Y558435D02*
X715472Y558353D01*
G01X715849Y558476D02*
X715766Y558394D01*
G01X714718Y559255D02*
X714844Y559378D01*
G01X714928Y561224D02*
X714844Y561142D01*
G01X714718Y561306D02*
X714802Y561388D01*
G01X715012Y559214D02*
X715137Y559255D01*
G01X714802Y561388D02*
X714928Y561429D01*
G01X715766Y558394D02*
X715682Y558353D01*
G01X714844Y559378D02*
X714928Y559419D01*
G01X714886Y559132D02*
X715012Y559214D01*
G01X745684Y655413D02*
X746405Y654439D01*
G01X744962Y655900D02*
X745684Y655413D01*
G01X743518Y656388D02*
X744962Y655900D01*
G01X740631Y656388D02*
X743518D01*
G01X739188Y655900D02*
X740631Y656388D01*
G01X738466Y655413D02*
X739188Y655900D01*
G01X737744Y654439D02*
X738466Y655413D01*
G01Y653464D02*
X737744Y654439D01*
G01X739188Y652977D02*
X738466Y653464D01*
G01X740631Y652490D02*
X739188Y652977D01*
G01X743518Y652490D02*
X740631D01*
G01X744962Y652977D02*
X743518Y652490D01*
G01X745684Y653464D02*
X744962Y652977D01*
G01X746405Y654439D02*
X745684Y653464D01*
G01Y638361D02*
X746405Y638848D01*
G01Y638361D02*
X745684D01*
G01X746405Y638848D02*
Y638361D01*
G01X744240Y644695D02*
Y649080D01*
G01X737744Y648105D02*
X744240Y644695D01*
G01X746405Y648105D02*
X737744D01*
G01X745684Y630079D02*
X744962Y629591D01*
G01X746405Y631053D02*
X745684Y630079D01*
G01Y632027D02*
X746405Y631053D01*
G01X744962Y632515D02*
X745684Y632027D01*
G01X743518Y633002D02*
X744962Y632515D01*
G01X740631Y633002D02*
X743518D01*
G01X739188Y632515D02*
X740631Y633002D01*
G01X738466Y632027D02*
X739188Y632515D01*
G01X737744Y631053D02*
X738466Y632027D01*
G01Y630079D02*
X737744Y631053D01*
G01X739188Y629591D02*
X738466Y630079D01*
G01X740631Y629104D02*
X739188Y629591D01*
G01X742075D02*
X740631Y629104D01*
G01X742797Y631053D02*
X742075Y629591D01*
G01Y632515D02*
X742797Y631053D01*
G01X740631Y633002D02*
X742075Y632515D01*
G01X737744Y623258D02*
X746405D01*
G01X814044Y-354220D02*
Y-371543D01*
G01X791506Y62242D02*
X795404D01*
G01X791506Y53580D02*
Y62242D01*
G01X795404Y53580D02*
X791506D01*
G01X822687Y55024D02*
X822200Y55746D01*
G01X823175Y54302D02*
X822687Y55024D01*
G01X824149Y53580D02*
X823175Y54302D01*
G01X825123Y53580D02*
X824149D01*
G01X826098Y54302D02*
X825123Y53580D01*
G01X826585Y55024D02*
X826098Y54302D01*
G01X826585Y56467D02*
Y55024D01*
G01X826098Y57189D02*
X826585Y56467D01*
G01X825123Y57911D02*
X826098Y57189D01*
G01X823175Y59354D02*
X825123Y57911D01*
G01X756915Y55746D02*
X756428Y55024D01*
G01X757402Y57911D02*
X756915Y55746D01*
G01Y60076D02*
X757402Y57911D01*
G01X756428Y60798D02*
X756915Y60076D01*
G01X755940Y61520D02*
X756428Y60798D01*
G01X754966Y62242D02*
X755940Y61520D01*
G01X753992Y62242D02*
X754966D01*
G01X780301Y55746D02*
X779813Y55024D01*
G01X780788Y57911D02*
X780301Y55746D01*
G01Y60076D02*
X780788Y57911D01*
G01X779813Y60798D02*
X780301Y60076D01*
G01X779326Y61520D02*
X779813Y60798D01*
G01X778352Y62242D02*
X779326Y61520D01*
G01X777377Y62242D02*
X778352D01*
G01X776403Y61520D02*
X777377Y62242D01*
G01X775916Y60798D02*
X776403Y61520D01*
G01X775429Y60076D02*
X775916Y60798D01*
G01X774941Y57911D02*
X775429Y60076D01*
G01Y55746D02*
X774941Y57911D01*
G01X776403Y54302D02*
X775429Y55746D01*
G01X822687Y60076D02*
X823175Y59354D01*
G01X822687Y60798D02*
Y60076D01*
G01X823175Y61520D02*
X822687Y60798D01*
G01X824149Y62242D02*
X823175Y61520D01*
G01X825123Y62242D02*
X824149D01*
G01X826098Y61520D02*
X825123Y62242D01*
G01X826585Y60798D02*
X826098Y61520D01*
G01X764710Y62242D02*
Y53580D01*
G01X762274Y55024D02*
X764710Y62242D01*
G01X759838D02*
X762274Y55024D01*
G01X759838Y53580D02*
Y62242D01*
G01X770557Y57911D02*
X768121D01*
G01X771531Y58633D02*
X770557Y57911D01*
G01X772018Y59354D02*
X771531Y58633D01*
G01X772018Y60798D02*
Y59354D01*
G01X771531Y61520D02*
X772018Y60798D01*
G01X770557Y62242D02*
X771531Y61520D01*
G01X768121Y62242D02*
X770557D01*
G01X768121Y53580D02*
Y62242D01*
G01X787609Y53580D02*
Y62242D01*
G01X783711D02*
X787609Y53580D01*
G01X783711D02*
Y62242D01*
G01X803199Y53580D02*
Y62242D01*
G01X799302D02*
X803199Y53580D01*
G01X799302D02*
Y62242D01*
G01X754966Y53580D02*
X753992D01*
G01X755940Y54302D02*
X754966Y53580D01*
G01X756428Y55024D02*
X755940Y54302D01*
G01X777377Y53580D02*
X776403Y54302D01*
G01X778352Y53580D02*
X777377D01*
G01X779326Y54302D02*
X778352Y53580D01*
G01X779813Y55024D02*
X779326Y54302D01*
G01X809046Y62242D02*
Y53580D01*
G01X806610Y62242D02*
X811482D01*
G01X791506Y57911D02*
X793942D01*
G01X785644Y131653D02*
X784923Y131166D01*
G01X786366Y132628D02*
X785644Y131653D01*
G01Y133602D02*
X786366Y132628D01*
G01X784923Y134089D02*
X785644Y133602D01*
G01X783479Y134577D02*
X784923Y134089D01*
G01X780592Y134577D02*
X783479D01*
G01X779148Y134089D02*
X780592Y134577D01*
G01X778427Y133602D02*
X779148Y134089D01*
G01X777705Y132628D02*
X778427Y133602D01*
G01Y131653D02*
X777705Y132628D01*
G01X779148Y131166D02*
X778427Y131653D01*
G01X780592Y130679D02*
X779148Y131166D01*
G01X782035D02*
X780592Y130679D01*
G01X782757Y132628D02*
X782035Y131166D01*
G01Y134089D02*
X782757Y132628D01*
G01X780592Y134577D02*
X782035Y134089D01*
G01X780592Y126781D02*
X781314Y126294D01*
G01X779148Y126781D02*
X780592D01*
G01X778427Y126294D02*
X779148Y126781D01*
G01X777705Y125320D02*
X778427Y126294D01*
G01X777705Y124345D02*
Y125320D01*
G01X778427Y123371D02*
X777705Y124345D01*
G01X779148Y122884D02*
X778427Y123371D01*
G01X786366Y122884D02*
Y126781D01*
G01X784201Y123371D02*
X786366Y122884D01*
G01X782757Y124345D02*
X784201Y123371D01*
G01X781314Y126294D02*
X782757Y124345D01*
G01X785644Y146757D02*
X784923Y146270D01*
G01X786366Y147731D02*
X785644Y146757D01*
G01X786366Y148706D02*
Y147731D01*
G01X780592D02*
Y148706D01*
G01X781314Y146757D02*
X780592Y147731D01*
G01X777705Y147244D02*
X781314Y146757D01*
G01X777705Y150167D02*
Y147244D01*
G01X785644Y139936D02*
X786366Y140423D01*
G01Y139936D02*
X785644D01*
G01X786366Y140423D02*
Y139936D01*
G01X788531Y300462D02*
Y164242D01*
G01X785644Y154552D02*
X784923Y154065D01*
G01X786366Y155526D02*
X785644Y154552D01*
G01X786366Y156501D02*
Y155526D01*
G01X785644Y157475D02*
X786366Y156501D01*
G01X784923Y157962D02*
X785644Y157475D01*
G01X783479Y158450D02*
X784923Y157962D01*
G01X782035D02*
X783479Y158450D01*
G01X781314Y157475D02*
X782035Y157962D01*
G01X780592Y156501D02*
X781314Y157475D01*
G01X780592Y155526D02*
Y156501D01*
G01X781314Y154552D02*
X780592Y155526D01*
G01X777705Y155039D02*
X781314Y154552D01*
G01X777705Y157962D02*
Y155039D01*
G01X785644Y149680D02*
X786366Y148706D01*
G01X784923Y150167D02*
X785644Y149680D01*
G01X783479Y150654D02*
X784923Y150167D01*
G01X782035D02*
X783479Y150654D01*
G01X781314Y149680D02*
X782035Y150167D01*
G01X780592Y148706D02*
X781314Y149680D01*
G01X778079Y200856D02*
X776504Y199281D01*
G01X828669Y224872D02*
X828532Y220935D01*
G01X823532D02*
X823669Y224872D01*
G01X813532Y220935D02*
X813669Y224872D01*
G01X828079D02*
Y220935D01*
G01X827094Y224872D02*
Y209518D01*
G01X823079Y220935D02*
Y224872D01*
G01X821091D02*
Y220935D01*
G01X820500Y224872D02*
Y220935D01*
G01X803532D02*
X803669Y224872D01*
G01X818984D02*
Y220935D01*
G01X816563Y224872D02*
Y220935D01*
G01X815972Y224872D02*
Y220935D01*
G01X813079D02*
Y224872D01*
G01X809299D02*
Y220935D01*
G01X808984D02*
Y224872D01*
G01X804968Y209518D02*
Y224872D01*
G01X818394D02*
X818531Y220935D01*
G01X793217D02*
X793354Y224872D01*
G01X783670Y220935D02*
X783807Y224872D01*
G01X783532Y220935D02*
X783669Y224872D01*
G01X803079Y220935D02*
Y224872D01*
G01X798591D02*
Y220935D01*
G01X798000Y224872D02*
Y220935D01*
G01X797094Y224872D02*
Y209518D01*
G01X794063Y224872D02*
Y220935D01*
G01X793472Y224872D02*
Y220935D01*
G01X792764D02*
Y224872D01*
G01X789122D02*
Y220935D01*
G01X788984D02*
Y224872D01*
G01X808709D02*
X808846Y220935D01*
G01X808531D02*
X808394Y224872D01*
G01X783217Y220935D02*
Y224872D01*
G01X783079Y220935D02*
Y224872D01*
G01X781346D02*
Y220935D01*
G01X780638Y224872D02*
Y220935D01*
G01X780539Y200147D02*
Y218573D01*
G01X779063Y224872D02*
Y222116D01*
G01X778472D02*
Y224872D01*
G01X778079Y200856D02*
Y218573D01*
G01X776822Y224872D02*
Y222116D01*
G01X776232Y224872D02*
Y222116D01*
G01X788531Y224872D02*
X788669Y220935D01*
G01X788531D02*
X788394Y224872D01*
G01X780756D02*
X780893Y220935D01*
G01X780047Y224872D02*
X780185Y220935D01*
G01X756485D02*
X756622Y224872D01*
G01X770795Y205187D02*
Y218573D01*
G01X770697Y222116D02*
Y224872D01*
G01X770106D02*
Y222116D01*
G01X766957Y224872D02*
Y222116D01*
G01X766366D02*
Y224872D01*
G01X766268Y218573D02*
Y205187D01*
G01X760831Y224872D02*
Y222116D01*
G01X760241Y224872D02*
Y222116D01*
G01X758984Y200856D02*
Y218573D01*
G01X758591Y222116D02*
Y224872D01*
G01X758000Y222116D02*
Y224872D01*
G01X756524Y200147D02*
Y218573D01*
G01X756031Y220935D02*
Y224872D01*
G01X758984Y200856D02*
X760559Y199281D01*
G01X779063Y222116D02*
X758000D01*
G01X818531Y220935D02*
X828532D01*
G01X783670D02*
X780185D01*
G01X794063D02*
X788531D01*
G01X803532D02*
X798000D01*
G01X816563D02*
X808531D01*
G01X778079Y217392D02*
X854339D01*
G01X827094Y210896D02*
X834968D01*
G01X797094D02*
X804968D01*
G01X827094Y209518D02*
X834968D01*
G01X797094D02*
X804968D01*
G01X770795Y205187D02*
X766268D01*
G01X758984Y200856D02*
X778079D01*
G01X777685Y200462D02*
X854339D01*
G01X756524Y200147D02*
X780539D01*
G01X799555Y304399D02*
G03I-11024J0D01*
G01X806642D02*
G03I-18111J0D01*
G01X810185D02*
G03I-21654J0D01*
G01X787838Y225561D02*
G03X787633Y225915I-205J118D01*
G01X789428Y225916D02*
G03X789225Y225561I1J-236D01*
G01X792838D02*
G03X792633Y225915I-205J118D01*
G01X794428Y225916D02*
G03X794225Y225561I1J-236D01*
G01X797838D02*
G03X797633Y225915I-205J118D01*
G01X799428Y225916D02*
G03X799225Y225561I1J-236D01*
G01X802838D02*
G03X802633Y225915I-205J118D01*
G01X804428Y225916D02*
G03X804225Y225561I1J-236D01*
G01X807838D02*
G03X807633Y225915I-205J118D01*
G01X809428Y225916D02*
G03X809225Y225561I1J-236D01*
G01X812838D02*
G03X812633Y225915I-205J118D01*
G01X814428Y225916D02*
G03X814225Y225561I1J-236D01*
G01X817838D02*
G03X817633Y225915I-205J118D01*
G01X819428Y225916D02*
G03X819225Y225561I1J-236D01*
G01X822838D02*
G03X822633Y225915I-205J118D01*
G01X824428Y225916D02*
G03X824225Y225561I1J-236D01*
G01X827838D02*
G03X827633Y225915I-205J118D01*
G01X829428Y225916D02*
G03X829225Y225561I1J-236D01*
G01X782705Y233069D02*
G03I-1674J0D01*
G01X774122Y225592D02*
G03X774319Y225789I0J197D01*
G01X775303D02*
G03X775500Y225592I197J0D01*
G01X770972D02*
G03X771169Y225789I0J197D01*
G01X772154D02*
G03X772350Y225592I197J0D01*
G01X767823D02*
G03X768020Y225789I0J197D01*
G01X769004D02*
G03X769201Y225592I197J0D01*
G01X764673D02*
G03X764870Y225789I0J197D01*
G01X765854D02*
G03X766051Y225592I197J0D01*
G01X761524D02*
G03X761720Y225789I0J196D01*
G01X762705D02*
G03X762902Y225592I197J0D01*
G01X758374D02*
G03X758571Y225789I0J197D01*
G01X759555D02*
G03X759752Y225592I197J0D01*
G01X777272D02*
G03X777468Y225789I0J196D01*
G01X778453D02*
G03X778650Y225592I197J0D01*
G01X784428Y225916D02*
G03X784225Y225561I1J-236D01*
G01X779428Y225916D02*
G03X779225Y225561I1J-236D01*
G01X782838D02*
G03X782633Y225915I-205J118D01*
G01X754831Y228218D02*
G03X755224Y228612I0J393D01*
G01X756799D02*
G03X757193Y228218I394J0D01*
G01X754558Y224872D02*
G03X754537Y224891I-406J-428D01*
G01X754092Y225555D02*
G03X754288Y225116I590J0D01*
G01X757736D02*
G03X757931Y225555I-395J438D01*
G01X757486Y224891D02*
G03X757466Y224872I397J-438D01*
G01X781610Y236977D02*
X781733Y237019D01*
G01X779642Y236600D02*
X779519Y236558D01*
G01X779560Y236349D02*
X779642Y236391D01*
G01X779519Y236558D02*
X779396Y236475D01*
G01X781569Y237187D02*
X781405Y237061D01*
G01X827855Y225551D02*
X827463Y224872D01*
G01X822855Y225551D02*
X822463Y224872D01*
G01X817855Y225551D02*
X817463Y224872D01*
G01X757736Y225116D02*
X757486Y224891D01*
G01X781528Y236894D02*
X781610Y236977D01*
G01X779478Y236265D02*
X779560Y236349D01*
G01X779396Y236475D02*
X779314Y236391D01*
G01X812855Y225551D02*
X812463Y224872D01*
G01X807855Y225551D02*
X807463Y224872D01*
G01X802855Y225551D02*
X802463Y224872D01*
G01X781405Y237061D02*
X781282Y236894D01*
G01X797855Y225551D02*
X797463Y224872D01*
G01X792855Y225551D02*
X792463Y224872D01*
G01X787855Y225551D02*
X787463Y224872D01*
G01X782855Y225551D02*
X782463Y224872D01*
G01X781487Y236768D02*
X781528Y236894D01*
G01X781282D02*
X781241Y236768D01*
G01X779314Y236391D02*
X779273Y236265D01*
G01X779043Y224977D02*
X779009Y224872D01*
G01X775894Y224977D02*
X775859Y224872D01*
G01X772744Y224977D02*
X772710Y224872D01*
G01X769594Y224977D02*
X769560Y224872D01*
G01X826917Y234132D02*
Y225935D01*
G01X825146Y234132D02*
Y225935D01*
G01X821917Y234132D02*
Y225935D01*
G01X820146Y234132D02*
Y225935D01*
G01X766445Y224977D02*
X766411Y224872D01*
G01X763295Y224977D02*
X763261Y224872D01*
G01X760146Y224977D02*
X760111Y224872D01*
G01X779437Y236056D02*
X779478Y236265D01*
G01X779273D02*
X779232Y236056D01*
G01X816917Y234132D02*
Y225935D01*
G01X815146Y234132D02*
Y225935D01*
G01X811917Y234132D02*
Y225935D01*
G01X810146Y234132D02*
Y225935D01*
G01X806917Y234132D02*
Y225935D01*
G01X805146Y234132D02*
Y225935D01*
G01X801917Y234132D02*
Y225935D01*
G01X800146Y234132D02*
Y225935D01*
G01X796917Y234132D02*
Y225935D01*
G01X795146Y234132D02*
Y225935D01*
G01X791917Y234132D02*
Y225935D01*
G01X790146Y234132D02*
Y225935D01*
G01X786917Y234132D02*
Y225935D01*
G01X785146Y234132D02*
Y225935D01*
G01X782759Y235260D02*
Y237229D01*
G01X782513Y236140D02*
Y235260D01*
G01Y237019D02*
Y236391D01*
G01X781917Y234132D02*
Y225935D01*
G01X781487Y236642D02*
Y236768D01*
G01X781241D02*
Y236600D01*
G01X780913Y237019D02*
Y237229D01*
G01Y235260D02*
Y236600D01*
G01X780708Y237229D02*
Y237019D01*
G01Y236600D02*
Y235260D01*
G01X780380D02*
Y236600D01*
G01X780175Y236223D02*
Y235260D01*
G01Y236600D02*
Y236391D01*
G01X780146Y234132D02*
Y225935D01*
G01X779437Y235260D02*
Y236056D01*
G01X779232D02*
Y235260D01*
G01X779043Y225592D02*
Y224977D01*
G01X778904Y236600D02*
Y236935D01*
G01X778658Y235260D02*
Y236894D01*
G01X778453Y234132D02*
Y225789D01*
G01X778412Y237229D02*
Y235260D01*
G01X777468Y225789D02*
Y234132D01*
G01X776878Y225592D02*
Y224977D01*
G01X775894Y225592D02*
Y224977D01*
G01X775303Y234132D02*
Y225789D01*
G01X774319D02*
Y234132D01*
G01X773728Y225592D02*
Y224977D01*
G01X772744Y225592D02*
Y224977D01*
G01X772154Y234132D02*
Y225789D01*
G01X771169D02*
Y234132D01*
G01X770579Y225592D02*
Y224977D01*
G01X769594Y225592D02*
Y224977D01*
G01X769004Y234132D02*
Y225789D01*
G01X768020D02*
Y234132D01*
G01X767429Y225592D02*
Y224977D01*
G01X766445Y225592D02*
Y224977D01*
G01X765854Y234132D02*
Y225789D01*
G01X764870Y234132D02*
Y225789D01*
G01X764280Y225592D02*
Y224977D01*
G01X763295Y225592D02*
Y224977D01*
G01X762705Y234132D02*
Y225789D01*
G01X761720D02*
Y234132D01*
G01X761130Y225592D02*
Y224977D01*
G01X760146Y225592D02*
Y224977D01*
G01X759555Y234132D02*
Y225789D01*
G01X758571D02*
Y234132D01*
G01X757980Y225592D02*
Y224977D01*
G01X757931Y228218D02*
Y225555D01*
G01X756799Y234132D02*
Y228612D01*
G01X755224Y234132D02*
Y228612D01*
G01X754092Y228218D02*
Y225555D01*
G01X781528Y236517D02*
X781487Y236642D01*
G01X781241Y236600D02*
X781282Y236475D01*
G01X829600Y224872D02*
X829208Y225551D01*
G01X824600Y224872D02*
X824208Y225551D01*
G01X819600Y224872D02*
X819208Y225551D01*
G01X814600Y224872D02*
X814208Y225551D01*
G01X776878Y224977D02*
X776912Y224872D01*
G01X773728Y224977D02*
X773763Y224872D01*
G01X770579Y224977D02*
X770613Y224872D01*
G01X767429Y224977D02*
X767463Y224872D01*
G01X764280Y224977D02*
X764314Y224872D01*
G01X809600D02*
X809208Y225551D01*
G01X804600Y224872D02*
X804208Y225551D01*
G01X799600Y224872D02*
X799208Y225551D01*
G01X761130Y224977D02*
X761164Y224872D01*
G01X757980Y224977D02*
X758015Y224872D01*
G01X794600D02*
X794208Y225551D01*
G01X789600Y224872D02*
X789208Y225551D01*
G01X784600Y224872D02*
X784208Y225551D01*
G01X779600Y224872D02*
X779208Y225551D01*
G01X781282Y236475D02*
X781405Y236307D01*
G01X778904Y236935D02*
X778658Y237229D01*
G01Y236894D02*
X778904Y236600D01*
G01X781610Y236433D02*
X781528Y236517D01*
G01X780175Y236391D02*
X780093Y236475D01*
G01Y236307D02*
X780175Y236223D01*
G01X781405Y236307D02*
X781569Y236182D01*
G01X780093Y236475D02*
X779970Y236558D01*
G01Y236391D02*
X780093Y236307D01*
G01X754288Y225116D02*
X754537Y224891D01*
G01X781733Y236391D02*
X781610Y236433D01*
G01X779970Y236558D02*
X779806Y236600D01*
G01Y236433D02*
X779970Y236391D01*
G01X781774Y237229D02*
X781569Y237187D01*
G01X779642Y236391D02*
X779806Y236433D01*
G01X781569Y236182D02*
X781774Y236140D01*
G01X825146Y225935D02*
X824429D01*
G01X820146D02*
X819429D01*
G01X815146D02*
X814429D01*
G01X810146D02*
X809429D01*
G01X805146D02*
X804429D01*
G01X800146D02*
X799429D01*
G01X795146D02*
X794429D01*
G01X790146D02*
X789429D01*
G01X785146D02*
X784429D01*
G01X780146D02*
X779429D01*
G01X778658Y237229D02*
X778412D01*
G01X780913D02*
X780708D01*
G01X782759D02*
X781774D01*
G01X780708Y237019D02*
X780913D01*
G01X781733D02*
X782513D01*
G01X780380Y236600D02*
X780175D01*
G01X779806D02*
X779642D01*
G01X780913D02*
X780708D01*
G01X782513Y236391D02*
X781733D01*
G01X781774Y236140D02*
X782513D01*
G01Y235260D02*
X782759D01*
G01X780708D02*
X780913D01*
G01X780175D02*
X780380D01*
G01X779232D02*
X779437D01*
G01X778412D02*
X778658D01*
G01X777468Y234132D02*
X778453D01*
G01X774319D02*
X775303D01*
G01X771169D02*
X772154D01*
G01X768020D02*
X769004D01*
G01X764870D02*
X765854D01*
G01X761720D02*
X762705D01*
G01X758571D02*
X759555D01*
G01X756799D02*
X755224D01*
G01X781917D02*
X780146D01*
G01X786917D02*
X785146D01*
G01X791917D02*
X790146D01*
G01X796917D02*
X795146D01*
G01X801917D02*
X800146D01*
G01X806917D02*
X805146D01*
G01X811917D02*
X810146D01*
G01X816917D02*
X815146D01*
G01X821917D02*
X820146D01*
G01X826917D02*
X825146D01*
G01X756799Y231769D02*
X755224D01*
G01X780146Y231171D02*
X781917D01*
G01X786917D02*
X785146D01*
G01X791917D02*
X790146D01*
G01X796917D02*
X795146D01*
G01X801917D02*
X800146D01*
G01X806917D02*
X805146D01*
G01X811917D02*
X810146D01*
G01X816917D02*
X815146D01*
G01X821917D02*
X820146D01*
G01X826917D02*
X825146D01*
G01X755224Y231025D02*
X756799D01*
G01X759555Y230327D02*
X758571D01*
G01X762705D02*
X761720D01*
G01X765854D02*
X764870D01*
G01X769004D02*
X768020D01*
G01X772154D02*
X771169D01*
G01X775303D02*
X774319D01*
G01X778453D02*
X777468D01*
G01X756799Y230280D02*
X755224D01*
G01Y230206D02*
X756799D01*
G01X781917Y230187D02*
X780146D01*
G01X786917D02*
X785146D01*
G01X791917D02*
X790146D01*
G01X796917D02*
X795146D01*
G01X801917D02*
X800146D01*
G01X806917D02*
X805146D01*
G01X811917D02*
X810146D01*
G01X816917D02*
X815146D01*
G01X821917D02*
X820146D01*
G01X826917D02*
X825146D01*
G01X777468Y229772D02*
X778453D01*
G01X774319D02*
X775303D01*
G01X771169D02*
X772154D01*
G01X768020D02*
X769004D01*
G01X764870D02*
X765854D01*
G01X761720D02*
X762705D01*
G01X758571D02*
X759555D01*
G01X777468Y229722D02*
X778453D01*
G01X774319D02*
X775303D01*
G01X771169D02*
X772154D01*
G01X768020D02*
X769004D01*
G01X764870D02*
X765854D01*
G01X761720D02*
X762705D01*
G01X758571D02*
X759555D01*
G01X756799Y229462D02*
X755224D01*
G01X759555Y229217D02*
X758571D01*
G01X762705D02*
X761720D01*
G01X765854D02*
X764870D01*
G01X769004D02*
X768020D01*
G01X772154D02*
X771169D01*
G01X775303D02*
X774319D01*
G01X778453D02*
X777468D01*
G01X781917Y229203D02*
X780146D01*
G01X786917D02*
X785146D01*
G01X791917D02*
X790146D01*
G01X796917D02*
X795146D01*
G01X801917D02*
X800146D01*
G01X806917D02*
X805146D01*
G01X811917D02*
X810146D01*
G01X816917D02*
X815146D01*
G01X821917D02*
X820146D01*
G01X826917D02*
X825146D01*
G01X759555Y229167D02*
X758571D01*
G01X762705D02*
X761720D01*
G01X765854D02*
X764870D01*
G01X769004D02*
X768020D01*
G01X772154D02*
X771169D01*
G01X775303D02*
X774319D01*
G01X778453D02*
X777468D01*
G01X756799Y228717D02*
X755224D01*
G01X759555Y228612D02*
X758571D01*
G01X762705D02*
X761720D01*
G01X765854D02*
X764870D01*
G01X769004D02*
X768020D01*
G01X772154D02*
X771169D01*
G01X775303D02*
X774319D01*
G01X778453D02*
X777468D01*
G01X781917Y228218D02*
X780146D01*
G01X786917D02*
X785146D01*
G01X791917D02*
X790146D01*
G01X796917D02*
X795146D01*
G01X801917D02*
X800146D01*
G01X806917D02*
X805146D01*
G01X811917D02*
X810146D01*
G01X816917D02*
X815146D01*
G01X821917D02*
X820146D01*
G01X826917D02*
X825146D01*
G01X754831D02*
X754092D01*
G01X757931D02*
X757193D01*
G01X759555Y227573D02*
X758571D01*
G01X762705D02*
X761720D01*
G01X765854D02*
X764870D01*
G01X769004D02*
X768020D01*
G01X772154D02*
X771169D01*
G01X775303D02*
X774319D01*
G01X778453D02*
X777468D01*
G01X759555Y227062D02*
X758571D01*
G01X762705D02*
X761720D01*
G01X765854D02*
X764870D01*
G01X769004D02*
X768020D01*
G01X772154D02*
X771169D01*
G01X775303D02*
X774319D01*
G01X778453D02*
X777468D01*
G01X759555Y226879D02*
X758571D01*
G01X762705D02*
X761720D01*
G01X765854D02*
X764870D01*
G01X769004D02*
X768020D01*
G01X772154D02*
X771169D01*
G01X775303D02*
X774319D01*
G01X778453D02*
X777468D01*
G01Y226551D02*
X778453D01*
G01X774319D02*
X775303D01*
G01X771169D02*
X772154D01*
G01X768020D02*
X769004D01*
G01X764870D02*
X765854D01*
G01X761720D02*
X762705D01*
G01X758571D02*
X759555D01*
G01X777468Y226368D02*
X778453D01*
G01X774319D02*
X775303D01*
G01X771169D02*
X772154D01*
G01X768020D02*
X769004D01*
G01X764870D02*
X765854D01*
G01X761720D02*
X762705D01*
G01X758571D02*
X759555D01*
G01X782633Y225935D02*
X781917D01*
G01X787633D02*
X786917D01*
G01X792633D02*
X791917D01*
G01X797633D02*
X796917D01*
G01X802633D02*
X801917D01*
G01X807633D02*
X806917D01*
G01X812633D02*
X811917D01*
G01X817633D02*
X816917D01*
G01X822633D02*
X821917D01*
G01X827633D02*
X826917D01*
G01X759555Y225856D02*
X758571D01*
G01X762705D02*
X761720D01*
G01X765854D02*
X764870D01*
G01X769004D02*
X768020D01*
G01X772154D02*
X771169D01*
G01X775303D02*
X774319D01*
G01X778453D02*
X777468D01*
G01X758374Y225592D02*
X757980D01*
G01X760146D02*
X759752D01*
G01X761524D02*
X761130D01*
G01X763295D02*
X762902D01*
G01X764673D02*
X764280D01*
G01X766445D02*
X766051D01*
G01X767823D02*
X767429D01*
G01X769594D02*
X769201D01*
G01X770972D02*
X770579D01*
G01X774122D02*
X773728D01*
G01X772744D02*
X772350D01*
G01X775894D02*
X775500D01*
G01X777272D02*
X776878D01*
G01X779043D02*
X778650D01*
G01X804787Y312383D02*
X925995Y371907D01*
G01X807176Y329990D02*
G03X809960Y331143I0J3938D01*
G01X767103D02*
G03X769887Y329990I2784J2785D01*
G01X839150Y360333D02*
X809960Y331143D01*
G01X807176Y329990D02*
X769887D01*
G01X799224Y307079D02*
X924189Y304404D01*
G01X828492Y506286D02*
Y615029D01*
G01X831184Y506084D02*
G03X828492Y502349I1245J-3735D01*
G01X831184Y506084D02*
G03X828492Y502349I1245J-3735D01*
G01Y484402D02*
G03X831184Y480667I3937J0D01*
G01X828492Y484402D02*
G03X831184Y480667I3937J0D01*
G01X828492Y502349D02*
Y484402D01*
G01Y502349D02*
Y484402D01*
G01X825605Y655413D02*
X826327Y654439D01*
G01X824883Y655900D02*
X825605Y655413D01*
G01X823440Y656388D02*
X824883Y655900D01*
G01X820552Y656388D02*
X823440D01*
G01X819109Y655900D02*
X820552Y656388D01*
G01X818387Y655413D02*
X819109Y655900D01*
G01X817665Y654439D02*
X818387Y655413D01*
G01Y653464D02*
X817665Y654439D01*
G01X819109Y652977D02*
X818387Y653464D01*
G01X820552Y652490D02*
X819109Y652977D01*
G01X823440Y652490D02*
X820552D01*
G01X824883Y652977D02*
X823440Y652490D01*
G01X825605Y653464D02*
X824883Y652977D01*
G01X826327Y654439D02*
X825605Y653464D01*
G01Y638361D02*
X826327Y638848D01*
G01Y638361D02*
X825605D01*
G01X826327Y638848D02*
Y638361D01*
G01X825605Y621796D02*
X824883Y621309D01*
G01X826327Y622771D02*
X825605Y621796D01*
G01X826327Y623745D02*
Y622771D01*
G01X825605Y624719D02*
X826327Y623745D01*
G01X824883Y625207D02*
X825605Y624719D01*
G01X824161Y625694D02*
X824883Y625207D01*
G01X823440Y625694D02*
X824161D01*
G01X822718Y625207D02*
X823440Y625694D01*
G01X821996Y624719D02*
X822718Y625207D01*
G01X821274Y623745D02*
X821996Y624719D01*
G01X820552D02*
X821274Y623745D01*
G01X819831Y625207D02*
X820552Y624719D01*
G01X819109Y625207D02*
X819831D01*
G01X818387Y624719D02*
X819109Y625207D01*
G01X817665Y623745D02*
X818387Y624719D01*
G01X817665Y622771D02*
Y623745D01*
G01X818387Y621796D02*
X817665Y622771D01*
G01Y648592D02*
Y644695D01*
G01X819109Y648105D02*
X817665Y648592D01*
G01X820552Y647618D02*
X819109Y648105D01*
G01X822718Y647131D02*
X820552Y647618D01*
G01X826327Y646644D02*
X822718Y647131D01*
G01X825605Y630079D02*
X824883Y629591D01*
G01X826327Y631053D02*
X825605Y630079D01*
G01Y632027D02*
X826327Y631053D01*
G01X824883Y632515D02*
X825605Y632027D01*
G01X823440Y633002D02*
X824883Y632515D01*
G01X820552Y633002D02*
X823440D01*
G01X819109Y632515D02*
X820552Y633002D01*
G01X818387Y632027D02*
X819109Y632515D01*
G01X817665Y631053D02*
X818387Y632027D01*
G01Y630079D02*
X817665Y631053D01*
G01X819109Y629591D02*
X818387Y630079D01*
G01X820552Y629104D02*
X819109Y629591D01*
G01X821996D02*
X820552Y629104D01*
G01X822718Y631053D02*
X821996Y629591D01*
G01Y632515D02*
X822718Y631053D01*
G01X820552Y633002D02*
X821996Y632515D01*
G01X821274Y622771D02*
Y623745D01*
G01X814044Y1006410D02*
Y989087D01*
G01X834765Y-278208D02*
Y-82686D01*
G01X846073Y62242D02*
X849971D01*
G01X846073Y53580D02*
Y62242D01*
G01X849971Y53580D02*
X846073D01*
G01X838278D02*
Y62242D01*
G01X840227Y53580D02*
X838278D01*
G01X841201Y54302D02*
X840227Y53580D01*
G01X841688Y55024D02*
X841201Y54302D01*
G01X842176Y55746D02*
X841688Y55024D01*
G01X842663Y57911D02*
X842176Y55746D01*
G01Y60076D02*
X842663Y57911D01*
G01X841688Y60798D02*
X842176Y60076D01*
G01X841201Y61520D02*
X841688Y60798D01*
G01X840227Y62242D02*
X841201Y61520D01*
G01X838278Y62242D02*
X840227D01*
G01X832432D02*
Y53580D01*
G01X846073Y57911D02*
X848509D01*
G01X901983Y131653D02*
X901261Y131166D01*
G01X902705Y132628D02*
X901983Y131653D01*
G01Y133602D02*
X902705Y132628D01*
G01X901261Y134089D02*
X901983Y133602D01*
G01X899818Y134577D02*
X901261Y134089D01*
G01X896930Y134577D02*
X899818D01*
G01X895487Y134089D02*
X896930Y134577D01*
G01X894765Y133602D02*
X895487Y134089D01*
G01X894043Y132628D02*
X894765Y133602D01*
G01Y131653D02*
X894043Y132628D01*
G01X895487Y131166D02*
X894765Y131653D01*
G01X896930Y130679D02*
X895487Y131166D01*
G01X898374D02*
X896930Y130679D01*
G01X899096Y132628D02*
X898374Y131166D01*
G01Y134089D02*
X899096Y132628D01*
G01X896930Y134577D02*
X898374Y134089D01*
G01X871661Y146270D02*
Y150167D01*
G01X869496Y146757D02*
X871661Y146270D01*
G01X868052Y147731D02*
X869496Y146757D01*
G01X867331Y148706D02*
X868052Y147731D01*
G01X863000D02*
Y148706D01*
G01X863722Y146757D02*
X863000Y147731D01*
G01X864444Y146270D02*
X863722Y146757D01*
G01X870940Y123371D02*
X870218Y122884D01*
G01X871661Y124345D02*
X870940Y123371D01*
G01X871661Y125320D02*
Y124345D01*
G01X870940Y126294D02*
X871661Y125320D01*
G01X870218Y126781D02*
X870940Y126294D01*
G01X868774Y127269D02*
X870218Y126781D01*
G01X867331D02*
X868774Y127269D01*
G01X866609Y126294D02*
X867331Y126781D01*
G01X865887Y125320D02*
X866609Y126294D01*
G01X865887Y124345D02*
Y125320D01*
G01X866609Y123371D02*
X865887Y124345D01*
G01X863000Y123858D02*
X866609Y123371D01*
G01X863000Y126781D02*
Y123858D01*
G01X870940Y139936D02*
X871661Y140423D01*
G01Y139936D02*
X870940D01*
G01X871661Y140423D02*
Y139936D01*
G01X901983Y123371D02*
X901261Y122884D01*
G01X902705Y124345D02*
X901983Y123371D01*
G01X902705Y125320D02*
Y124345D01*
G01X901983Y126294D02*
X902705Y125320D01*
G01X901261Y126781D02*
X901983Y126294D01*
G01X899818Y127269D02*
X901261Y126781D01*
G01X898374D02*
X899818Y127269D01*
G01X897652Y126294D02*
X898374Y126781D01*
G01X896930Y125320D02*
X897652Y126294D01*
G01X896930Y124345D02*
Y125320D01*
G01X897652Y123371D02*
X896930Y124345D01*
G01X894043Y123858D02*
X897652Y123371D01*
G01X894043Y126781D02*
Y123858D01*
G01X901983Y139936D02*
X902705Y140423D01*
G01Y139936D02*
X901983D01*
G01X902705Y140423D02*
Y139936D01*
G01X863000Y132628D02*
X871661D01*
G01X873827Y197313D02*
Y164242D01*
G01X904870Y199281D02*
Y164242D01*
G01X868386Y218577D02*
X868422Y218583D01*
G01X868351Y218574D02*
X868386Y218577D01*
G01X868315Y218573D02*
X868351Y218574D01*
G01X866609Y149680D02*
X867331Y148706D01*
G01X865887Y150167D02*
X866609Y149680D01*
G01X864444Y150167D02*
X865887D01*
G01X863722Y149680D02*
X864444Y150167D01*
G01X863000Y148706D02*
X863722Y149680D01*
G01X865887Y157962D02*
X866609Y157475D01*
G01X864444Y157962D02*
X865887D01*
G01X863722Y157475D02*
X864444Y157962D01*
G01X863000Y156501D02*
X863722Y157475D01*
G01X863000Y155526D02*
Y156501D01*
G01X863722Y154552D02*
X863000Y155526D01*
G01X864444Y154065D02*
X863722Y154552D01*
G01X871661Y154065D02*
Y157962D01*
G01X869496Y154552D02*
X871661Y154065D01*
G01X868052Y155526D02*
X869496Y154552D01*
G01X866609Y157475D02*
X868052Y155526D01*
G01X901983Y156988D02*
X902705Y156014D01*
G01X901261Y157475D02*
X901983Y156988D01*
G01X899818Y157962D02*
X901261Y157475D01*
G01X896930Y157962D02*
X899818D01*
G01X895487Y157475D02*
X896930Y157962D01*
G01X894765Y156988D02*
X895487Y157475D01*
G01X894043Y156014D02*
X894765Y156988D01*
G01Y155039D02*
X894043Y156014D01*
G01X895487Y154552D02*
X894765Y155039D01*
G01X896930Y154065D02*
X895487Y154552D01*
G01X899818Y154065D02*
X896930D01*
G01X901261Y154552D02*
X899818Y154065D01*
G01X901983Y155039D02*
X901261Y154552D01*
G01X902705Y156014D02*
X901983Y155039D01*
G01X872961Y220541D02*
G03X873433Y220069I472J0D01*
G01X874614D02*
G03X875087Y220541I0J473D01*
G01X872842D02*
G03X873433Y219951I590J0D01*
G01X874614D02*
G03X875205Y220541I0J591D01*
G01X884260Y218376D02*
G03X885047Y219163I0J787D01*
G01X880717Y223100D02*
G03X883079I1181J0D01*
G01X881307Y213061D02*
G03X882488Y214242I0J1181D01*
G01X873827Y201250D02*
G03X875795Y199281I1969J0D01*
G01X900933D02*
G03X904870Y203218I0J3937D01*
G01X855520Y218573D02*
G03X854339Y217392I0J-1181D01*
G01X876976Y215226D02*
X877764Y216014D01*
G01X854339Y200462D02*
X853157Y199281D01*
G01X904870Y203218D02*
Y404328D01*
G01X885047Y228612D02*
Y219163D01*
G01X883079Y224675D02*
Y223100D01*
G01X882488Y214242D02*
Y217667D01*
G01X880717Y224675D02*
Y223100D01*
G01X879575Y217667D02*
Y215226D01*
G01X879339Y229399D02*
Y218376D01*
G01X878787Y217667D02*
Y216014D01*
G01X878748Y231762D02*
Y216014D01*
G01X877764Y231762D02*
Y216014D01*
G01X876976Y232549D02*
Y215226D01*
G01X875205Y231171D02*
Y220541D01*
G01X875067D02*
Y224085D01*
G01X874614Y219951D02*
Y220088D01*
G01X873827Y224872D02*
Y201250D01*
G01X873433Y220088D02*
Y219951D01*
G01X872980Y224085D02*
Y220541D01*
G01X872842D02*
Y231171D01*
G01X872646Y199281D02*
Y235502D01*
G01X869496Y218573D02*
Y201327D01*
G01X868315Y199281D02*
Y201327D01*
G01Y218573D02*
Y199281D01*
G01X853611Y220935D02*
X853748Y224872D01*
G01X853217Y220935D02*
X853354Y224872D01*
G01X861740Y201328D02*
Y216525D01*
G01X856701Y226053D02*
Y218573D01*
G01X854339Y217392D02*
Y200462D01*
G01X853157Y220935D02*
Y224872D01*
G01X852764Y220935D02*
Y224872D01*
G01X843532Y220935D02*
X843669Y224872D01*
G01X843335Y220935D02*
X843472Y224872D01*
G01X849181D02*
Y220935D01*
G01X848984Y224872D02*
Y220935D01*
G01X843079D02*
Y224872D01*
G01X842882Y220935D02*
Y224872D01*
G01X838984D02*
Y220935D01*
G01X834968Y209518D02*
Y224872D01*
G01X848728Y220935D02*
X848591Y224872D01*
G01X848394D02*
X848531Y220935D01*
G01X833984Y224872D02*
Y220935D01*
G01X838394Y224872D02*
X838531Y220935D01*
G01X833531D02*
X833394Y224872D01*
G01X865992Y226053D02*
X869496Y218573D01*
G01X864923Y226053D02*
X868422Y218583D01*
G01X869496Y201327D02*
X870677Y199281D01*
G01X879575Y215226D02*
X878787Y216014D01*
G01X859693Y218573D02*
X861740Y216525D01*
G01D02*
X859693Y218573D01*
G01X863787Y199281D02*
X861740Y201328D01*
G01X869491Y218583D02*
X869384Y218645D01*
G01X869148Y218666D02*
X869385Y218644D01*
G01X843532Y220935D02*
X833531D01*
G01X853611D02*
X848531D01*
G01X875067Y220541D02*
X875205D01*
G01X872980D02*
X872842D01*
G01X874614Y220088D02*
X873433D01*
G01X874614Y219951D02*
X873433D01*
G01X884260Y218376D02*
X877764D01*
G01X882488Y217667D02*
X877764D01*
G01X878748Y217588D02*
X877764D01*
G01X878787Y217273D02*
X877764D01*
G01X878748Y216801D02*
X877764D01*
G01Y216469D02*
X878748D01*
G01X877764Y216453D02*
X878748D01*
G01Y216210D02*
X877764D01*
G01X878748Y216117D02*
X877764D01*
G01X878787Y216014D02*
X877764D01*
G01X876976Y215226D02*
X879575D01*
G01X882488Y215029D02*
X872646D01*
G01X881307Y213061D02*
X872646D01*
G01X868815Y218644D02*
X869152Y218666D01*
G01X869496Y201327D02*
X861740Y201328D01*
G01X875795Y199281D02*
X900933D01*
G01X872646D02*
X863787D01*
G01X868422Y218583D02*
X868818Y218645D01*
G01X868422Y218583D02*
X868386Y218577D01*
G01X894043Y148218D02*
X902705D01*
G01X875795Y226840D02*
X947783D01*
G01X875087Y231171D02*
G03X874614Y231644I-473J0D01*
G01X873433D02*
G03X872961Y231171I0J-472D01*
G01X873433Y231762D02*
G03X872842Y231171I0J-591D01*
G01X875205D02*
G03X874614Y231762I-591J0D01*
G01X885047Y228612D02*
G03X884260Y229399I-787J0D01*
G01X883079Y224675D02*
G03X880717I-1181J0D01*
G01X882488Y233533D02*
G03X881307Y234714I-1181J0D01*
G01X857882Y227431D02*
G03X858276Y227037I394J0D01*
G01Y233336D02*
G03X857882Y232943I0J-394D01*
G01X859654D02*
G03X859260Y233336I-393J0D01*
G01Y227037D02*
G03X859654Y227431I0J394D01*
G01X870087Y226998D02*
G03X870520Y227431I0J433D01*
G01X866504D02*
G03X866937Y226998I433J0D01*
G01Y233376D02*
G03X866504Y232943I0J-433D01*
G01X870520D02*
G03X870087Y233376I-433J0D01*
G01X858276Y233533D02*
G03X857685Y232943I0J-591D01*
G01X870677D02*
G03X870087Y233533I-590J0D01*
G01X866937D02*
G03X866346Y232943I0J-591D01*
G01Y227431D02*
G03X866937Y226840I591J0D01*
G01X870087D02*
G03X870677Y227431I0J590D01*
G01X859260Y226840D02*
G03X859850Y227431I0J590D01*
G01Y232943D02*
G03X859260Y233533I-590J0D01*
G01X857685Y227432D02*
G03X858276Y226840I591J-1D01*
G01X864693Y230777D02*
G03I-1575J0D01*
G01X865480D02*
G03I-2362J0D01*
G01X865795D02*
G03I-2657J0D01*
G01X866071D02*
G03I-2953J0D01*
G01X873827Y224872D02*
G03X871858Y226840I-1968J0D01*
G01X844428Y225916D02*
G03X844225Y225561I1J-236D01*
G01X847838D02*
G03X847633Y225915I-205J118D01*
G01X849428Y225916D02*
G03X849225Y225561I1J-236D01*
G01X852838D02*
G03X852633Y225915I-205J118D01*
G01X832838Y225561D02*
G03X832633Y225915I-205J118D01*
G01X834428Y225916D02*
G03X834225Y225561I1J-236D01*
G01X837838D02*
G03X837633Y225915I-205J118D01*
G01X839428Y225916D02*
G03X839225Y225561I1J-236D01*
G01X842838D02*
G03X842633Y225915I-205J118D01*
G01X879575Y232549D02*
X878787Y231762D01*
G01X852855Y225551D02*
X852463Y224872D01*
G01X876494Y286560D02*
X877232Y286811D01*
G01X873295Y285806D02*
X872557Y285555D01*
G01Y286560D02*
X873295Y286811D01*
G01X876986Y285806D02*
X876494Y285555D01*
G01X865913Y285806D02*
X865421Y285555D01*
G01X855333Y279021D02*
X856563Y279775D01*
G01X855825Y280780D02*
X855087Y280277D01*
G01X876494Y285555D02*
X876248Y285303D01*
G01X875756Y285806D02*
X876494Y286560D01*
G01X872557Y285555D02*
X872065Y285052D01*
G01Y286057D02*
X872557Y286560D01*
G01X865421Y285555D02*
X865175Y285303D01*
G01X864683Y285806D02*
X865421Y286560D01*
G01X861484Y285555D02*
X860992Y285052D01*
G01Y286057D02*
X861484Y286560D01*
G01X847855Y225551D02*
X847463Y224872D01*
G01X842855Y225551D02*
X842463Y224872D01*
G01X837855Y225551D02*
X837463Y224872D01*
G01X876248Y285303D02*
X876002Y284801D01*
G01X865421Y286560D02*
X866159Y286811D01*
G01X862222Y285806D02*
X861484Y285555D01*
G01Y286560D02*
X862222Y286811D01*
G01X846967Y286560D02*
X843522Y284801D01*
G01X841799D02*
X846474Y287314D01*
G01X851396Y286057D02*
X850165Y285303D01*
G01X850657Y284047D02*
X851642Y284801D01*
G01X856563Y279775D02*
X857301Y280780D01*
G01X856317Y281534D02*
X855825Y280780D01*
G01X846967Y283042D02*
X846474Y282288D01*
G01X832855Y225551D02*
X832463Y224872D01*
G01X865175Y285303D02*
X864929Y284801D01*
G01X857301Y280780D02*
X857793Y282036D01*
G01X856563Y282288D02*
X856317Y281534D01*
G01X882488Y233533D02*
Y230108D01*
G01X870283Y235502D02*
X870077Y229596D01*
G01X865165Y235502D02*
X864959Y229596D01*
G01X879939Y284801D02*
Y278770D01*
G01X879575Y232549D02*
Y230108D01*
G01X878787Y231762D02*
Y230108D01*
G01X878709Y278770D02*
Y284801D01*
G01X876002D02*
Y278770D01*
G01X875150Y224085D02*
Y226053D01*
G01X875067D02*
Y231171D01*
G01X874772Y278770D02*
Y284801D01*
G01X874614Y231624D02*
Y231762D01*
G01X873433Y231624D02*
Y231762D01*
G01X872980Y226053D02*
Y231171D01*
G01X872897Y224085D02*
Y226053D01*
G01X872065Y285052D02*
Y278770D01*
G01Y286811D02*
Y286057D01*
G01X870835Y278770D02*
Y286811D01*
G01X870697Y235502D02*
Y224872D01*
G01X870677Y235502D02*
Y232943D01*
G01Y227431D02*
Y224872D01*
G01X870533Y227431D02*
Y232943D01*
G01X870087Y233389D02*
Y233533D01*
G01Y226985D02*
Y226840D01*
G01X869496Y235502D02*
Y229596D01*
G01X868866Y284801D02*
Y278770D01*
G01X867636D02*
Y284801D01*
G01X866937Y233389D02*
Y233533D01*
G01Y226985D02*
Y226840D01*
G01X866491Y227431D02*
Y232943D01*
G01X866346D02*
Y227431D01*
G01X865953Y235502D02*
Y229596D01*
G01X864929Y284801D02*
Y278770D01*
G01X864575Y235502D02*
Y229596D01*
G01X863699Y278770D02*
Y284801D01*
G01X861819Y229596D02*
Y235502D01*
G01X860992Y285052D02*
Y278770D01*
G01Y286811D02*
Y286057D01*
G01X860441Y235502D02*
Y229596D01*
G01X859850Y227431D02*
Y232943D01*
G01X859762Y278770D02*
Y286811D01*
G01X859665Y232943D02*
Y227431D01*
G01X859260Y226840D02*
Y227026D01*
G01Y235502D02*
Y229596D01*
G01X858276Y233348D02*
Y233533D01*
G01Y226840D02*
Y227026D01*
G01X857871Y227432D02*
Y232943D01*
G01X857793Y282036D02*
Y283042D01*
G01X857685Y224872D02*
Y227432D01*
G01Y232943D02*
Y235502D01*
G01X857301Y289324D02*
Y290581D01*
G01X856563Y282790D02*
Y282288D01*
G01X855717Y235502D02*
Y224872D01*
G01X851917Y234132D02*
Y225935D01*
G01X850165Y285303D02*
Y289324D01*
G01X850146Y234132D02*
Y225935D01*
G01X857670Y224872D02*
X857664Y235502D01*
G01X861228D02*
X861435Y229596D01*
G01X858472Y235502D02*
X858679Y229596D01*
G01X879447Y286057D02*
X879939Y284801D01*
G01X848935Y290581D02*
Y284047D01*
G01X846917Y234132D02*
Y225935D01*
G01X845146Y234132D02*
Y225935D01*
G01X841917Y234132D02*
Y225935D01*
G01X840146Y234132D02*
Y225935D01*
G01X839831Y290581D02*
Y278770D01*
G01X838354Y285806D02*
Y290581D01*
G01Y278770D02*
Y284298D01*
G01X836917Y234132D02*
Y225935D01*
G01X835146Y234132D02*
Y225935D01*
G01X856317Y283544D02*
X856563Y282790D01*
G01X868374Y286057D02*
X868866Y284801D01*
G01X878709D02*
X878463Y285303D01*
G01X874772Y284801D02*
X874526Y285303D01*
G01X831917Y234132D02*
Y225935D01*
G01X831465Y284298D02*
Y278770D01*
G01Y290581D02*
Y285806D01*
G01X830146Y234132D02*
Y225935D01*
G01X829988Y278770D02*
Y290581D01*
G01X857793Y283042D02*
X857301Y284298D01*
G01X867636Y284801D02*
X867390Y285303D01*
G01X863699Y284801D02*
X863453Y285303D01*
G01X850904Y280780D02*
X850411Y281785D01*
G01X848935D02*
X849427Y280780D01*
G01X855825Y284298D02*
X856317Y283544D01*
G01X846474Y287314D02*
X846967Y286560D01*
G01X857301Y284298D02*
X856563Y285303D01*
G01X878955Y286560D02*
X879447Y286057D01*
G01X878463Y285303D02*
X878217Y285555D01*
G01X875018Y286560D02*
X875756Y285806D01*
G01X874526Y285303D02*
X874280Y285555D01*
G01X849600Y224872D02*
X849208Y225551D01*
G01X849427Y280780D02*
X850165Y279775D01*
G01X867882Y286560D02*
X868374Y286057D01*
G01X867390Y285303D02*
X867144Y285555D01*
G01X863945Y286560D02*
X864683Y285806D01*
G01X863453Y285303D02*
X863207Y285555D01*
G01X844600Y224872D02*
X844208Y225551D01*
G01X839600Y224872D02*
X839208Y225551D01*
G01X834600Y224872D02*
X834208Y225551D01*
G01X877764Y231762D02*
X876976Y232549D01*
G01X855087Y284801D02*
X855825Y284298D01*
G01X851642Y280277D02*
X850904Y280780D01*
G01X856563Y285303D02*
X855333Y286057D01*
G01X878217Y285555D02*
X877724Y285806D01*
G01X874280Y285555D02*
X873787Y285806D01*
G01X867144Y285555D02*
X866652Y285806D01*
G01X863207Y285555D02*
X862715Y285806D01*
G01X850165Y279775D02*
X851396Y279021D01*
G01X846474Y282288D02*
X841799Y284801D01*
G01X843522D02*
X846967Y283042D01*
G01X878217Y286811D02*
X878955Y286560D01*
G01X874280Y286811D02*
X875018Y286560D01*
G01X867144Y286811D02*
X867882Y286560D01*
G01X863207Y286811D02*
X863945Y286560D01*
G01X854102Y285052D02*
X855087Y284801D01*
G01X855333Y286057D02*
X854102Y286308D01*
G01X852626Y280026D02*
X851642Y280277D01*
G01X851396Y279021D02*
X852626Y278770D01*
G01X838354Y290581D02*
X839831D01*
G01X829988D02*
X831465D01*
G01X857301D02*
X848935D01*
G01X850165Y289324D02*
X857301D01*
G01X877232Y286811D02*
X878217D01*
G01X873295D02*
X874280D01*
G01X870835D02*
X872065D01*
G01X866159D02*
X867144D01*
G01X862222D02*
X863207D01*
G01X859762D02*
X860992D01*
G01X854102Y286308D02*
X852626D01*
G01X831465Y285806D02*
X838354D01*
G01X862715D02*
X862222D01*
G01X866652D02*
X865913D01*
G01X873787D02*
X873295D01*
G01X877724D02*
X876986D01*
G01X852626Y285052D02*
X854102D01*
G01X838354Y284298D02*
X831465D01*
G01X848935Y284047D02*
X850657D01*
G01X850411Y281785D02*
X848935D01*
G01X854102Y280026D02*
X852626D01*
G01Y278770D02*
X854102D01*
G01X831465D02*
X829988D01*
G01X839831D02*
X838354D01*
G01X860992D02*
X859762D01*
G01X864929D02*
X863699D01*
G01X868866D02*
X867636D01*
G01X872065D02*
X870835D01*
G01X876002D02*
X874772D01*
G01X879939D02*
X878709D01*
G01X852626Y286308D02*
X851396Y286057D01*
G01X851642Y284801D02*
X852626Y285052D01*
G01X854102Y278770D02*
X855333Y279021D01*
G01X855087Y280277D02*
X854102Y280026D01*
G01X857685Y227432D02*
X857871Y227431D01*
G01X850146Y225935D02*
X849429D01*
G01X845146D02*
X844429D01*
G01X840146D02*
X839429D01*
G01X835146D02*
X834429D01*
G01X830146D02*
X829429D01*
G01X872646Y235502D02*
X855717D01*
G01X872646Y234714D02*
X881307D01*
G01X831917Y234132D02*
X830146D01*
G01X836917D02*
X835146D01*
G01X841917D02*
X840146D01*
G01X846917D02*
X845146D01*
G01X851917D02*
X850146D01*
G01X859260Y233533D02*
X858276D01*
G01X870087D02*
X866937D01*
G01Y233389D02*
X870087D01*
G01X859260Y233348D02*
X858276D01*
G01X870533Y232943D02*
X870677D01*
G01X857685D02*
X857871D01*
G01X859850D02*
X859665D01*
G01X866491D02*
X866346D01*
G01X882488Y232746D02*
X872646D01*
G01X876976Y232549D02*
X879575D01*
G01X873433Y231762D02*
X874614D01*
G01X878787D02*
X877764D01*
G01Y231660D02*
X878748D01*
G01X874614Y231624D02*
X873433D01*
G01X878748Y231565D02*
X877764D01*
G01X878748Y231322D02*
X877764D01*
G01Y231306D02*
X878748D01*
G01X831917Y231171D02*
X830146D01*
G01X836917D02*
X835146D01*
G01X841917D02*
X840146D01*
G01X846917D02*
X845146D01*
G01X851917D02*
X850146D01*
G01X875067D02*
X875205D01*
G01X872980D02*
X872842D01*
G01X878748Y230974D02*
X877764D01*
G01X878787Y230502D02*
X877764D01*
G01X831917Y230187D02*
X830146D01*
G01X836917D02*
X835146D01*
G01X841917D02*
X840146D01*
G01X846917D02*
X845146D01*
G01X851917D02*
X850146D01*
G01X878748D02*
X877764D01*
G01X882488Y230108D02*
X877764D01*
G01X858679Y229596D02*
X870077D01*
G01X884260Y229399D02*
X877764D01*
G01X831917Y229203D02*
X830146D01*
G01X836917D02*
X835146D01*
G01X841917D02*
X840146D01*
G01X846917D02*
X845146D01*
G01X851917D02*
X850146D01*
G01X831917Y228218D02*
X830146D01*
G01X836917D02*
X835146D01*
G01X841917D02*
X840146D01*
G01X846917D02*
X845146D01*
G01X851917D02*
X850146D01*
G01X859665Y227431D02*
X859850D01*
G01X866491D02*
X866346D01*
G01X870677D02*
X870533D01*
G01X859260Y227026D02*
X858276D01*
G01X870087Y226985D02*
X866937D01*
G01X865992Y226053D02*
X856701D01*
G01X875150D02*
X872897D01*
G01X832633Y225935D02*
X831917D01*
G01X837633D02*
X836917D01*
G01X842633D02*
X841917D01*
G01X847633D02*
X846917D01*
G01X852633D02*
X851917D01*
G01X875150Y224085D02*
X872897D01*
G01X873645Y354834D02*
X873669Y354990D01*
G01X873578Y354702D02*
X873645Y354834D01*
G01X873464Y354590D02*
X873578Y354702D01*
G01X873330Y354521D02*
X873464Y354590D01*
G01X873177Y354498D02*
X873330Y354521D01*
G01X856716Y354834D02*
X856740Y354990D01*
G01X856648Y354702D02*
X856716Y354834D01*
G01X856535Y354590D02*
X856648Y354702D01*
G01X856401Y354521D02*
X856535Y354590D01*
G01X856248Y354498D02*
X856401Y354521D01*
G01X873645Y371764D02*
X873669Y371919D01*
G01X873578Y371631D02*
X873645Y371764D01*
G01X873464Y371519D02*
X873578Y371631D01*
G01X873330Y371450D02*
X873464Y371519D01*
G01X873177Y371427D02*
X873330Y371450D01*
G01X856119Y354515D02*
X856057Y354535D01*
G01X856183Y354502D02*
X856119Y354515D01*
G01X856248Y354498D02*
X856183Y354502D01*
G01X873048Y354515D02*
X872986Y354535D01*
G01X873112Y354502D02*
X873048Y354515D01*
G01X873177Y354498D02*
X873112Y354502D01*
G01X856716Y371764D02*
X856740Y371919D01*
G01X856648Y371631D02*
X856716Y371764D01*
G01X856535Y371519D02*
X856648Y371631D01*
G01X856401Y371450D02*
X856535Y371519D01*
G01X856248Y371427D02*
X856401Y371450D01*
G01X856119Y371444D02*
X856057Y371464D01*
G01X856183Y371432D02*
X856119Y371444D01*
G01X856248Y371427D02*
X856183Y371432D01*
G01X873048Y371444D02*
X872986Y371464D01*
G01X873112Y371432D02*
X873048Y371444D01*
G01X873177Y371427D02*
X873112Y371432D01*
G01X855764Y354897D02*
X855756Y354990D01*
G01X855787Y354817D02*
X855764Y354897D01*
G01X855819Y354749D02*
X855787Y354817D01*
G01X855856Y354693D02*
X855819Y354749D01*
G01X855898Y354645D02*
X855856Y354693D01*
G01X855939Y354607D02*
X855898Y354645D01*
G01X855980Y354576D02*
X855939Y354607D01*
G01X856024Y354550D02*
X855980Y354576D01*
G01X856057Y354535D02*
X856024Y354550D01*
G01X872693Y354897D02*
X872685Y354990D01*
G01X872716Y354817D02*
X872693Y354897D01*
G01X872748Y354749D02*
X872716Y354817D01*
G01X872785Y354693D02*
X872748Y354749D01*
G01X872827Y354645D02*
X872785Y354693D01*
G01X872868Y354607D02*
X872827Y354645D01*
G01X872909Y354576D02*
X872868Y354607D01*
G01X872953Y354550D02*
X872909Y354576D01*
G01X872986Y354535D02*
X872953Y354550D01*
G01X855764Y371826D02*
X855756Y371919D01*
G01X855787Y371746D02*
X855764Y371826D01*
G01X855819Y371679D02*
X855787Y371746D01*
G01X855856Y371622D02*
X855819Y371679D01*
G01X855898Y371574D02*
X855856Y371622D01*
G01X855939Y371536D02*
X855898Y371574D01*
G01X855980Y371505D02*
X855939Y371536D01*
G01X856024Y371479D02*
X855980Y371505D01*
G01X856057Y371464D02*
X856024Y371479D01*
G01X872693Y371826D02*
X872685Y371919D01*
G01X872716Y371746D02*
X872693Y371826D01*
G01X872748Y371679D02*
X872716Y371746D01*
G01X872785Y371622D02*
X872748Y371679D01*
G01X872827Y371574D02*
X872785Y371622D01*
G01X872868Y371536D02*
X872827Y371574D01*
G01X872909Y371505D02*
X872868Y371536D01*
G01X872953Y371479D02*
X872909Y371505D01*
G01X872986Y371464D02*
X872953Y371479D01*
G01X856279Y371428D02*
X856248Y371427D01*
G01X856306Y371430D02*
X856279Y371428D01*
G01X856333Y371434D02*
X856306Y371430D01*
G01X856357Y371438D02*
X856333Y371434D01*
G01X856380Y371444D02*
X856357Y371438D01*
G01X856400Y371450D02*
X856380Y371444D01*
G01X856421Y371457D02*
X856400Y371450D01*
G01X856435Y371462D02*
X856421Y371457D01*
G01X873208Y371428D02*
X873177Y371427D01*
G01X873235Y371430D02*
X873208Y371428D01*
G01X873262Y371434D02*
X873235Y371430D01*
G01X873286Y371438D02*
X873262Y371434D01*
G01X873309Y371444D02*
X873286Y371438D01*
G01X873329Y371450D02*
X873309Y371444D01*
G01X873350Y371457D02*
X873329Y371450D01*
G01X873364Y371462D02*
X873350Y371457D01*
G01X856279Y354499D02*
X856248Y354498D01*
G01X856306Y354501D02*
X856279Y354499D01*
G01X856333Y354505D02*
X856306Y354501D01*
G01X856357Y354509D02*
X856333Y354505D01*
G01X856380Y354515D02*
X856357Y354509D01*
G01X856400Y354521D02*
X856380Y354515D01*
G01X856421Y354528D02*
X856400Y354521D01*
G01X856435Y354533D02*
X856421Y354528D01*
G01X856723Y371790D02*
X856703Y371728D01*
G01X856736Y371854D02*
X856723Y371790D01*
G01X856740Y371919D02*
X856736Y371854D01*
G01X856723Y354861D02*
X856703Y354799D01*
G01X856736Y354925D02*
X856723Y354861D01*
G01X856740Y354990D02*
X856736Y354925D01*
G01X856492Y371492D02*
X856435Y371462D01*
G01X856541Y371524D02*
X856492Y371492D01*
G01X856585Y371560D02*
X856541Y371524D01*
G01X856620Y371597D02*
X856585Y371560D01*
G01X856646Y371629D02*
X856620Y371597D01*
G01X856675Y371672D02*
X856646Y371629D01*
G01X856692Y371703D02*
X856675Y371672D01*
G01X856703Y371728D02*
X856692Y371703D01*
G01X873208Y354499D02*
X873177Y354498D01*
G01X873235Y354501D02*
X873208Y354499D01*
G01X873262Y354505D02*
X873235Y354501D01*
G01X873286Y354509D02*
X873262Y354505D01*
G01X873309Y354515D02*
X873286Y354509D01*
G01X873329Y354521D02*
X873309Y354515D01*
G01X873350Y354528D02*
X873329Y354521D01*
G01X873364Y354533D02*
X873350Y354528D01*
G01X856093Y354522D02*
X856248Y354498D01*
G01X855957Y354592D02*
X856093Y354522D01*
G01X855847Y354706D02*
X855957Y354592D01*
G01X855777Y354845D02*
X855847Y354706D01*
G01X855756Y354990D02*
X855777Y354845D01*
G01X856093Y371451D02*
X856248Y371427D01*
G01X855957Y371521D02*
X856093Y371451D01*
G01X855847Y371635D02*
X855957Y371521D01*
G01X855777Y371774D02*
X855847Y371635D01*
G01X855756Y371919D02*
X855777Y371774D01*
G01X873652Y371790D02*
X873632Y371728D01*
G01X873665Y371854D02*
X873652Y371790D01*
G01X873669Y371919D02*
X873665Y371854D01*
G01X873652Y354861D02*
X873632Y354799D01*
G01X873665Y354925D02*
X873652Y354861D01*
G01X873669Y354990D02*
X873665Y354925D01*
G01X856492Y354562D02*
X856435Y354533D01*
G01X856541Y354595D02*
X856492Y354562D01*
G01X856585Y354631D02*
X856541Y354595D01*
G01X856620Y354667D02*
X856585Y354631D01*
G01X856646Y354700D02*
X856620Y354667D01*
G01X856675Y354743D02*
X856646Y354700D01*
G01X856692Y354774D02*
X856675Y354743D01*
G01X856703Y354799D02*
X856692Y354774D01*
G01X873421Y371492D02*
X873364Y371462D01*
G01X873470Y371524D02*
X873421Y371492D01*
G01X873514Y371560D02*
X873470Y371524D01*
G01X873549Y371597D02*
X873514Y371560D01*
G01X873575Y371629D02*
X873549Y371597D01*
G01X873604Y371672D02*
X873575Y371629D01*
G01X873621Y371703D02*
X873604Y371672D01*
G01X873632Y371728D02*
X873621Y371703D01*
G01X873022Y354522D02*
X873177Y354498D01*
G01X872886Y354592D02*
X873022Y354522D01*
G01X872776Y354706D02*
X872886Y354592D01*
G01X872706Y354845D02*
X872776Y354706D01*
G01X872685Y354990D02*
X872706Y354845D01*
G01X873022Y371451D02*
X873177Y371427D01*
G01X872886Y371521D02*
X873022Y371451D01*
G01X872776Y371635D02*
X872886Y371521D01*
G01X872706Y371774D02*
X872776Y371635D01*
G01X872685Y371919D02*
X872706Y371774D01*
G01X873421Y354562D02*
X873364Y354533D01*
G01X873470Y354595D02*
X873421Y354562D01*
G01X873514Y354631D02*
X873470Y354595D01*
G01X873549Y354667D02*
X873514Y354631D01*
G01X873575Y354700D02*
X873549Y354667D01*
G01X873604Y354743D02*
X873575Y354700D01*
G01X873621Y354774D02*
X873604Y354743D01*
G01X873632Y354799D02*
X873621Y354774D01*
G01X873650Y371919D02*
G03X872705I-473J0D01*
G01X876917Y374085D02*
G03X875342Y375659I-1574J0D01*
G01X874850Y371919D02*
G03I-1673J0D01*
G01X874949D02*
G03I-1772J0D01*
G01X870619Y363455D02*
G03I-5906J0D01*
G01X871602D02*
G03I-6889J0D01*
G01X871904D02*
G03I-7191J0D01*
G01X871996D02*
G03I-7283J0D01*
G01X869378Y354610D02*
G03X873558Y358789I-4664J8846D01*
G01Y368120D02*
G03X869378Y372300I-8845J-4665D01*
G01X860047D02*
G03X855868Y368120I4667J-8844D01*
G01Y358789D02*
G03X860047Y354610I8845J4666D01*
G01X874949Y363455D02*
G03I-10236J0D01*
G01X873650Y354990D02*
G03X872705I-473J0D01*
G01X875342Y351250D02*
G03X876917Y352825I0J1575D01*
G01X874850Y354990D02*
G03I-1673J0D01*
G01X874949D02*
G03I-1772J0D01*
G01X856720Y371919D02*
G03X855776I-472J0D01*
G01X854083Y375659D02*
G03X852508Y374085I0J-1575D01*
G01X857921Y371919D02*
G03I-1673J0D01*
G01X858020D02*
G03I-1772J0D01*
G01X856720Y354990D02*
G03X855776I-472J0D01*
G01X852508Y352825D02*
G03X854083Y351250I1575J0D01*
G01X857921Y354990D02*
G03I-1673J0D01*
G01X858020D02*
G03I-1772J0D01*
G01X839150Y360333D02*
G03X840303Y363117I-2785J2784D01*
G01X883902Y372422D02*
X883935Y372489D01*
G01X883312Y372455D02*
X883295Y372405D01*
G01X883197Y372422D02*
X883213Y372472D01*
G01X884033Y372489D02*
X884017Y372422D01*
G01X883459Y372522D02*
X883476Y372589D01*
G01X884033Y372003D02*
Y371919D01*
G01Y372522D02*
Y372489D01*
G01X883935D02*
Y372522D01*
G01X883443Y371919D02*
Y372003D01*
G01X883312Y372522D02*
Y372455D01*
G01X883213Y372472D02*
Y372522D01*
G01X882803Y372623D02*
Y372371D01*
G01Y372271D02*
Y371919D01*
G01X882705D02*
Y372707D01*
G01X882429Y355974D02*
Y353218D01*
G01Y373691D02*
Y370935D01*
G01X884017Y372589D02*
X884033Y372522D01*
G01X883295Y372573D02*
X883312Y372522D01*
G01X883213D02*
X883197Y372573D01*
G01X883443Y372003D02*
X883902Y372422D01*
G01X883476Y372589D02*
X883541Y372656D01*
G01X883164Y372388D02*
X883197Y372422D01*
G01X883295Y372405D02*
X883246Y372338D01*
G01X884017Y372422D02*
X883984Y372371D01*
G01X883574Y372573D02*
X883541Y372522D01*
G01X870460Y374478D02*
X870618Y375069D01*
G01X858965Y352431D02*
X858807Y351840D01*
G01X879531Y355974D02*
Y353218D01*
G01Y373691D02*
Y370935D01*
G01X878759D02*
Y373691D01*
G01Y353218D02*
Y355974D01*
G01X878415Y370935D02*
Y373691D01*
G01Y353218D02*
Y355974D01*
G01X877601Y370935D02*
Y373691D01*
G01Y353218D02*
Y355974D01*
G01X877257Y370935D02*
Y373691D01*
G01Y353218D02*
Y355974D01*
G01X876917Y374085D02*
Y352825D01*
G01X876485Y355974D02*
Y353218D01*
G01Y373691D02*
Y370935D01*
G01X876327Y357549D02*
Y351840D01*
G01Y375069D02*
Y369360D01*
G01X875736Y369202D02*
Y357707D01*
G01X875342Y358789D02*
Y368120D01*
G01X869378Y372300D02*
Y374085D01*
G01Y352825D02*
Y354610D01*
G01X867331Y374675D02*
X867334Y374478D01*
G01X870618Y351840D02*
X870460Y352431D01*
G01X858807Y375069D02*
X858965Y374478D01*
G01X883935Y372522D02*
X883902Y372573D01*
G01X883246Y372640D02*
X883295Y372573D01*
G01X883623Y372606D02*
X883574Y372573D01*
G01X883246Y372338D02*
X883180Y372288D01*
G01X883984Y372371D02*
X883574Y372003D01*
G01X862094Y374675D02*
X862091Y374478D01*
G01X860047Y354610D02*
Y352825D01*
G01Y374085D02*
Y372300D01*
G01X854083Y368120D02*
Y358789D01*
G01X853689Y369202D02*
Y357707D01*
G01X853098Y357549D02*
Y351840D01*
G01Y375069D02*
Y369360D01*
G01X852750Y370935D02*
Y373691D01*
G01Y353218D02*
Y355974D01*
G01X852508Y352825D02*
Y374085D01*
G01X852002Y355974D02*
Y353218D01*
G01Y373691D02*
Y370935D01*
G01X851328Y355974D02*
Y353218D01*
G01Y373691D02*
Y370935D01*
G01X850881Y355974D02*
Y353218D01*
G01Y373691D02*
Y370935D01*
G01X850206Y355974D02*
Y353218D01*
G01Y373691D02*
Y370935D01*
G01X846287Y372415D02*
X846304Y372365D01*
G01X846205D02*
X846189Y372415D01*
G01X883951Y372656D02*
X884017Y372589D01*
G01X883197Y372573D02*
X883164Y372606D01*
G01X883541Y372656D02*
X883607Y372690D01*
G01X846238Y372181D02*
X846173Y372130D01*
G01X846156Y372231D02*
X846189Y372264D01*
G01X846533Y372415D02*
X846435Y372298D01*
G01Y372432D02*
X846533Y372549D01*
G01X846287Y372248D02*
X846238Y372181D01*
G01X846304Y372298D02*
X846287Y372248D01*
G01X846189Y372264D02*
X846205Y372315D01*
G01X849458Y370935D02*
Y373691D01*
G01Y353218D02*
Y355974D01*
G01X846996Y370935D02*
Y373691D01*
G01Y355974D02*
Y353218D01*
G01X846632Y372549D02*
Y371762D01*
G01X846533D02*
Y372415D01*
G01X846435Y372298D02*
Y372432D01*
G01X846304Y372365D02*
Y372298D01*
G01X846205Y372315D02*
Y372365D01*
G01X845795Y372465D02*
Y372214D01*
G01Y372113D02*
Y371762D01*
G01X845697D02*
Y372549D01*
G01X840303Y474790D02*
Y363117D01*
G01X846238Y372482D02*
X846287Y372415D01*
G01X883180Y372690D02*
X883246Y372640D01*
G01X883902Y372573D02*
X883853Y372606D01*
G01X883115Y372371D02*
X883164Y372388D01*
G01X846107Y372214D02*
X846156Y372231D01*
G01X846189Y372415D02*
X846156Y372449D01*
G01X846173Y372532D02*
X846238Y372482D01*
G01X883886Y372690D02*
X883951Y372656D01*
G01X883164Y372606D02*
X883115Y372623D01*
G01X846156Y372449D02*
X846107Y372465D01*
G01X883853Y372606D02*
X883771Y372623D01*
G01X883098Y372707D02*
X883180Y372690D01*
G01X853689Y369202D02*
X853098Y369360D01*
G01X875736Y357707D02*
X876327Y357549D01*
G01X846091Y372549D02*
X846173Y372532D01*
G01X883787Y372707D02*
X883886Y372690D01*
G01X867331Y374675D02*
X862094D01*
G01X862091Y374478D02*
X858965D01*
G01X870460D02*
X867334D01*
G01X869378Y374085D02*
X860047D01*
G01X846996Y373691D02*
X882429D01*
G01X883722Y372707D02*
X883787D01*
G01X882705D02*
X883098D01*
G01X883115Y372623D02*
X882803D01*
G01X883771D02*
X883705D01*
G01X846533Y372549D02*
X846632D01*
G01X845697D02*
X846091D01*
G01X883541Y372522D02*
X883459D01*
G01X846107Y372465D02*
X845795D01*
G01X882803Y372371D02*
X883115D01*
G01X883098Y372271D02*
X882803D01*
G01X845795Y372214D02*
X846107D01*
G01X846091Y372113D02*
X845795D01*
G01X883574Y372003D02*
X884033D01*
G01X882803Y371919D02*
X882705D01*
G01X884033D02*
X883443D01*
G01X846632Y371762D02*
X846533D01*
G01X845795D02*
X845697D01*
G01X882429Y370935D02*
X846996D01*
G01X855868Y368120D02*
X854083D01*
G01X875342D02*
X873558D01*
G01Y358789D02*
X875342D01*
G01X854083D02*
X855868D01*
G01X882429Y355974D02*
X846996D01*
G01X882429Y353218D02*
X846996D01*
G01X860047Y352825D02*
X869378D01*
G01X870460Y352431D02*
X858965D01*
G01X858807Y351840D02*
X853098D01*
G01X876327D02*
X870618D01*
G01X875342Y351250D02*
X854083D01*
G01X883607Y372690D02*
X883722Y372707D01*
G01X846173Y372130D02*
X846091Y372113D01*
G01X883705Y372623D02*
X883623Y372606D01*
G01X883180Y372288D02*
X883098Y372271D01*
G01X876327Y369360D02*
X875736Y369202D01*
G01X853098Y357549D02*
X853689Y357707D01*
G01X862041Y437807D02*
X862063Y437698D01*
G01X862015Y437860D02*
X862041Y437807D01*
G01X861989Y437851D02*
X862015Y437860D01*
G01X866078Y399824D02*
X865776Y399872D01*
G01X866352Y399685D02*
X866078Y399824D01*
G01X866571Y399467D02*
X866352Y399685D01*
G01X866711Y399193D02*
X866571Y399467D01*
G01X866760Y398889D02*
X866711Y399193D01*
G01X866712Y398584D02*
X866760Y398889D01*
G01X866572Y398310D02*
X866712Y398584D01*
G01X866354Y398092D02*
X866572Y398310D01*
G01X866079Y397951D02*
X866354Y398092D01*
G01X865776Y397903D02*
X866079Y397951D01*
G01X853501Y446827D02*
X853559Y446839D01*
G01X853465Y446814D02*
X853501Y446827D01*
G01X853453Y446802D02*
X853465Y446814D01*
G01X866532Y399517D02*
X866681Y399273D01*
G01X866319Y399708D02*
X866532Y399517D01*
G01X866059Y399830D02*
X866319Y399708D01*
G01X865776Y399872D02*
X866059Y399830D01*
G01X873699Y447115D02*
X873807Y447109D01*
G01X873629Y447123D02*
X873699Y447115D01*
G01X873611Y447132D02*
X873629Y447123D01*
G01X873646Y447141D02*
X873611Y447132D01*
G01X854638Y446806D02*
X854634Y446802D01*
G01X854650Y446810D02*
X854638Y446806D01*
G01X854669Y446814D02*
X854650Y446810D01*
G01X864126Y447135D02*
X864148Y447313D01*
G01X864061Y446972D02*
X864126Y447135D01*
G01X863958Y446839D02*
X864061Y446972D01*
G01X863825Y446753D02*
X863958Y446839D01*
G01X863676Y446722D02*
X863825Y446753D01*
G01X864582Y449063D02*
X864560Y448888D01*
G01X864646Y449228D02*
X864582Y449063D01*
G01X864750Y449362D02*
X864646Y449228D01*
G01X864884Y449449D02*
X864750Y449362D01*
G01X865032Y449478D02*
X864884Y449449D01*
G01X864115Y446723D02*
X864090Y446722D01*
G01X864140Y446726D02*
X864115Y446723D01*
G01X864164Y446730D02*
X864140Y446726D01*
G01X875965Y447458D02*
X875972Y447460D01*
G01X875958Y447457D02*
X875965Y447458D01*
G01X875951Y447455D02*
X875958Y447457D01*
G01X867167Y436643D02*
X867221Y436780D01*
G01X867048Y436520D02*
X867167Y436643D01*
G01X866874Y436423D02*
X867048Y436520D01*
G01X866662Y436362D02*
X866874Y436423D01*
G01X866435Y436341D02*
X866662Y436362D01*
G01X866578Y437294D02*
X866348Y437273D01*
G01X866788Y437356D02*
X866578Y437294D01*
G01X866960Y437451D02*
X866788Y437356D01*
G01X867079Y437574D02*
X866960Y437451D01*
G01X867134Y437712D02*
X867079Y437574D01*
G01X855211Y447092D02*
X855502Y447105D01*
G01X854973Y447074D02*
X855211Y447092D01*
G01X854810Y447054D02*
X854973Y447074D01*
G01X855814Y447132D02*
X855779Y447141D01*
G01X855796Y447123D02*
X855814Y447132D01*
G01X855726Y447115D02*
X855796Y447123D01*
G01X855618Y447109D02*
X855726Y447115D01*
G01X855960Y447033D02*
X855920Y447028D01*
G01X856020Y447038D02*
X855960Y447033D01*
G01X856093Y447041D02*
X856020Y447038D01*
G01X874453Y447074D02*
X874615Y447054D01*
G01X874215Y447092D02*
X874453Y447074D01*
G01X873923Y447105D02*
X874215Y447092D01*
G01X872444Y447144D02*
X872571Y447171D01*
G01X872449Y447115D02*
X872444Y447144D01*
G01X872592Y447087D02*
X872449Y447115D01*
G01X872858Y447063D02*
X872592Y447087D01*
G01X873216Y447045D02*
X872858Y447063D01*
G01X862346Y437574D02*
X862291Y437712D01*
G01X862465Y437452D02*
X862346Y437574D01*
G01X862637Y437356D02*
X862465Y437452D01*
G01X862847Y437295D02*
X862637Y437356D01*
G01X863077Y437273D02*
X862847Y437295D01*
G01X864472Y449449D02*
X864619Y449478D01*
G01X864338Y449362D02*
X864472Y449449D01*
G01X864234Y449228D02*
X864338Y449362D01*
G01X864169Y449063D02*
X864234Y449228D01*
G01X864148Y448888D02*
X864169Y449063D01*
G01X864322Y446800D02*
X864164Y446730D01*
G01X864451Y446935D02*
X864322Y446800D01*
G01X864533Y447115D02*
X864451Y446935D01*
G01X864560Y447313D02*
X864533Y447115D01*
G01X867411Y437860D02*
X867437Y437851D01*
G01X867385Y437807D02*
X867411Y437860D01*
G01X867362Y437698D02*
X867385Y437807D01*
G01X866751Y399021D02*
X866681Y399273D01*
G01X866751Y398756D02*
Y399021D01*
G01X866681Y398502D02*
X866751Y398756D01*
G01X866058Y397945D02*
X865776Y397903D01*
G01X866318Y398066D02*
X866058Y397945D01*
G01X866532Y398258D02*
X866318Y398066D01*
G01X866681Y398502D02*
X866532Y398258D01*
G01X873405Y447038D02*
X873332Y447041D01*
G01X873465Y447033D02*
X873405Y447038D01*
G01X873505Y447028D02*
X873465Y447033D01*
G01X875960Y446814D02*
X875972Y446802D01*
G01X875925Y446827D02*
X875960Y446814D01*
G01X875866Y446839D02*
X875925Y446827D01*
G01X856567Y447063D02*
X856209Y447045D01*
G01X856833Y447087D02*
X856567Y447063D01*
G01X856976Y447115D02*
X856833Y447087D01*
G01X856981Y447144D02*
X856976Y447115D01*
G01X856854Y447171D02*
X856981Y447144D01*
G01X853467Y447457D02*
X853474Y447455D01*
G01X853460Y447458D02*
X853467Y447457D01*
G01X853453Y447460D02*
X853460Y447458D01*
G01X867332Y438902D02*
X867275Y438630D01*
G01X867397Y439036D02*
X867332Y438902D01*
G01X867462Y439013D02*
X867397Y439036D01*
G01X874972Y447534D02*
X874876Y447486D01*
G01X875059Y447650D02*
X874972Y447534D01*
G01X875127Y447825D02*
X875059Y447650D01*
G01X875170Y448040D02*
X875127Y447825D01*
G01X875185Y448272D02*
X875170Y448040D01*
G01X854255Y448041D02*
X854240Y448272D01*
G01X854298Y447825D02*
X854255Y448041D01*
G01X854366Y447651D02*
X854298Y447825D01*
G01X854453Y447534D02*
X854366Y447651D01*
G01X854549Y447486D02*
X854453Y447534D01*
G01X862760Y436362D02*
X862990Y436341D01*
G01X862550Y436423D02*
X862760Y436362D01*
G01X862379Y436519D02*
X862550Y436423D01*
G01X862260Y436641D02*
X862379Y436519D01*
G01X862204Y436780D02*
X862260Y436641D01*
G01X862028Y439036D02*
X861963Y439013D01*
G01X862093Y438903D02*
X862028Y439036D01*
G01X862150Y438630D02*
X862093Y438903D01*
G01X874775Y446810D02*
X874756Y446814D01*
G01X874787Y446806D02*
X874775Y446810D01*
G01X874791Y446802D02*
X874787Y446806D01*
G01X872744Y438651D02*
G03X873531Y439439I0J787D01*
G01Y437273D02*
G03X874791Y438533I0J1260D01*
G01X872744Y437470D02*
G03X874713Y439439I0J1969D01*
G01X877311Y439833D02*
G03X879280Y441801I0J1969D01*
G01X873531Y436092D02*
G03X875972Y438533I0J2441D01*
G01X904870Y440691D02*
G03X907046Y437170I3937J0D01*
G01Y407850D02*
G03X904870Y404328I1762J-3522D01*
G01X907046Y407850D02*
G03X904870Y404328I1762J-3522D01*
G01Y440691D02*
G03X907046Y437170I3937J0D01*
G01X869437Y440029D02*
G03X871957Y442549I0J2520D01*
G01X870224Y432746D02*
G03X872193Y434714I0J1969D01*
G01X866760Y398888D02*
G03I-984J0D01*
G01X855894Y439439D02*
G03X856681Y438651I788J0D01*
G01X854634Y438533D02*
G03X855894Y437273I1260J0D01*
G01X854713Y439439D02*
G03X856681Y437470I1969J0D01*
G01X850146Y441801D02*
G03X852114Y439833I1968J0D01*
G01X857232Y434714D02*
G03X859201Y432746I1968J0D01*
G01X853453Y438533D02*
G03X855894Y436092I2441J0D01*
G01X856760Y398888D02*
G03I-984J0D01*
G01X866681D02*
G03I-5905J0D01*
G01X868650D02*
G03I-7874J0D01*
G01X904870Y440691D02*
Y576053D01*
G01Y441089D02*
Y403924D01*
G01X868596Y437273D02*
X867462Y439013D01*
G01X867437Y437851D02*
X868583Y436092D01*
G01X865500Y448612D02*
X864713Y449714D01*
G01X871439Y441019D02*
X870461Y441998D01*
G01X862291Y437712D02*
X862150Y438630D01*
G01X862063Y437698D02*
X862204Y436780D01*
G01X864840Y398582D02*
X864791Y398889D01*
G01X874348Y399302D02*
X874373Y399202D01*
G01X870559Y399277D02*
X870584Y399202D01*
G01X870436D02*
X870411Y399277D01*
G01X875013Y399001D02*
X875456Y398297D01*
G01X875259D02*
X874890Y398875D01*
G01X874225Y399202D02*
X874176Y399277D01*
G01X874373Y399152D02*
X874348Y399051D01*
G01X873512Y399202D02*
X873536Y399302D01*
G01X879280Y481959D02*
Y441801D01*
G01X877468Y437273D02*
Y436092D01*
G01X877430D02*
Y437273D01*
G01X877402D02*
Y436092D01*
G01X876760Y483927D02*
Y439833D01*
G01X876069Y436092D02*
Y437273D01*
G01X875972Y438533D02*
Y485226D01*
G01Y437273D02*
Y436092D01*
G01X875894Y437470D02*
Y441801D01*
G01X875866Y446839D02*
Y453298D01*
G01X875849Y448100D02*
Y452037D01*
G01X875670Y436092D02*
Y437273D01*
G01X875185Y448261D02*
Y451865D01*
G01Y436092D02*
Y437273D01*
G01X874791Y438533D02*
Y485226D01*
G01X874756Y446814D02*
Y453323D01*
G01X874717Y399478D02*
Y398900D01*
G01Y398699D02*
Y398297D01*
G01X874713Y439439D02*
Y484321D01*
G01X874615Y453084D02*
Y447054D01*
G01X874570Y398297D02*
Y399478D01*
G01X874373Y398423D02*
Y398297D01*
G01Y399202D02*
Y399152D01*
G01X874225D02*
Y399202D01*
G01X874162Y437273D02*
Y436092D01*
G01X873954Y452037D02*
Y448100D01*
G01X873923Y447105D02*
Y453032D01*
G01X873807Y447109D02*
Y453028D01*
G01X873768Y437273D02*
Y436092D01*
G01X873646Y452997D02*
Y447141D01*
G01X873610Y436092D02*
Y437276D01*
G01Y453007D02*
Y447131D01*
G01X873531Y484321D02*
Y439439D01*
G01X873505Y453109D02*
Y447028D01*
G01X873487Y398297D02*
Y398423D01*
G01X873332Y447041D02*
Y453096D01*
G01X873216Y447045D02*
Y453092D01*
G01X872980Y436092D02*
Y437273D01*
G01X872823D02*
Y436092D01*
G01Y452037D02*
Y448100D01*
G01X872744Y437470D02*
Y438651D01*
G01X872587Y441998D02*
Y441801D01*
G01Y452431D02*
Y447707D01*
G01X872571Y452966D02*
Y447171D01*
G01X872429Y453007D02*
Y447131D01*
G01X872193Y437273D02*
Y434714D01*
G01X872109Y399478D02*
Y398297D01*
G01X871962Y398473D02*
Y399478D01*
G01X871957Y481210D02*
Y442549D01*
G01X871824Y447313D02*
Y444951D01*
G01X871405Y437273D02*
Y436092D01*
G01X871273Y399327D02*
Y398297D01*
G01X871209Y447903D02*
Y444360D01*
G01X871125Y398297D02*
Y399478D01*
G01X871012Y447707D02*
Y444557D01*
G01X871011Y436092D02*
Y437273D01*
G01X870928Y399478D02*
Y398297D01*
G01X870780D02*
Y399478D01*
G01X870748Y444557D02*
Y447707D01*
G01X870708Y444557D02*
Y447707D01*
G01X870618Y437273D02*
Y436092D01*
G01X870611Y437273D02*
Y436092D01*
G01X870584Y399202D02*
Y399101D01*
G01X870579Y443081D02*
Y449183D01*
G01X870480D02*
Y443081D01*
G01X870461Y481762D02*
Y441998D01*
G01X870436Y399126D02*
Y399202D01*
G01X870373Y443671D02*
Y448592D01*
G01X870224Y447707D02*
Y444557D01*
G01X870066D02*
Y447707D01*
G01X870028Y447903D02*
Y444360D01*
G01X869957Y444557D02*
Y447707D01*
G01X869821Y399353D02*
Y398976D01*
G01Y398825D02*
Y398297D01*
G01X869693Y443081D02*
Y449183D01*
G01X869673Y398297D02*
Y399478D01*
G01X869639Y443671D02*
Y448592D01*
G01X869594Y443651D02*
Y443081D01*
G01Y449183D02*
Y448612D01*
G01X869504Y437273D02*
Y436092D01*
G01X869201Y437273D02*
Y436092D01*
G01X869104Y437273D02*
Y436092D01*
G01X869043Y444951D02*
Y443651D01*
G01Y448612D02*
Y447313D01*
G01X868846Y444360D02*
Y447903D01*
G01X868732Y436092D02*
Y437273D01*
G01X868657Y436092D02*
Y437273D01*
G01X868413Y436092D02*
Y437273D01*
G01X867951D02*
Y436092D01*
G01X867941Y450856D02*
Y449281D01*
G01X867771Y436092D02*
Y437273D01*
G01X867744Y450659D02*
Y449478D01*
G01X867743Y437273D02*
Y436092D01*
G01X867705Y437273D02*
Y436092D01*
G01X867640Y443671D02*
Y448592D01*
G01X867587D02*
Y443671D01*
G01X867173Y450266D02*
Y445935D01*
G01X867111Y450659D02*
Y449478D01*
G01X866907Y443671D02*
Y448592D01*
G01X866799D02*
Y443671D01*
G01X866760Y450659D02*
Y449478D01*
G01X866747Y444951D02*
Y447313D01*
G01X866681Y404096D02*
Y393679D01*
G01Y448612D02*
Y443651D01*
G01X866602Y448592D02*
Y443671D01*
G01X866563Y448612D02*
Y443651D01*
G01X866479Y450659D02*
Y449478D01*
G01X866405Y443671D02*
Y448592D01*
G01X866209Y441998D02*
Y481762D01*
G01X865992Y450266D02*
Y445935D01*
G01X865894Y450955D02*
Y449183D01*
G01X865815Y448612D02*
Y443651D01*
G01X865776Y449281D02*
Y445108D01*
G01X865697D02*
Y451092D01*
G01X865654Y446722D02*
Y450659D01*
G01X865500Y448612D02*
Y443651D01*
G01X867134Y437712D02*
X867221Y436780D01*
G01X866348Y437273D02*
X866435Y436341D01*
G01X856711Y399193D02*
X856760Y398886D01*
G01X854840Y398582D02*
X854791Y398889D01*
G01X850006Y422333D02*
X849939Y422661D01*
G01X850542Y413737D02*
X850475Y414065D01*
G01X848531Y413343D02*
X848598Y413015D01*
G01X850140Y413999D02*
X850207Y413737D01*
G01X848934Y413081D02*
X848867Y413343D01*
G01X851834Y399378D02*
X852055Y398699D01*
G01X852178Y398297D02*
X852080Y398599D01*
G01X851932Y399478D02*
X852326Y398297D01*
G01X850341Y422595D02*
X850408Y422398D01*
G01X864980Y398308D02*
X864839Y398584D01*
G01X856571Y399467D02*
X856712Y399191D01*
G01X854980Y398308D02*
X854839Y398584D01*
G01X871888Y398297D02*
X871273Y399327D01*
G01X871346Y399478D02*
X871962Y398473D01*
G01X850475Y414065D02*
X850274Y414393D01*
G01X848598Y413015D02*
X848800Y412687D01*
G01X849068Y412884D02*
X848934Y413081D01*
G01X870485Y399378D02*
X870559Y399277D01*
G01X850207Y422070D02*
X850006Y422333D01*
G01X849939Y414262D02*
X850140Y413999D01*
G01X874250Y399403D02*
X874348Y399302D01*
G01X870411Y399277D02*
X870362Y399327D01*
G01X850408Y422398D02*
X850542Y422267D01*
G01X850475Y421873D02*
X850207Y422070D01*
G01X874615Y447054D02*
X875866Y446839D01*
G01X874756Y446814D02*
X873505Y447028D01*
G01X854549Y447486D02*
X856854Y447171D01*
G01X855779Y447141D02*
X853474Y447455D01*
G01X874348Y399051D02*
X874299Y398976D01*
G01X873684Y399277D02*
X873635Y399202D01*
G01X864839Y399191D02*
X864980Y399467D01*
G01X874176Y399051D02*
X874225Y399152D01*
G01X870584Y399101D02*
X870559Y399026D01*
G01X870411Y399051D02*
X870436Y399126D01*
G01X864791Y398886D02*
X864840Y399193D01*
G01X856760Y398889D02*
X856711Y398582D01*
G01X854791Y398886D02*
X854840Y399193D01*
G01X867221Y436780D02*
X867362Y437698D01*
G01X867275Y438630D02*
X867134Y437712D01*
G01X862990Y436341D02*
X863077Y437273D01*
G01X862204Y436780D02*
X862291Y437712D01*
G01X864713Y440029D02*
Y483730D01*
G01X864685Y446722D02*
Y450659D01*
G01X864560Y448888D02*
Y447313D01*
G01X864319Y441998D02*
Y441210D01*
G01X864164Y450659D02*
Y446730D01*
G01X864148Y447313D02*
Y448888D01*
G01X863559Y446722D02*
Y450659D01*
G01X863531D02*
Y446132D01*
G01X862590Y446722D02*
Y450659D01*
G01X862547D02*
Y446722D01*
G01X862449Y450069D02*
Y446132D01*
G01X862252Y450266D02*
Y445935D01*
G01X861720Y437273D02*
Y436092D01*
G01X861682D02*
Y437273D01*
G01X861654D02*
Y436092D01*
G01X861474D02*
Y437273D01*
G01X861465Y450266D02*
Y445935D01*
G01X861268Y446132D02*
Y450069D01*
G01X861169Y441210D02*
Y441998D01*
G01X861012Y437273D02*
Y436092D01*
G01X860776Y443376D02*
Y440620D01*
G01X860769Y437273D02*
Y436092D01*
G01X860693Y437273D02*
Y436092D01*
G01X860321D02*
Y437273D01*
G01X860283Y450069D02*
Y446132D01*
G01X860224Y437273D02*
Y436092D01*
G01X860185Y450856D02*
Y445738D01*
G01X860087Y450266D02*
Y445935D01*
G01X859921Y436092D02*
Y437273D01*
G01X858905Y450266D02*
Y445935D01*
G01X858814Y436092D02*
Y437273D01*
G01X858807D02*
Y436092D01*
G01X858414Y437273D02*
Y436092D01*
G01X858020Y437273D02*
Y436092D01*
G01X857232Y437273D02*
Y434714D01*
G01X856996Y453007D02*
Y447131D01*
G01X856854Y447171D02*
Y452966D01*
G01X856839Y447707D02*
Y452431D01*
G01Y441801D02*
Y441998D01*
G01X856681Y438651D02*
Y437470D01*
G01X856602Y448100D02*
Y452037D01*
G01Y436092D02*
Y437273D01*
G01X856445Y428514D02*
Y408632D01*
G01Y437273D02*
Y436092D01*
G01X856209Y453092D02*
Y447045D01*
G01X856093Y453096D02*
Y447041D01*
G01X855920Y447028D02*
Y453109D01*
G01X855894Y439439D02*
Y484321D01*
G01X855815Y436092D02*
Y437276D01*
G01Y453007D02*
Y447131D01*
G01X855779Y447141D02*
Y452997D01*
G01X855657Y437273D02*
Y436092D01*
G01X855618Y453028D02*
Y447109D01*
G01X855502Y453032D02*
Y447105D01*
G01X855471Y448100D02*
Y452037D01*
G01X855263Y436092D02*
Y437273D01*
G01X854810Y447054D02*
Y453084D01*
G01X854713Y484321D02*
Y439439D01*
G01X854669Y453323D02*
Y446814D01*
G01X854634Y485226D02*
Y438533D01*
G01X854240Y437273D02*
Y436092D01*
G01Y451865D02*
Y448272D01*
G01X853756Y437273D02*
Y436092D01*
G01X853576Y452037D02*
Y448100D01*
G01X853559Y453298D02*
Y446839D01*
G01X853531Y437470D02*
Y441801D01*
G01X853453Y437273D02*
Y436092D01*
G01Y485226D02*
Y438533D01*
G01X853356Y437273D02*
Y436092D01*
G01X852665Y439833D02*
Y461860D01*
G01X852023Y436092D02*
Y437273D01*
G01X851995D02*
Y436092D01*
G01X851957Y437273D02*
Y436092D01*
G01X851681Y412490D02*
Y414721D01*
G01Y417608D02*
Y415246D01*
G01Y418724D02*
Y418133D01*
G01Y421283D02*
Y420692D01*
G01Y424235D02*
Y422661D01*
G01Y427254D02*
Y424760D01*
G01X851346Y426204D02*
Y427254D01*
G01Y424760D02*
Y425810D01*
G01Y422595D02*
Y423842D01*
G01Y415640D02*
Y417608D01*
G01Y414393D02*
Y412490D01*
G01X851145Y399478D02*
Y398297D01*
G01X850997D02*
Y399277D01*
G01X850849Y399101D02*
Y399302D01*
G01X850542Y413343D02*
Y413737D01*
G01X850341Y423842D02*
Y422595D01*
G01X850207Y413737D02*
Y413343D01*
G01X850146Y461860D02*
Y441801D01*
G01X849939Y422661D02*
Y423842D01*
G01Y414721D02*
Y414262D01*
G01X847921Y399277D02*
X847946Y399202D01*
G01X847798D02*
X847774Y399277D01*
G01X849250Y398297D02*
X848635Y399327D01*
G01X848709Y399478D02*
X849324Y398473D01*
G01X847847Y399378D02*
X847921Y399277D01*
G01X847774D02*
X847724Y399327D01*
G01X865199Y398090D02*
X864979Y398310D01*
G01X856352Y399685D02*
X856572Y399465D01*
G01X855199Y398090D02*
X854979Y398310D01*
G01X870387Y399453D02*
X870485Y399378D01*
G01X848800Y412687D02*
X849068Y412490D01*
G01X874176Y399277D02*
X874102Y399327D01*
G01X849269Y412752D02*
X849068Y412884D01*
G01X874152Y399453D02*
X874250Y399403D01*
G01X848531Y416952D02*
X851346Y415640D01*
G01Y415246D02*
X848531Y416558D01*
G01X851011Y418527D02*
X848531Y419445D01*
G01X848867Y419708D02*
X851681Y418724D01*
G01X850542Y422267D02*
X850743Y422201D01*
G01X850676Y421808D02*
X850475Y421873D01*
G01X873807Y447109D02*
X873923Y447105D01*
G01X873332Y447041D02*
X873216Y447045D01*
G01X874876Y447486D02*
X875951Y447455D01*
G01X865697Y450730D02*
X864713D01*
G01X862547Y450659D02*
X867744D01*
G01X865697Y450561D02*
X864713D01*
G01X858905Y450266D02*
X867173D01*
G01X865697Y450069D02*
X860283D01*
G01X867744Y449478D02*
X864619D01*
G01X867941Y449281D02*
X865776D01*
G01X871957Y449183D02*
X865776D01*
G01X869693Y449163D02*
X870480D01*
G01X869693Y449085D02*
X870480D01*
G01Y449010D02*
X869693D01*
G01Y448986D02*
X870480D01*
G01Y448950D02*
X869693D01*
G01X864148Y448888D02*
X864560D01*
G01X861268D02*
X860283D01*
G01X870480Y448862D02*
X869693D01*
G01X870480Y448838D02*
X869693D01*
G01Y448809D02*
X870480D01*
G01X869693Y448691D02*
X870480D01*
G01X861268D02*
X860283D01*
G01X870579Y448612D02*
X865500D01*
G01X865815Y448592D02*
X870480D01*
G01X875185Y448261D02*
X875972D01*
G01X856602Y448100D02*
X853453D01*
G01X875972D02*
X872823D01*
G01X868846Y447903D02*
X871209D01*
G01X856839Y447707D02*
X854713D01*
G01X871012D02*
X869693D01*
G01X874713D02*
X872587D01*
G01X861268Y447510D02*
X860283D01*
G01X864148Y447313D02*
X864560D01*
G01X861268D02*
X860283D01*
G01X871957D02*
X866747D01*
G01X871012Y446919D02*
X870224D01*
G01Y446722D02*
X871012D01*
G01X865697D02*
X862547D01*
G01X854634Y446565D02*
X853453D01*
G01X875972D02*
X874791D01*
G01X864713Y446549D02*
X865697D01*
G01X874791Y446537D02*
X875972D01*
G01X853453D02*
X854634D01*
G01X874791Y446525D02*
X875972D01*
G01X854634D02*
X853453D01*
G01X860283Y446132D02*
X865697D01*
G01X858905Y445935D02*
X867173D01*
G01X854634Y445751D02*
X853453D01*
G01X875972D02*
X874791D01*
G01X865776Y445738D02*
X860185D01*
G01X865697Y445640D02*
X864713D01*
G01X870224Y445541D02*
X871012D01*
G01X865697D02*
X864713D01*
G01Y445470D02*
X865697D01*
G01Y445423D02*
X864713D01*
G01Y445374D02*
X865697D01*
G01X871012Y445344D02*
X870224D01*
G01X864713Y445281D02*
X865697D01*
G01X865776Y445108D02*
X864713D01*
G01X871957Y444951D02*
X866747D01*
G01X874791Y444754D02*
X875972D01*
G01X854634D02*
X853453D01*
G01X869693Y444557D02*
X871012D01*
G01X868846Y444360D02*
X871209D01*
G01X854634Y443966D02*
X853453D01*
G01X875972D02*
X874791D01*
G01X870480Y443671D02*
X865815D01*
G01X870579Y443651D02*
X865500D01*
G01X869693Y443573D02*
X870480D01*
G01Y443455D02*
X869693D01*
G01Y443425D02*
X870480D01*
G01X869693Y443401D02*
X870480D01*
G01X864713Y443376D02*
X860776D01*
G01X869693Y443313D02*
X870480D01*
G01Y443277D02*
X869693D01*
G01Y443254D02*
X870480D01*
G01Y443179D02*
X869693D01*
G01X870480Y443100D02*
X869693D01*
G01X870579Y443081D02*
X869594D01*
G01X854634Y441998D02*
X853453D01*
G01X872587D02*
X856839D01*
G01X875972D02*
X874791D01*
G01X875894Y441801D02*
X853531D01*
G01X854634Y441210D02*
X853453D01*
G01X864319D02*
X861169D01*
G01X875972D02*
X874791D01*
G01X854713Y440620D02*
X853531D01*
G01X864713D02*
X860776D01*
G01X875894D02*
X874713D01*
G01X869437Y440029D02*
X864713D01*
G01X874791Y439833D02*
X877311D01*
G01X854634D02*
X852114D01*
G01X854713Y439439D02*
X855894D01*
G01X873531D02*
X874713D01*
G01X874791Y439045D02*
X875972D01*
G01X853453D02*
X854634D01*
G01X867420D02*
X862006D01*
G01X867462Y439013D02*
X861963D01*
G01X872744Y438651D02*
X856681D01*
G01X862150Y438630D02*
X867275D01*
G01X867420Y437864D02*
X862006D01*
G01X867437Y437851D02*
X861989D01*
G01X862063Y437698D02*
X867362D01*
G01X875894Y437470D02*
X853531D01*
G01X853453Y448250D02*
X854240Y448272D01*
G01X853474Y447455D02*
X854549Y447486D01*
G01X855502Y447105D02*
X855618Y447109D01*
G01X856209Y447045D02*
X856093Y447041D01*
G01X874299Y398976D02*
X873684Y398423D01*
G01X873487D02*
X874176Y399051D01*
G01X864979Y399465D02*
X865199Y399685D01*
G01X874890Y398875D02*
X874717Y398699D01*
G01X873536Y399302D02*
X873635Y399403D01*
G01X870362Y399001D02*
X870411Y399051D01*
G01X874717Y398900D02*
X875259Y399478D01*
G01X875456D02*
X875013Y399001D01*
G01X870559Y399026D02*
X870485Y398925D01*
G01X856712Y398584D02*
X856571Y398308D01*
G01X854839Y399191D02*
X854980Y399467D01*
G01X851279Y422398D02*
X851346Y422595D01*
G01X851342Y398297D02*
X851735Y399478D01*
G01X851588Y398599D02*
X851489Y398297D01*
G01X851612Y398699D02*
X851834Y399378D01*
G01X847946Y399101D02*
X847921Y399026D01*
G01X847774Y399051D02*
X847798Y399126D01*
G01X850207Y413343D02*
X850140Y413081D01*
G01X848867Y413737D02*
X848934Y413999D01*
G01X850475Y413015D02*
X850542Y413343D01*
G01X851681Y422661D02*
X851614Y422333D01*
G01X848598Y414065D02*
X848531Y413737D01*
G01X849471Y399478D02*
Y398297D01*
G01X849336Y414327D02*
Y414721D01*
G01X849324Y398473D02*
Y399478D01*
G01X848867Y413343D02*
Y413737D01*
G01X848635Y399327D02*
Y398297D01*
G01X848531Y425810D02*
Y426204D01*
G01Y423842D02*
Y424235D01*
G01Y420889D02*
Y421283D01*
G01Y419445D02*
Y419970D01*
G01Y418133D02*
Y418527D01*
G01Y416558D02*
Y416952D01*
G01Y413737D02*
Y413343D01*
G01X848487Y398297D02*
Y399478D01*
G01X848290D02*
Y398297D01*
G01X848143D02*
Y399478D01*
G01X847946Y399202D02*
Y399101D01*
G01X847798Y399126D02*
Y399202D01*
G01X847183Y399353D02*
Y398976D01*
G01Y398825D02*
Y398297D01*
G01X847035D02*
Y399478D01*
G01X844240Y408632D02*
Y428514D01*
G01X847749Y399453D02*
X847847Y399378D01*
G01X865474Y397951D02*
X865197Y398092D01*
G01X856078Y399824D02*
X856354Y399683D01*
G01X855474Y397951D02*
X855197Y398092D01*
G01X849068Y412490D02*
X849403Y412359D01*
G01X870362Y399327D02*
X870288Y399353D01*
G01X849470Y412687D02*
X849269Y412752D01*
G01X851958Y437273D02*
X877468D01*
G01X866435Y436341D02*
X862990D01*
G01X851958Y436092D02*
X877468D01*
G01X872193Y435305D02*
X857232D01*
G01X870224Y432746D02*
X859201D01*
G01X844240Y428514D02*
X856445D01*
G01X851346Y427254D02*
X851681D01*
G01X848531Y426204D02*
X851346D01*
G01Y425810D02*
X848531D01*
G01X851681Y424760D02*
X851346D01*
G01X848531Y424235D02*
X851681D01*
G01X849939Y423842D02*
X848531D01*
G01X851346D02*
X850341D01*
G01X850743Y422201D02*
X850944D01*
G01X872571Y447171D02*
X874876Y447486D01*
G01X875951Y447455D02*
X873646Y447141D01*
G01X853559Y446839D02*
X854810Y447054D01*
G01X855920Y447028D02*
X854669Y446814D01*
G01X873758Y399327D02*
X873684Y399277D01*
G01X870485Y398925D02*
X870387Y398850D01*
G01X856572Y398310D02*
X856352Y398090D01*
G01X854979Y399465D02*
X855199Y399685D01*
G01X847724Y399001D02*
X847774Y399051D01*
G01X850997Y399277D02*
X850849Y399101D01*
G01Y399302D02*
X850997Y399478D01*
G01X847921Y399026D02*
X847847Y398925D01*
G01X864713Y442549D02*
X865500Y443651D01*
G01X850140Y413081D02*
X850006Y412884D01*
G01X848934Y413999D02*
X849068Y414196D01*
G01X860842Y436092D02*
X861989Y437851D01*
G01X861963Y439013D02*
X860830Y437273D01*
G01X850274Y412687D02*
X850475Y413015D01*
G01X848800Y414393D02*
X848598Y414065D01*
G01X847724Y399327D02*
X847651Y399353D01*
G01X874102Y399327D02*
X873979Y399353D01*
G01X870264Y399478D02*
X870387Y399453D01*
G01X847626Y399478D02*
X847749Y399453D01*
G01X874004Y399478D02*
X874152Y399453D01*
G01X855776Y399872D02*
X856079Y399824D01*
G01X865776Y397903D02*
X865472Y397951D01*
G01X855776Y397903D02*
X855472Y397951D01*
G01X850944Y421808D02*
X850676D01*
G01X848531Y421283D02*
X851681D01*
G01X851011Y420889D02*
X848531D01*
G01Y418527D02*
X851011D01*
G01X851681Y418133D02*
X848531D01*
G01X851346Y417608D02*
X851681D01*
G01Y415246D02*
X851346D01*
G01X851681Y414721D02*
X849939D01*
G01X850274Y414393D02*
X851346D01*
G01X849604Y412687D02*
X849470D01*
G01X851346Y412490D02*
X851681D01*
G01X849403Y412359D02*
X849671D01*
G01X856445Y408632D02*
X844240D01*
G01X870288Y398976D02*
X870362Y399001D01*
G01X865197Y399683D02*
X865474Y399824D01*
G01X856354Y398092D02*
X856078Y397951D01*
G01X855197Y399683D02*
X855474Y399824D01*
G01X873635Y399403D02*
X873733Y399453D01*
G01X850006Y412490D02*
X850274Y412687D01*
G01X847847Y398925D02*
X847749Y398850D01*
G01X851145Y422267D02*
X851279Y422398D01*
G01X866209Y441998D02*
X864713Y440502D01*
G01X851614Y422333D02*
X851413Y422070D01*
G01X864713Y450423D02*
X865500Y451525D01*
G01X875259Y399478D02*
X875456D01*
G01X874570D02*
X874717D01*
G01X873905D02*
X874004D01*
G01X871962D02*
X872109D01*
G01X871125D02*
X871346D01*
G01X870780D02*
X870928D01*
G01X869673D02*
X870264D01*
G01X851735D02*
X851932D01*
G01X850997D02*
X851145D01*
G01X848487D02*
X848709D01*
G01X849324D02*
X849471D01*
G01X848143D02*
X848290D01*
G01X847035D02*
X847626D01*
G01X847651Y399353D02*
X847183D01*
G01X870288D02*
X869821D01*
G01X873979D02*
X873881D01*
G01X873635Y399202D02*
X873512D01*
G01X869821Y398976D02*
X870288D01*
G01X847183D02*
X847651D01*
G01X847626Y398825D02*
X847183D01*
G01X870264D02*
X869821D01*
G01X852055Y398699D02*
X851612D01*
G01X852080Y398599D02*
X851588D01*
G01X873684Y398423D02*
X874373D01*
G01X848290Y398297D02*
X848143D01*
G01X847183D02*
X847035D01*
G01X848635D02*
X848487D01*
G01X849471D02*
X849250D01*
G01X851489D02*
X851342D01*
G01X851145D02*
X850997D01*
G01X852326D02*
X852178D01*
G01X869821D02*
X869673D01*
G01X871273D02*
X871125D01*
G01X870928D02*
X870780D01*
G01X872109D02*
X871888D01*
G01X874717D02*
X874570D01*
G01X874373D02*
X873487D01*
G01X875456D02*
X875259D01*
G01X847651Y398976D02*
X847724Y399001D01*
G01X849068Y414196D02*
X849336Y414327D01*
G01Y414721D02*
X849068Y414590D01*
G01X850006Y412884D02*
X849805Y412752D01*
G01X849068Y414590D02*
X848800Y414393D01*
G01X851413Y422070D02*
X851145Y421873D01*
G01X873733Y399453D02*
X873905Y399478D01*
G01X855776Y399872D02*
X855472Y399824D01*
G01X865776Y399872D02*
X865472Y399824D01*
G01X855776Y397903D02*
X856079Y397951D01*
G01X847749Y398850D02*
X847626Y398825D01*
G01X870387Y398850D02*
X870264Y398825D01*
G01X873881Y399353D02*
X873758Y399327D01*
G01X849805Y412752D02*
X849604Y412687D01*
G01X851145Y421873D02*
X850944Y421808D01*
G01Y422201D02*
X851145Y422267D01*
G01X851681Y420692D02*
X848867Y419708D01*
G01X848531Y419970D02*
X851011Y420889D01*
G01X849671Y412359D02*
X850006Y412490D01*
G01X854083Y375659D02*
X875342D01*
G01X858807Y375069D02*
X853098D01*
G01X876327D02*
X870618D01*
G01X867384Y485953D02*
X867362Y486061D01*
G01X867410Y485899D02*
X867384Y485953D01*
G01X867437Y485908D02*
X867410Y485899D01*
G01X854255Y475719D02*
X854240Y475487D01*
G01X854298Y475934D02*
X854255Y475719D01*
G01X854366Y476109D02*
X854298Y475934D01*
G01X854453Y476225D02*
X854366Y476109D01*
G01X854549Y476274D02*
X854453Y476225D01*
G01X875170Y471660D02*
X875185Y471894D01*
G01X875127Y471446D02*
X875170Y471660D01*
G01X875059Y471273D02*
X875127Y471446D01*
G01X874973Y471157D02*
X875059Y471273D01*
G01X874876Y471108D02*
X874973Y471157D01*
G01X872446Y464509D02*
X872519Y464488D01*
G01X872431Y464530D02*
X872446Y464509D01*
G01X872476Y464551D02*
X872431Y464530D01*
G01X853501Y470449D02*
X853559Y470461D01*
G01X853465Y470436D02*
X853501Y470449D01*
G01X853453Y470424D02*
X853465Y470436D01*
G01X874755Y459983D02*
X874765Y460214D01*
G01X874723Y459768D02*
X874755Y459983D01*
G01X874674Y459593D02*
X874723Y459768D01*
G01X874612Y459476D02*
X874674Y459593D01*
G01X874543Y459428D02*
X874612Y459476D01*
G01X875925Y476933D02*
X875866Y476920D01*
G01X875960Y476945D02*
X875925Y476933D01*
G01X875972Y476958D02*
X875960Y476945D01*
G01X875925Y453310D02*
X875866Y453298D01*
G01X875960Y453323D02*
X875925Y453310D01*
G01X875972Y453336D02*
X875960Y453323D01*
G01X862847Y486465D02*
X863077Y486486D01*
G01X862637Y486404D02*
X862847Y486465D01*
G01X862465Y486308D02*
X862637Y486404D01*
G01X862346Y486186D02*
X862465Y486308D01*
G01X862291Y486048D02*
X862346Y486186D01*
G01X874770Y465194D02*
X874744Y465185D01*
G01X874786Y465203D02*
X874770Y465194D01*
G01X874791Y465212D02*
X874786Y465203D01*
G01X875939Y465183D02*
X875897Y465169D01*
G01X875964Y465198D02*
X875939Y465183D01*
G01X875972Y465212D02*
X875964Y465198D01*
G01X872431Y459229D02*
X872476Y459208D01*
G01X872446Y459251D02*
X872431Y459229D01*
G01X872519Y459272D02*
X872446Y459251D01*
G01X855728Y453022D02*
X855618Y453028D01*
G01X855796Y453015D02*
X855728Y453022D01*
G01X855814Y453006D02*
X855796Y453015D01*
G01X855779Y452997D02*
X855814Y453006D01*
G01X874787Y453332D02*
X874791Y453336D01*
G01X874775Y453327D02*
X874787Y453332D01*
G01X874756Y453323D02*
X874775Y453327D01*
G01X862015Y485899D02*
X861989Y485908D01*
G01X862041Y485952D02*
X862015Y485899D01*
G01X862063Y486061D02*
X862041Y485952D01*
G01X875958Y471079D02*
X875951Y471078D01*
G01X875965Y471080D02*
X875958Y471079D01*
G01X875972Y471082D02*
X875965Y471080D01*
G01X873699Y470737D02*
X873807Y470731D01*
G01X873629Y470745D02*
X873699Y470737D01*
G01X873611Y470754D02*
X873629Y470745D01*
G01X873646Y470763D02*
X873611Y470754D01*
G01X864126Y456387D02*
X864148Y456565D01*
G01X864061Y456224D02*
X864126Y456387D01*
G01X863958Y456091D02*
X864061Y456224D01*
G01X863825Y456005D02*
X863958Y456091D01*
G01X863676Y455974D02*
X863825Y456005D01*
G01X864126Y464261D02*
X864148Y464439D01*
G01X864061Y464098D02*
X864126Y464261D01*
G01X863958Y463965D02*
X864061Y464098D01*
G01X863825Y463879D02*
X863958Y463965D01*
G01X863676Y463848D02*
X863825Y463879D01*
G01X864582Y456937D02*
X864560Y456762D01*
G01X864646Y457102D02*
X864582Y456937D01*
G01X864750Y457236D02*
X864646Y457102D01*
G01X864884Y457323D02*
X864750Y457236D01*
G01X865032Y457352D02*
X864884Y457323D01*
G01X864582Y464811D02*
X864560Y464636D01*
G01X864646Y464976D02*
X864582Y464811D01*
G01X864750Y465110D02*
X864646Y464976D01*
G01X864884Y465197D02*
X864750Y465110D01*
G01X865032Y465226D02*
X864884Y465197D01*
G01X864115Y455975D02*
X864090Y455974D01*
G01X864140Y455978D02*
X864115Y455975D01*
G01X864164Y455982D02*
X864140Y455978D01*
G01X864115Y463849D02*
X864090Y463848D01*
G01X864140Y463852D02*
X864115Y463849D01*
G01X864164Y463856D02*
X864140Y463852D01*
G01X853460Y452679D02*
X853453Y452677D01*
G01X853467Y452681D02*
X853460Y452679D01*
G01X853474Y452682D02*
X853467Y452681D01*
G01X874214Y453046D02*
X873923Y453032D01*
G01X874452Y453064D02*
X874214Y453046D01*
G01X874615Y453084D02*
X874452Y453064D01*
G01X873611Y453005D02*
X873646Y452997D01*
G01X873629Y453014D02*
X873611Y453005D01*
G01X873699Y453023D02*
X873629Y453014D01*
G01X873807Y453028D02*
X873699Y453023D01*
G01X873465Y453104D02*
X873505Y453109D01*
G01X873405Y453100D02*
X873465Y453104D01*
G01X873332Y453096D02*
X873405Y453100D01*
G01X854453Y471156D02*
X854549Y471108D01*
G01X854367Y471272D02*
X854453Y471156D01*
G01X854298Y471447D02*
X854367Y471272D01*
G01X854255Y471662D02*
X854298Y471447D01*
G01X854240Y471894D02*
X854255Y471662D01*
G01X854453Y452604D02*
X854549Y452651D01*
G01X854367Y452487D02*
X854453Y452604D01*
G01X854298Y452313D02*
X854367Y452487D01*
G01X854255Y452097D02*
X854298Y452313D01*
G01X854240Y451865D02*
X854255Y452097D01*
G01X864472Y465197D02*
X864619Y465226D01*
G01X864338Y465110D02*
X864472Y465197D01*
G01X864234Y464976D02*
X864338Y465110D01*
G01X864169Y464811D02*
X864234Y464976D01*
G01X864148Y464636D02*
X864169Y464811D01*
G01X864472Y457323D02*
X864619Y457352D01*
G01X864338Y457236D02*
X864472Y457323D01*
G01X864234Y457102D02*
X864338Y457236D01*
G01X864169Y456937D02*
X864234Y457102D01*
G01X864148Y456762D02*
X864169Y456937D01*
G01X864322Y463926D02*
X864164Y463856D01*
G01X864451Y464061D02*
X864322Y463926D01*
G01X864533Y464241D02*
X864451Y464061D01*
G01X864560Y464439D02*
X864533Y464241D01*
G01X864322Y456052D02*
X864164Y455982D01*
G01X864451Y456187D02*
X864322Y456052D01*
G01X864533Y456367D02*
X864451Y456187D01*
G01X864560Y456565D02*
X864533Y456367D01*
G01X853467Y476303D02*
X853474Y476304D01*
G01X853460Y476301D02*
X853467Y476303D01*
G01X853453Y476299D02*
X853460Y476301D01*
G01X855726Y476645D02*
X855618Y476650D01*
G01X855796Y476637D02*
X855726Y476645D01*
G01X855814Y476627D02*
X855796Y476637D01*
G01X855779Y476619D02*
X855814Y476627D01*
G01X854638Y470428D02*
X854634Y470424D01*
G01X854650Y470432D02*
X854638Y470428D01*
G01X854669Y470436D02*
X854650Y470432D01*
G01X874787Y476954D02*
X874791Y476958D01*
G01X874775Y476950D02*
X874787Y476954D01*
G01X874756Y476945D02*
X874775Y476950D01*
G01X855211Y470714D02*
X855502Y470727D01*
G01X854973Y470696D02*
X855211Y470714D01*
G01X854810Y470676D02*
X854973Y470696D01*
G01X874214Y476668D02*
X873923Y476655D01*
G01X874452Y476686D02*
X874214Y476668D01*
G01X874615Y476706D02*
X874452Y476686D01*
G01X855814Y470754D02*
X855779Y470763D01*
G01X855796Y470745D02*
X855814Y470754D01*
G01X855726Y470737D02*
X855796Y470745D01*
G01X855618Y470731D02*
X855726Y470737D01*
G01X856982Y470766D02*
X856854Y470793D01*
G01X856975Y470737D02*
X856982Y470766D01*
G01X856835Y470709D02*
X856975Y470737D01*
G01X856571Y470685D02*
X856835Y470709D01*
G01X856209Y470668D02*
X856571Y470685D01*
G01X855961Y470656D02*
X855920Y470650D01*
G01X856019Y470660D02*
X855961Y470656D01*
G01X856093Y470663D02*
X856019Y470660D01*
G01X856981Y452994D02*
X856854Y452966D01*
G01X856976Y453023D02*
X856981Y452994D01*
G01X856834Y453050D02*
X856976Y453023D01*
G01X856567Y453074D02*
X856834Y453050D01*
G01X856209Y453092D02*
X856567Y453074D01*
G01X855209Y453046D02*
X855502Y453032D01*
G01X854974Y453064D02*
X855209Y453046D01*
G01X854810Y453084D02*
X854974Y453064D01*
G01X856020Y453100D02*
X856093Y453096D01*
G01X855960Y453104D02*
X856020Y453100D01*
G01X855920Y453109D02*
X855960Y453104D01*
G01X863785Y459900D02*
X863695Y459911D01*
G01X863869Y459866D02*
X863785Y459900D01*
G01X863947Y459811D02*
X863869Y459866D01*
G01X864015Y459738D02*
X863947Y459811D01*
G01X864072Y459648D02*
X864015Y459738D01*
G01X864113Y459546D02*
X864072Y459648D01*
G01X864139Y459435D02*
X864113Y459546D01*
G01X864148Y459321D02*
X864139Y459435D01*
G01X863785Y467774D02*
X863695Y467785D01*
G01X863869Y467740D02*
X863785Y467774D01*
G01X863947Y467685D02*
X863869Y467740D01*
G01X864015Y467612D02*
X863947Y467685D01*
G01X864072Y467522D02*
X864015Y467612D01*
G01X864113Y467420D02*
X864072Y467522D01*
G01X864139Y467309D02*
X864113Y467420D01*
G01X864148Y467195D02*
X864139Y467309D01*
G01X865143Y458545D02*
X865233Y458533D01*
G01X865059Y458579D02*
X865143Y458545D01*
G01X864981Y458633D02*
X865059Y458579D01*
G01X864913Y458706D02*
X864981Y458633D01*
G01X864856Y458797D02*
X864913Y458706D01*
G01X864814Y458899D02*
X864856Y458797D01*
G01X864789Y459009D02*
X864814Y458899D01*
G01X864780Y459124D02*
X864789Y459009D01*
G01X865143Y466419D02*
X865233Y466407D01*
G01X865059Y466453D02*
X865143Y466419D01*
G01X864981Y466507D02*
X865059Y466453D01*
G01X864913Y466580D02*
X864981Y466507D01*
G01X864856Y466671D02*
X864913Y466580D01*
G01X864814Y466773D02*
X864856Y466671D01*
G01X864789Y466883D02*
X864814Y466773D01*
G01X864780Y466998D02*
X864789Y466883D01*
G01X863664Y477022D02*
X863544Y477037D01*
G01X863776Y476977D02*
X863664Y477022D01*
G01X863880Y476904D02*
X863776Y476977D01*
G01X863971Y476807D02*
X863880Y476904D01*
G01X864047Y476686D02*
X863971Y476807D01*
G01X864102Y476550D02*
X864047Y476686D01*
G01X864136Y476403D02*
X864102Y476550D01*
G01X864148Y476250D02*
X864136Y476403D01*
G01X865264Y474297D02*
X865383Y474281D01*
G01X865152Y474342D02*
X865264Y474297D01*
G01X865048Y474414D02*
X865152Y474342D01*
G01X864957Y474512D02*
X865048Y474414D01*
G01X864881Y474633D02*
X864957Y474512D01*
G01X864826Y474769D02*
X864881Y474633D01*
G01X864792Y474916D02*
X864826Y474769D01*
G01X864780Y475069D02*
X864792Y474916D01*
G01X874973Y452602D02*
X874876Y452651D01*
G01X875059Y452486D02*
X874973Y452602D01*
G01X875127Y452314D02*
X875059Y452486D01*
G01X875170Y452100D02*
X875127Y452314D01*
G01X875185Y451865D02*
X875170Y452100D01*
G01X874612Y464283D02*
X874543Y464332D01*
G01X874674Y464167D02*
X874612Y464283D01*
G01X874723Y463993D02*
X874674Y464167D01*
G01X874754Y463777D02*
X874723Y463993D01*
G01X874765Y463545D02*
X874754Y463777D01*
G01X873486Y459499D02*
X873416Y459450D01*
G01X873547Y459616D02*
X873486Y459499D01*
G01X873596Y459788D02*
X873547Y459616D01*
G01X873627Y460001D02*
X873596Y459788D01*
G01X873638Y460236D02*
X873627Y460001D01*
G01X862259Y487116D02*
X862204Y486980D01*
G01X862378Y487240D02*
X862259Y487116D01*
G01X862551Y487336D02*
X862378Y487240D01*
G01X862763Y487398D02*
X862551Y487336D01*
G01X862990Y487418D02*
X862763Y487398D01*
G01X873611Y476627D02*
X873646Y476619D01*
G01X873629Y476637D02*
X873611Y476627D01*
G01X873699Y476645D02*
X873629Y476637D01*
G01X873807Y476650D02*
X873699Y476645D01*
G01X873465Y476726D02*
X873505Y476731D01*
G01X873405Y476722D02*
X873465Y476726D01*
G01X873332Y476718D02*
X873405Y476722D01*
G01X874453Y470696D02*
X874615Y470676D01*
G01X874215Y470714D02*
X874453Y470696D01*
G01X873923Y470727D02*
X874215Y470714D01*
G01X854973Y476686D02*
X854810Y476706D01*
G01X855210Y476668D02*
X854973Y476686D01*
G01X855502Y476655D02*
X855210Y476668D01*
G01X872444Y470766D02*
X872571Y470793D01*
G01X872449Y470737D02*
X872444Y470766D01*
G01X872592Y470709D02*
X872449Y470737D01*
G01X872858Y470685D02*
X872592Y470709D01*
G01X873216Y470668D02*
X872858Y470685D01*
G01X856981Y476616D02*
X856854Y476588D01*
G01X856976Y476645D02*
X856981Y476616D01*
G01X856834Y476672D02*
X856976Y476645D01*
G01X856567Y476696D02*
X856834Y476672D01*
G01X856209Y476714D02*
X856567Y476696D01*
G01X873405Y470660D02*
X873332Y470663D01*
G01X873465Y470656D02*
X873405Y470660D01*
G01X873505Y470650D02*
X873465Y470656D01*
G01X864157Y459007D02*
X864148Y459124D01*
G01X864182Y458897D02*
X864157Y459007D01*
G01X864224Y458795D02*
X864182Y458897D01*
G01X864280Y458706D02*
X864224Y458795D01*
G01X864350Y458632D02*
X864280Y458706D01*
G01X864428Y458578D02*
X864350Y458632D01*
G01X864512Y458545D02*
X864428Y458578D01*
G01X864600Y458533D02*
X864512Y458545D01*
G01X864771Y459437D02*
X864780Y459321D01*
G01X864746Y459548D02*
X864771Y459437D01*
G01X864704Y459649D02*
X864746Y459548D01*
G01X864648Y459738D02*
X864704Y459649D01*
G01X864578Y459813D02*
X864648Y459738D01*
G01X864500Y459867D02*
X864578Y459813D01*
G01X864416Y459900D02*
X864500Y459867D01*
G01X864328Y459911D02*
X864416Y459900D01*
G01X864157Y466881D02*
X864148Y466998D01*
G01X864182Y466771D02*
X864157Y466881D01*
G01X864224Y466669D02*
X864182Y466771D01*
G01X864280Y466580D02*
X864224Y466669D01*
G01X864350Y466506D02*
X864280Y466580D01*
G01X864428Y466452D02*
X864350Y466506D01*
G01X864512Y466419D02*
X864428Y466452D01*
G01X864600Y466407D02*
X864512Y466419D01*
G01X864771Y467311D02*
X864780Y467195D01*
G01X864746Y467422D02*
X864771Y467311D01*
G01X864704Y467523D02*
X864746Y467422D01*
G01X864648Y467612D02*
X864704Y467523D01*
G01X864578Y467687D02*
X864648Y467612D01*
G01X864500Y467741D02*
X864578Y467687D01*
G01X864416Y467774D02*
X864500Y467741D01*
G01X864328Y467785D02*
X864416Y467774D01*
G01X853460Y471080D02*
X853453Y471082D01*
G01X853467Y471079D02*
X853460Y471080D01*
G01X853474Y471078D02*
X853467Y471079D01*
G01X872858Y453074D02*
X873216Y453092D01*
G01X872592Y453051D02*
X872858Y453074D01*
G01X872450Y453023D02*
X872592Y453051D01*
G01X872444Y452994D02*
X872450Y453023D01*
G01X872571Y452966D02*
X872444Y452994D01*
G01X875958Y452681D02*
X875951Y452682D01*
G01X875965Y452679D02*
X875958Y452681D01*
G01X875972Y452677D02*
X875965Y452679D01*
G01X853500Y453310D02*
X853559Y453298D01*
G01X853465Y453323D02*
X853500Y453310D01*
G01X853453Y453336D02*
X853465Y453323D01*
G01X854650Y453327D02*
X854669Y453323D01*
G01X854638Y453332D02*
X854650Y453327D01*
G01X854634Y453336D02*
X854638Y453332D01*
G01X874973Y476225D02*
X874876Y476274D01*
G01X875059Y476108D02*
X874973Y476225D01*
G01X875127Y475936D02*
X875059Y476108D01*
G01X875170Y475722D02*
X875127Y475936D01*
G01X875185Y475487D02*
X875170Y475722D01*
G01X867079Y486186D02*
X867134Y486048D01*
G01X866960Y486308D02*
X867079Y486186D01*
G01X866789Y486404D02*
X866960Y486308D01*
G01X866578Y486465D02*
X866789Y486404D01*
G01X866348Y486486D02*
X866578Y486465D01*
G01X856020Y476722D02*
X856093Y476718D01*
G01X855960Y476726D02*
X856020Y476722D01*
G01X855920Y476731D02*
X855960Y476726D01*
G01X864160Y474913D02*
X864148Y475069D01*
G01X864194Y474766D02*
X864160Y474913D01*
G01X864250Y474631D02*
X864194Y474766D01*
G01X864324Y474512D02*
X864250Y474631D01*
G01X864417Y474413D02*
X864324Y474512D01*
G01X864521Y474341D02*
X864417Y474413D01*
G01X864634Y474296D02*
X864521Y474341D01*
G01X864751Y474281D02*
X864634Y474296D01*
G01X864768Y476405D02*
X864780Y476250D01*
G01X864734Y476552D02*
X864768Y476405D01*
G01X864678Y476688D02*
X864734Y476552D01*
G01X864604Y476807D02*
X864678Y476688D01*
G01X864511Y476906D02*
X864604Y476807D01*
G01X864407Y476978D02*
X864511Y476906D01*
G01X864294Y477022D02*
X864407Y476978D01*
G01X864177Y477037D02*
X864294Y477022D01*
G01X875965Y476301D02*
X875972Y476299D01*
G01X875958Y476303D02*
X875965Y476301D01*
G01X875951Y476304D02*
X875958Y476303D01*
G01X875960Y470436D02*
X875972Y470424D01*
G01X875925Y470449D02*
X875960Y470436D01*
G01X875866Y470461D02*
X875925Y470449D01*
G01X853465Y476945D02*
X853453Y476958D01*
G01X853501Y476933D02*
X853465Y476945D01*
G01X853559Y476920D02*
X853501Y476933D01*
G01X872858Y476696D02*
X873216Y476714D01*
G01X872592Y476673D02*
X872858Y476696D01*
G01X872450Y476645D02*
X872592Y476673D01*
G01X872444Y476616D02*
X872450Y476645D01*
G01X872571Y476588D02*
X872444Y476616D01*
G01X873611Y464527D02*
X873629Y464535D01*
G01X873617Y464518D02*
X873611Y464527D01*
G01X873646Y464510D02*
X873617Y464518D01*
G01X874786Y458557D02*
X874791Y458548D01*
G01X874770Y458566D02*
X874786Y458557D01*
G01X874744Y458574D02*
X874770Y458566D01*
G01X875964Y458562D02*
X875972Y458548D01*
G01X875939Y458576D02*
X875964Y458562D01*
G01X875897Y458590D02*
X875939Y458576D01*
G01X873617Y459241D02*
X873646Y459250D01*
G01X873611Y459233D02*
X873617Y459241D01*
G01X873629Y459224D02*
X873611Y459233D01*
G01X867397Y484724D02*
X867462Y484747D01*
G01X867332Y484857D02*
X867397Y484724D01*
G01X867275Y485129D02*
X867332Y484857D01*
G01X862093D02*
X862150Y485129D01*
G01X862028Y484724D02*
X862093Y484857D01*
G01X861963Y484747D02*
X862028Y484724D01*
G01X873627Y463758D02*
X873638Y463534D01*
G01X873596Y463971D02*
X873627Y463758D01*
G01X873548Y464144D02*
X873596Y463971D01*
G01X873486Y464260D02*
X873548Y464144D01*
G01X873416Y464310D02*
X873486Y464260D01*
G01X854650Y476950D02*
X854669Y476945D01*
G01X854638Y476954D02*
X854650Y476950D01*
G01X854634Y476958D02*
X854638Y476954D01*
G01X874775Y470432D02*
X874756Y470436D01*
G01X874787Y470428D02*
X874775Y470432D01*
G01X874791Y470424D02*
X874787Y470428D01*
G01X866665Y487397D02*
X866435Y487418D01*
G01X866875Y487336D02*
X866665Y487397D01*
G01X867047Y487240D02*
X866875Y487336D01*
G01X867165Y487118D02*
X867047Y487240D01*
G01X867221Y486980D02*
X867165Y487118D01*
G01X873531Y484321D02*
G03X872744Y485108I-787J0D01*
G01X874791Y485226D02*
G03X873531Y486486I-1260J0D01*
G01X874713Y484321D02*
G03X872744Y486289I-1968J0D01*
G01X879280Y481959D02*
G03X877311Y483927I-1968J0D01*
G01X875972Y485226D02*
G03X873531Y487667I-2441J0D01*
G01X877508Y538651D02*
G03I-12795J0D01*
G01X878098D02*
G03I-13385J0D01*
G01X878295D02*
G03I-13582J0D01*
G01X856838Y526867D02*
G03X872587I7875J11784D01*
G01X879476Y538651D02*
G03I-14763J0D01*
G01X880264D02*
G03I-15551J0D01*
G01X882707D02*
G03I-17994J0D01*
G01X883490D02*
G03I-18777J0D01*
G01X884398D02*
G03I-19685J0D01*
G01X872193Y489045D02*
G03X870224Y491014I-1969J0D01*
G01X859201D02*
G03X857232Y489045I0J-1969D01*
G01X837611Y508226D02*
G03X840303Y511962I-1245J3735D01*
G01X837611Y508226D02*
G03X840303Y511962I-1245J3735D01*
G01X856681Y485108D02*
G03X855894Y484321I0J-787D01*
G01Y486486D02*
G03X854634Y485226I0J-1260D01*
G01X856681Y486289D02*
G03X854713Y484321I0J-1968D01*
G01X852114Y483927D02*
G03X850146Y481959I0J-1968D01*
G01X855894Y487667D02*
G03X853453Y485226I0J-2441D01*
G01X871957Y481210D02*
G03X869437Y483730I-2520J0D01*
G01X840303Y474790D02*
G03X837611Y478525I-3937J0D01*
G01X840303Y474790D02*
G03X837611Y478525I-3937J0D01*
G01X872193Y526613D02*
X872505Y526111D01*
G01X872587Y526867D02*
X872915Y526376D01*
G01X849949Y526447D02*
X847193D01*
G01X882232D02*
X879476D01*
G01X877114Y526250D02*
X852311D01*
G01X847587Y523888D02*
X881839D01*
G01X847193Y523494D02*
X882232D01*
G01X847193Y520935D02*
X882232D01*
G01X861989Y485908D02*
X860842Y487667D01*
G01X860830Y486486D02*
X861963Y484747D01*
G01X864713Y481210D02*
X865500Y480108D01*
G01Y472234D02*
X864713Y473336D01*
G01X866209Y481762D02*
X864713Y483258D01*
G01X835244Y496539D02*
X834992Y496785D01*
G01X858800Y479188D02*
X859861Y478297D01*
G01X858648D02*
X857587Y479188D01*
G01X834909Y496293D02*
X834406Y496621D01*
G01X832312Y494980D02*
X832814Y494652D01*
G01X834992Y496785D02*
X834657Y496949D01*
G01X832228Y494488D02*
X832563Y494324D01*
G01X833820Y491700D02*
X833652Y491782D01*
G01X833820Y488009D02*
X833652Y488091D01*
G01X834657Y496949D02*
X834406Y497031D01*
G01X832563Y494324D02*
X832814Y494242D01*
G01X834406Y497031D02*
X833987Y497113D01*
G01X832814Y494242D02*
X833233Y494160D01*
G01X834406Y496621D02*
X833903Y496703D01*
G01X832814Y494652D02*
X833317Y494570D01*
G01X831642Y503019D02*
X835579D01*
G01X833485Y502526D02*
X831642D01*
G01X835579D02*
X833987D01*
G01Y500230D02*
X835579D01*
G01X831642D02*
X833485D01*
G01X835579Y499738D02*
X831642D01*
G01X833987Y499082D02*
X834322D01*
G01X832982D02*
X833317D01*
G01X867362Y486061D02*
X867221Y486980D01*
G01X867134Y486048D02*
X867275Y485129D01*
G01X835495Y496129D02*
X835244Y496539D01*
G01X831725Y495145D02*
X831977Y494734D01*
G01X835076Y496047D02*
X834909Y496293D01*
G01X832144Y495227D02*
X832312Y494980D01*
G01X865500Y464360D02*
X864713Y465462D01*
G01X865500Y456486D02*
X864713Y457588D01*
G01X834071Y493094D02*
X834238Y492930D01*
G01X833903D02*
X833736Y493094D01*
G01X831977Y494734D02*
X832228Y494488D01*
G01X833987Y491864D02*
X834238Y491618D01*
G01X833903D02*
X833820Y491700D01*
G01X834071Y489403D02*
X834238Y489239D01*
G01X833903D02*
X833736Y489403D01*
G01X833987Y488173D02*
X834238Y487927D01*
G01X833903D02*
X833820Y488009D01*
G01X837611Y478525D02*
X831184Y480667D01*
G01X837611Y478525D02*
X831184Y480667D01*
G01X854669Y476945D02*
X855920Y476731D01*
G01X854810Y476706D02*
X853559Y476920D01*
G01X874615Y470676D02*
X875866Y470461D01*
G01X874756Y470436D02*
X873505Y470650D01*
G01X873646Y476619D02*
X875951Y476304D01*
G01X874876Y476274D02*
X872571Y476588D01*
G01X833317Y497769D02*
X832982D01*
G01X834322D02*
X833987D01*
G01Y497113D02*
X833233D01*
G01X833903Y496703D02*
X833317D01*
G01Y494570D02*
X833903D01*
G01X833233Y494160D02*
X833987D01*
G01X831642Y493504D02*
X834322D01*
G01X833736Y493094D02*
X831642D01*
G01X834322D02*
X834071D01*
G01X831642Y492192D02*
X833652D01*
G01Y491782D02*
X831642D01*
G01X870224Y491014D02*
X859201D01*
G01X831642Y490879D02*
X833652D01*
G01Y490469D02*
X831642D01*
G01Y489813D02*
X834322D01*
G01X833736Y489403D02*
X831642D01*
G01X834322D02*
X834071D01*
G01X831642Y488501D02*
X833652D01*
G01X857232Y488455D02*
X872193D01*
G01X833652Y488091D02*
X831642D01*
G01X851958Y487667D02*
X877467D01*
G01X862990Y487418D02*
X866435D01*
G01X831642Y487188D02*
X833652D01*
G01Y486778D02*
X831642D01*
G01X851958Y486486D02*
X877467D01*
G01X875894Y486289D02*
X853531D01*
G01X867362Y486061D02*
X862063D01*
G01X861989Y485908D02*
X867437D01*
G01X867420Y485896D02*
X862006D01*
G01X867275Y485129D02*
X862150D01*
G01X856681Y485108D02*
X872744D01*
G01X861963Y484747D02*
X867462D01*
G01X854634Y484714D02*
X853453D01*
G01X867420D02*
X862006D01*
G01X875972D02*
X874791D01*
G01X855894Y484321D02*
X854713D01*
G01X874713D02*
X873531D01*
G01X854634Y483927D02*
X852114D01*
G01X877311D02*
X874791D01*
G01X864713Y483730D02*
X869437D01*
G01X874713Y483140D02*
X875894D01*
G01X853531D02*
X854713D01*
G01X864713D02*
X860776D01*
G01X833317Y496703D02*
X832814Y496621D01*
G01X833903Y494570D02*
X834406Y494652D01*
G01X833233Y497113D02*
X832814Y497031D01*
G01X833987Y494160D02*
X834406Y494242D01*
G01X882232Y520935D02*
Y556368D01*
G01X881839Y529695D02*
Y523888D01*
G01X834238Y492930D02*
X834322Y492684D01*
G01X833987Y491454D02*
X833903Y491618D01*
G01X833987Y487763D02*
X833903Y487927D01*
G01X875897Y458590D02*
X873629Y459224D01*
G01X872476Y459208D02*
X874744Y458574D01*
G01X874543Y464332D02*
X873646Y464510D01*
G01X872519Y464488D02*
X873416Y464310D01*
G01X854549Y471108D02*
X856854Y470793D01*
G01X855779Y470763D02*
X853474Y471078D01*
G01X856093Y476718D02*
X856209Y476714D01*
G01X855618Y476650D02*
X855502Y476655D01*
G01X873807Y470731D02*
X873923Y470727D01*
G01X873332Y470663D02*
X873216Y470668D01*
G01X854549Y476274D02*
X853474Y476304D01*
G01X853453Y475510D02*
X854240Y475487D01*
G01X875972Y471872D02*
X875185Y471894D01*
G01X874876Y471108D02*
X875951Y471078D01*
G01X874791Y482549D02*
X875972D01*
G01X853453D02*
X854634D01*
G01X864319D02*
X861169D01*
G01X853531Y481959D02*
X875894D01*
G01X856839Y481762D02*
X872587D01*
G01X854634D02*
X853453D01*
G01X875972D02*
X874791D01*
G01X870579Y480679D02*
X869594D01*
G01X869693Y480659D02*
X870480D01*
G01X869693Y480581D02*
X870480D01*
G01Y480506D02*
X869693D01*
G01Y480482D02*
X870480D01*
G01Y480446D02*
X869693D01*
G01X864713Y480384D02*
X860776D01*
G01X870480Y480358D02*
X869693D01*
G01X870480Y480335D02*
X869693D01*
G01Y480305D02*
X870480D01*
G01X869693Y480187D02*
X870480D01*
G01X865500Y480108D02*
X870579D01*
G01X865815Y480088D02*
X870480D01*
G01X857587Y480079D02*
X864713D01*
G01X874791Y479793D02*
X875972D01*
G01X853453D02*
X854634D01*
G01X868846Y479399D02*
X871209D01*
G01X871012Y479203D02*
X869693D01*
G01X864713Y479188D02*
X858800D01*
G01X854634Y479006D02*
X853453D01*
G01X875972D02*
X874791D01*
G01X871957Y478809D02*
X866747D01*
G01X865776Y478651D02*
X864713D01*
G01X865697Y478478D02*
X864713D01*
G01X871012Y478415D02*
X870224D01*
G01X865697Y478386D02*
X864713D01*
G01Y478336D02*
X865697D01*
G01X859861Y478297D02*
X858648D01*
G01X865697Y478289D02*
X864713D01*
G01X870224Y478218D02*
X871012D01*
G01X865697D02*
X864713D01*
G01X865697Y478120D02*
X864713D01*
G01X860185Y478022D02*
X865776D01*
G01X874791Y478008D02*
X875972D01*
G01X853453D02*
X854634D01*
G01X858905Y477825D02*
X867173D01*
G01X865697Y477628D02*
X860283D01*
G01X865697Y477268D02*
X864713D01*
G01X854634Y477234D02*
X853453D01*
G01X875972D02*
X874791D01*
G01X854634Y477223D02*
X853453D01*
G01X875972D02*
X874791D01*
G01Y477195D02*
X875972D01*
G01X853453D02*
X854634D01*
G01X870224Y477037D02*
X871012D01*
G01X862547D02*
X865697D01*
G01X871012Y476840D02*
X870224D01*
G01X861268Y476447D02*
X860283D01*
G01X871957D02*
X866747D01*
G01X860283Y476250D02*
X861268D01*
G01X864780D02*
X864148D01*
G01X869693Y476053D02*
X871012D01*
G01X856839D02*
X854713D01*
G01X874713D02*
X872587D01*
G01X868846Y475856D02*
X871209D01*
G01X872823Y475659D02*
X875972D01*
G01X856602D02*
X853453D01*
G01X870480Y475167D02*
X865815D01*
G01X870579Y475147D02*
X865500D01*
G01X869693Y475069D02*
X870480D01*
G01X860283D02*
X861268D01*
G01X864780D02*
X864148D01*
G01X870480Y474951D02*
X869693D01*
G01Y474921D02*
X870480D01*
G01X869693Y474898D02*
X870480D01*
G01X861268Y474872D02*
X860283D01*
G01X869693Y474809D02*
X870480D01*
G01Y474773D02*
X869693D01*
G01Y474750D02*
X870480D01*
G01Y474675D02*
X869693D01*
G01X870480Y474596D02*
X869693D01*
G01X871957Y474577D02*
X865776D01*
G01X867941Y474478D02*
X865776D01*
G01X867744Y474281D02*
X864751D01*
G01X860283Y473691D02*
X865697D01*
G01X858905Y473494D02*
X867173D01*
G01X865697Y473199D02*
X864713D01*
G01X867744Y473100D02*
X862547D01*
G01X864713Y473029D02*
X865697D01*
G01Y472982D02*
X864713D01*
G01Y472933D02*
X865697D01*
G01X867941Y472903D02*
X860185D01*
G01X864713Y472870D02*
X865697D01*
G01X864713Y472840D02*
X865697D01*
G01X871957Y472805D02*
X865894D01*
G01X869693Y472785D02*
X870480D01*
G01X869693Y472707D02*
X870480D01*
G01X865776Y472667D02*
X864713D01*
G01X870480Y472632D02*
X869693D01*
G01Y472608D02*
X870480D01*
G01Y472572D02*
X869693D01*
G01X870480Y472484D02*
X869693D01*
G01X870480Y472460D02*
X869693D01*
G01Y472431D02*
X870480D01*
G01X869693Y472313D02*
X870480D01*
G01X865500Y472234D02*
X870579D01*
G01X865815Y472214D02*
X870480D01*
G01X856602Y471722D02*
X853453D01*
G01X875972D02*
X872823D01*
G01X868846Y471525D02*
X871209D01*
G01X856839Y471329D02*
X854713D01*
G01X871012D02*
X869693D01*
G01X874713D02*
X872587D01*
G01X871957Y470935D02*
X866747D01*
G01X871012Y470541D02*
X870224D01*
G01Y470344D02*
X871012D01*
G01X854634Y470187D02*
X853453D01*
G01X875972D02*
X874791D01*
G01Y470159D02*
X875972D01*
G01X853453D02*
X854634D01*
G01X874791Y470147D02*
X875972D01*
G01X853453D02*
X854634D01*
G01Y469373D02*
X853453D01*
G01X875972D02*
X874791D01*
G01X870224Y469163D02*
X871012D01*
G01Y468966D02*
X870224D01*
G01X865776Y468809D02*
X864713D01*
G01X865697Y468636D02*
X864713D01*
G01X871957Y468573D02*
X866747D01*
G01X875972D02*
X874791D01*
G01X865697Y468543D02*
X864713D01*
G01Y468494D02*
X865697D01*
G01Y468447D02*
X864713D01*
G01X874791Y468376D02*
X875972D01*
G01X854634D02*
X853453D01*
G01X865697D02*
X864713D01*
G01X865697Y468277D02*
X864713D01*
G01X869693Y468179D02*
X871012D01*
G01X865776D02*
X860185D01*
G01X868846Y467982D02*
X871209D01*
G01X858905D02*
X867173D01*
G01X865697Y467958D02*
X864713D01*
G01X875951Y476304D02*
X874876Y476274D01*
G01X875185Y475487D02*
X875972Y475510D01*
G01X854240Y471894D02*
X853453Y471872D01*
G01X853474Y471078D02*
X854549Y471108D01*
G01X873216Y476714D02*
X873332Y476718D01*
G01X873923Y476655D02*
X873807Y476650D01*
G01X855502Y470727D02*
X855618Y470731D01*
G01X856209Y470668D02*
X856093Y470663D01*
G01X879476Y520935D02*
Y556368D01*
G01X877468Y486486D02*
Y487667D01*
G01X877430Y486486D02*
Y487667D01*
G01X877402D02*
Y486486D01*
G01X877114Y535699D02*
Y523888D01*
G01X876327Y526250D02*
Y523888D01*
G01X876069Y486486D02*
Y487667D01*
G01X875972D02*
Y486486D01*
G01X875897Y465169D02*
Y458590D01*
G01X875894Y481959D02*
Y486289D01*
G01Y467588D02*
Y456171D01*
G01X875866Y470461D02*
Y476920D01*
G01X875849Y471722D02*
Y475659D01*
G01X875670Y486486D02*
Y487667D01*
G01X875185Y486486D02*
Y487667D01*
G01Y475487D02*
Y471894D01*
G01X874765Y463534D02*
Y460214D01*
G01X874756Y470436D02*
Y476945D01*
G01X874744Y465185D02*
Y458574D01*
G01X874615Y476706D02*
Y470676D01*
G01X874162Y487667D02*
Y486486D01*
G01X873954Y475659D02*
Y471722D01*
G01X873923Y470727D02*
Y476655D01*
G01X873807Y470731D02*
Y476650D01*
G01X873768Y487667D02*
Y486486D01*
G01X873646Y459250D02*
Y464510D01*
G01Y476619D02*
Y470763D01*
G01X873638Y463523D02*
Y460236D01*
G01X873629Y464535D02*
Y459224D01*
G01X873610Y486484D02*
Y487667D01*
G01Y464524D02*
Y459235D01*
G01Y476629D02*
Y470753D01*
G01X873505Y476731D02*
Y470650D01*
G01X873332Y470663D02*
Y476718D01*
G01X873216Y470668D02*
Y476714D01*
G01X872980Y486486D02*
Y487667D01*
G01X872823Y475659D02*
Y471722D01*
G01Y487667D02*
Y486486D01*
G01X872744Y485108D02*
Y486289D01*
G01X872587Y476053D02*
Y471329D01*
G01Y481959D02*
Y481762D01*
G01X872571Y476588D02*
Y470793D01*
G01X872519Y459272D02*
Y464488D01*
G01X872476Y464551D02*
Y459208D01*
G01X872429Y464524D02*
Y459235D01*
G01Y476629D02*
Y470753D01*
G01X872193Y489045D02*
Y486486D01*
G01X871824Y455187D02*
Y452825D01*
G01Y463061D02*
Y460699D01*
G01Y470935D02*
Y468573D01*
G01Y478809D02*
Y476447D01*
G01X871405Y487667D02*
Y486486D01*
G01X871209Y455777D02*
Y452234D01*
G01Y463651D02*
Y460108D01*
G01Y471525D02*
Y467982D01*
G01Y479399D02*
Y475856D01*
G01X871012Y455581D02*
Y452431D01*
G01Y463455D02*
Y460305D01*
G01Y471329D02*
Y468179D01*
G01Y479203D02*
Y476053D01*
G01X871011Y486486D02*
Y487667D01*
G01X870748Y476053D02*
Y479203D01*
G01Y468179D02*
Y471329D01*
G01Y460305D02*
Y463455D01*
G01Y452431D02*
Y455581D01*
G01X870708Y476053D02*
Y479203D01*
G01Y468179D02*
Y471329D01*
G01Y460305D02*
Y463455D01*
G01Y452431D02*
Y455581D01*
G01X870618Y487667D02*
Y486486D01*
G01X870611Y487667D02*
Y486486D01*
G01X870579Y474577D02*
Y480679D01*
G01Y466703D02*
Y472805D01*
G01Y458829D02*
Y464931D01*
G01Y450955D02*
Y457057D01*
G01X870480D02*
Y450955D01*
G01Y464931D02*
Y458829D01*
G01Y472805D02*
Y466703D01*
G01Y480679D02*
Y474577D01*
G01X870373Y475167D02*
Y480088D01*
G01Y467293D02*
Y472214D01*
G01Y459419D02*
Y464340D01*
G01Y451545D02*
Y456466D01*
G01X870224Y455581D02*
Y452431D01*
G01Y463455D02*
Y460305D01*
G01Y471329D02*
Y468179D01*
G01Y479203D02*
Y476053D01*
G01X870066D02*
Y479203D01*
G01Y468179D02*
Y471329D01*
G01Y460305D02*
Y463455D01*
G01Y452431D02*
Y455581D01*
G01X870028Y455777D02*
Y452234D01*
G01Y463651D02*
Y460108D01*
G01Y471525D02*
Y467982D01*
G01Y479399D02*
Y475856D01*
G01X869957Y476053D02*
Y479203D01*
G01Y468179D02*
Y471329D01*
G01Y460305D02*
Y463455D01*
G01Y452431D02*
Y455581D01*
G01X869693Y474577D02*
Y480679D01*
G01Y466703D02*
Y472805D01*
G01Y458829D02*
Y464931D01*
G01Y450955D02*
Y457057D01*
G01X869639Y475167D02*
Y480088D01*
G01Y467293D02*
Y472214D01*
G01Y459419D02*
Y464340D01*
G01Y451545D02*
Y456466D01*
G01X869594Y451525D02*
Y450955D01*
G01Y457057D02*
Y456486D01*
G01Y459399D02*
Y458829D01*
G01Y464931D02*
Y464360D01*
G01Y467273D02*
Y466703D01*
G01Y472805D02*
Y472234D01*
G01Y475147D02*
Y474577D01*
G01Y480679D02*
Y480108D01*
G01X869504Y487667D02*
Y486486D01*
G01X869201Y487667D02*
Y486486D01*
G01X869104Y487667D02*
Y486486D01*
G01X869043Y525156D02*
Y526611D01*
G01Y452825D02*
Y451525D01*
G01Y456486D02*
Y455187D01*
G01Y460699D02*
Y459399D01*
G01Y464360D02*
Y463061D01*
G01Y468573D02*
Y467273D01*
G01Y472234D02*
Y470935D01*
G01Y476447D02*
Y475147D01*
G01Y480108D02*
Y478809D01*
G01X868846Y475856D02*
Y479399D01*
G01Y467982D02*
Y471525D01*
G01Y460108D02*
Y463651D01*
G01Y452234D02*
Y455777D01*
G01X868732Y486486D02*
Y487667D01*
G01X868657Y486486D02*
Y487667D01*
G01X868413Y486486D02*
Y487667D01*
G01X867951D02*
Y486486D01*
G01X867941Y458730D02*
Y457155D01*
G01Y466604D02*
Y465029D01*
G01Y474478D02*
Y472903D01*
G01X867771Y486486D02*
Y487667D01*
G01X867744Y458533D02*
Y457352D01*
G01Y466407D02*
Y465226D01*
G01Y474281D02*
Y473100D01*
G01X867743Y487667D02*
Y486486D01*
G01X867705D02*
Y487667D01*
G01X867640Y475167D02*
Y480088D01*
G01Y467293D02*
Y472214D01*
G01Y459419D02*
Y464340D01*
G01Y451545D02*
Y456466D01*
G01X867587D02*
Y451545D01*
G01Y464340D02*
Y459419D01*
G01Y472214D02*
Y467293D01*
G01Y480088D02*
Y475167D01*
G01X867173Y460108D02*
Y455777D01*
G01Y467982D02*
Y463651D01*
G01Y477825D02*
Y473494D01*
G01X867111Y458533D02*
Y457352D01*
G01Y466407D02*
Y465226D01*
G01Y474281D02*
Y473100D01*
G01X866907Y475167D02*
Y480088D01*
G01Y467293D02*
Y472214D01*
G01Y459419D02*
Y464340D01*
G01Y451545D02*
Y456466D01*
G01X866799D02*
Y451545D01*
G01Y464340D02*
Y459419D01*
G01Y472214D02*
Y467293D01*
G01Y480088D02*
Y475167D01*
G01X866760Y458533D02*
Y457352D01*
G01Y466407D02*
Y465226D01*
G01Y474281D02*
Y473100D01*
G01X866747Y476447D02*
Y478809D01*
G01Y468573D02*
Y470935D01*
G01Y460699D02*
Y463061D01*
G01Y452825D02*
Y455187D01*
G01X866681Y456486D02*
Y451525D01*
G01Y464360D02*
Y459399D01*
G01Y472234D02*
Y467273D01*
G01Y480108D02*
Y475147D01*
G01X866602Y456466D02*
Y451545D01*
G01Y464340D02*
Y459419D01*
G01Y472214D02*
Y467293D01*
G01Y480088D02*
Y475167D01*
G01X866563Y456486D02*
Y451525D01*
G01Y464360D02*
Y459399D01*
G01Y472234D02*
Y467273D01*
G01Y480108D02*
Y475147D01*
G01X866479Y458533D02*
Y457352D01*
G01Y466407D02*
Y465226D01*
G01Y474281D02*
Y473100D01*
G01X866405Y475167D02*
Y480088D01*
G01Y467293D02*
Y472214D01*
G01Y459419D02*
Y464340D01*
G01Y451545D02*
Y456466D01*
G01X865992Y460108D02*
Y455777D01*
G01Y467982D02*
Y463651D01*
G01Y477825D02*
Y473494D01*
G01X865894Y458829D02*
Y457057D01*
G01Y466703D02*
Y464931D01*
G01Y474577D02*
Y472805D01*
G01X865815Y456486D02*
Y451525D01*
G01Y464360D02*
Y459399D01*
G01Y472234D02*
Y467273D01*
G01Y480108D02*
Y475147D01*
G01X865776Y451092D02*
Y450856D01*
G01Y457155D02*
Y454951D01*
G01Y460935D02*
Y458730D01*
G01Y465029D02*
Y462825D01*
G01Y468809D02*
Y466604D01*
G01Y472903D02*
Y472667D01*
G01Y478651D02*
Y474478D01*
G01X865697Y472667D02*
Y478651D01*
G01Y462825D02*
Y468809D01*
G01Y454951D02*
Y460935D01*
G01X865654Y473100D02*
Y477037D01*
G01Y463848D02*
Y467785D01*
G01Y455974D02*
Y459911D01*
G01X865500Y459399D02*
Y464360D01*
G01Y456486D02*
Y451525D01*
G01Y472234D02*
Y467273D01*
G01Y480108D02*
Y475147D01*
G01X864780Y459321D02*
Y459124D01*
G01Y467195D02*
Y466998D01*
G01Y476250D02*
Y475069D01*
G01X863077Y486486D02*
X862990Y487418D01*
G01X862291Y486048D02*
X862204Y486980D01*
G01X835579Y495637D02*
X835495Y496129D01*
G01X835160Y495637D02*
X835076Y496047D01*
G01X832061Y495637D02*
X832144Y495227D01*
G01X833987Y492684D02*
X833903Y492930D01*
G01X834238Y491618D02*
X834322Y491372D01*
G01X834238Y489239D02*
X834322Y488993D01*
G01X833987D02*
X833903Y489239D01*
G01X834238Y487927D02*
X834322Y487681D01*
G01X854669Y453323D02*
X855920Y453109D01*
G01X853559Y453298D02*
X854810Y453084D01*
G01X873646Y452997D02*
X875951Y452682D01*
G01X874876Y452651D02*
X872571Y452966D01*
G01X856093Y453096D02*
X856209Y453092D01*
G01X855618Y453028D02*
X855502Y453032D01*
G01X854549Y452651D02*
X853474Y452682D01*
G01X854240Y451865D02*
X853453Y451887D01*
G01X873638Y460236D02*
X874765Y460214D01*
G01X874543Y459428D02*
X873416Y459450D01*
G01X865697Y467785D02*
X860283D01*
G01X875972D02*
X874791D01*
G01X875894Y467588D02*
X874713D01*
G01X870480Y467293D02*
X865815D01*
G01X870579Y467273D02*
X865500D01*
G01X869693Y467195D02*
X870480D01*
G01X864780D02*
X864148D01*
G01X870480Y467077D02*
X869693D01*
G01Y467047D02*
X870480D01*
G01X869693Y467024D02*
X870480D01*
G01X864780Y466998D02*
X864148D01*
G01X875972D02*
X874791D01*
G01X869693Y466935D02*
X870480D01*
G01Y466899D02*
X869693D01*
G01Y466876D02*
X870480D01*
G01X874791Y466812D02*
X875972D01*
G01X874791Y466810D02*
X875972D01*
G01X870480Y466801D02*
X869693D01*
G01X870480Y466722D02*
X869693D01*
G01X865776Y466703D02*
X871957D01*
G01X861268Y466604D02*
X860283D01*
G01X867941D02*
X865776D01*
G01X864600Y466407D02*
X867744D01*
G01X861268D02*
X860283D01*
G01X875894D02*
X874713D01*
G01X875972Y465693D02*
X874791D01*
G01X875972Y465238D02*
X874791D01*
G01X861268Y465226D02*
X860283D01*
G01X867744D02*
X864619D01*
G01X861268Y465029D02*
X860283D01*
G01X867941D02*
X865776D01*
G01X871957Y464931D02*
X865776D01*
G01X869693Y464911D02*
X870480D01*
G01X874791Y464907D02*
X875972D01*
G01X869693Y464833D02*
X870480D01*
G01Y464758D02*
X869693D01*
G01Y464734D02*
X870480D01*
G01Y464698D02*
X869693D01*
G01X864148Y464636D02*
X864560D01*
G01X870480Y464610D02*
X869693D01*
G01X870480Y464586D02*
X869693D01*
G01Y464557D02*
X870480D01*
G01X869693Y464439D02*
X870480D01*
G01X864148D02*
X864560D01*
G01X865500Y464360D02*
X870579D01*
G01X865815Y464340D02*
X870480D01*
G01X860283Y463848D02*
X865697D01*
G01X864713Y463675D02*
X865697D01*
G01X868846Y463651D02*
X871209D01*
G01X858905D02*
X867173D01*
G01X873638Y463534D02*
X874765D01*
G01X865776Y463455D02*
X860185D01*
G01X871012D02*
X869693D01*
G01X865697Y463356D02*
X864713D01*
G01X865697Y463258D02*
X864713D01*
G01Y463187D02*
X865697D01*
G01Y463140D02*
X864713D01*
G01Y463090D02*
X865697D01*
G01X871957Y463061D02*
X866747D01*
G01X864713Y462998D02*
X865697D01*
G01X865776Y462825D02*
X864713D01*
G01X871012Y462667D02*
X870224D01*
G01Y462470D02*
X871012D01*
G01X854634Y461899D02*
X850146D01*
G01X854634Y461860D02*
X850146D01*
G01X870224Y461289D02*
X871012D01*
G01Y461092D02*
X870224D01*
G01X865776Y460935D02*
X864713D01*
G01X865697Y460762D02*
X864713D01*
G01X871957Y460699D02*
X866747D01*
G01X865697Y460669D02*
X864713D01*
G01Y460620D02*
X865697D01*
G01Y460573D02*
X864713D01*
G01X854634Y460515D02*
X853453D01*
G01X865697Y460502D02*
X864713D01*
G01X854634Y460489D02*
X853453D01*
G01X865697Y460403D02*
X864713D01*
G01X869693Y460305D02*
X871012D01*
G01X865776D02*
X860185D01*
G01X868846Y460108D02*
X871209D01*
G01X858905D02*
X867173D01*
G01X865697Y460084D02*
X864713D01*
G01X865697Y459911D02*
X860283D01*
G01X854634Y459465D02*
X853453D01*
G01X854634Y459439D02*
X853453D01*
G01X870480Y459419D02*
X865815D01*
G01X870579Y459399D02*
X865500D01*
G01X869693Y459321D02*
X870480D01*
G01X864780D02*
X864148D01*
G01X870480Y459203D02*
X869693D01*
G01Y459173D02*
X870480D01*
G01X869693Y459150D02*
X870480D01*
G01X864780Y459124D02*
X864148D01*
G01X869693Y459061D02*
X870480D01*
G01Y459025D02*
X869693D01*
G01Y459002D02*
X870480D01*
G01Y458927D02*
X869693D01*
G01X875972Y458852D02*
X874791D01*
G01X870480Y458848D02*
X869693D01*
G01X871957Y458829D02*
X865776D01*
G01X861268Y458730D02*
X860283D01*
G01X867941D02*
X865776D01*
G01X864600Y458533D02*
X867744D01*
G01X861268D02*
X860283D01*
G01X874791Y458515D02*
X875972D01*
G01X874791Y458067D02*
X875972D01*
G01X854634Y457962D02*
X853453D01*
G01X854634Y457923D02*
X853453D01*
G01X861268Y457352D02*
X860283D01*
G01X867744D02*
X864619D01*
G01X875894D02*
X874713D01*
G01X861268Y457155D02*
X860283D01*
G01X867941D02*
X865776D01*
G01X871957Y457057D02*
X865776D01*
G01X869693Y457037D02*
X870480D01*
G01X869693Y456959D02*
X870480D01*
G01X875972Y456943D02*
X874791D01*
G01Y456942D02*
X875972D01*
G01X870480Y456884D02*
X869693D01*
G01Y456860D02*
X870480D01*
G01Y456824D02*
X869693D01*
G01X874791Y456762D02*
X875972D01*
G01X864148D02*
X864560D01*
G01X870480Y456736D02*
X869693D01*
G01X870480Y456712D02*
X869693D01*
G01Y456683D02*
X870480D01*
G01X869693Y456565D02*
X870480D01*
G01X864148D02*
X864560D01*
G01X870579Y456486D02*
X865500D01*
G01X865815Y456466D02*
X870480D01*
G01X875894Y456171D02*
X874713D01*
G01X860283Y455974D02*
X865697D01*
G01X875972D02*
X874791D01*
G01X864713Y455801D02*
X865697D01*
G01X868846Y455777D02*
X871209D01*
G01X858905D02*
X867173D01*
G01X865776Y455581D02*
X860185D01*
G01X871012D02*
X869693D01*
G01X865697Y455482D02*
X864713D01*
G01X854634Y455384D02*
X853453D01*
G01X865697D02*
X864713D01*
G01X875972D02*
X874791D01*
G01X864713Y455313D02*
X865697D01*
G01Y455266D02*
X864713D01*
G01Y455216D02*
X865697D01*
G01X874791Y455187D02*
X875972D01*
G01X871957D02*
X866747D01*
G01X864713Y455124D02*
X865697D01*
G01X865776Y454951D02*
X864713D01*
G01X871012Y454793D02*
X870224D01*
G01Y454596D02*
X871012D01*
G01X874791Y454386D02*
X875972D01*
G01X853453D02*
X854634D01*
G01Y453612D02*
X853453D01*
G01X875972D02*
X874791D01*
G01X854634Y453601D02*
X853453D01*
G01X875972D02*
X874791D01*
G01X854634Y453573D02*
X853453D01*
G01X875972D02*
X874791D01*
G01X870224Y453415D02*
X871012D01*
G01Y453218D02*
X870224D01*
G01X871957Y452825D02*
X866747D01*
G01X873416Y464310D02*
X874543Y464332D01*
G01X853474Y476304D02*
X855779Y476619D01*
G01X856854Y476588D02*
X854549Y476274D01*
G01X872571Y470793D02*
X874876Y471108D01*
G01X875951Y471078D02*
X873646Y470763D01*
G01X873505Y476731D02*
X874756Y476945D01*
G01X875866Y476920D02*
X874615Y476706D01*
G01X853559Y470461D02*
X854810Y470676D01*
G01X855920Y470650D02*
X854669Y470436D01*
G01X867221Y486980D02*
X867134Y486048D01*
G01X866435Y487418D02*
X866348Y486486D01*
G01X864713Y480079D02*
Y479188D01*
G01X864685Y473100D02*
Y477037D01*
G01Y463848D02*
Y467785D01*
G01Y455974D02*
Y459911D01*
G01X864560Y456762D02*
Y456565D01*
G01Y464636D02*
Y464439D01*
G01X864319Y482549D02*
Y481762D01*
G01X864164Y459911D02*
Y455982D01*
G01Y467785D02*
Y463856D01*
G01Y477037D02*
Y473100D01*
G01X864148Y475069D02*
Y476250D01*
G01Y466998D02*
Y467195D01*
G01Y464439D02*
Y464636D01*
G01Y459124D02*
Y459321D01*
G01Y456565D02*
Y456762D01*
G01X863559Y473100D02*
Y477037D01*
G01Y463848D02*
Y467785D01*
G01Y455974D02*
Y459911D01*
G01X863531D02*
Y455974D01*
G01Y467785D02*
Y463848D01*
G01Y477628D02*
Y473100D01*
G01X862590D02*
Y477037D01*
G01Y463848D02*
Y467785D01*
G01Y455974D02*
Y459911D01*
G01X862547D02*
Y455974D01*
G01Y467785D02*
Y463848D01*
G01Y477037D02*
Y473100D01*
G01X862449Y459911D02*
Y455974D01*
G01Y467785D02*
Y463848D01*
G01Y477628D02*
Y473691D01*
G01X862252Y473494D02*
Y477825D01*
G01Y460108D02*
Y455777D01*
G01Y467982D02*
Y463651D01*
G01X861720Y486486D02*
Y487667D01*
G01X861682Y486486D02*
Y487667D01*
G01X861654D02*
Y486486D01*
G01X861474D02*
Y487667D01*
G01X861465Y460108D02*
Y455777D01*
G01Y467982D02*
Y463651D01*
G01Y477825D02*
Y473494D01*
G01X861268Y473691D02*
Y477628D01*
G01Y463848D02*
Y467785D01*
G01Y455974D02*
Y459911D01*
G01X861169Y481762D02*
Y482549D01*
G01X861012Y487667D02*
Y486486D01*
G01X860776Y483140D02*
Y480384D01*
G01X860769Y487667D02*
Y486486D01*
G01X860693Y487667D02*
Y486486D01*
G01X860382Y526611D02*
Y525156D01*
G01X860321Y486486D02*
Y487667D01*
G01X860283Y459911D02*
Y455974D01*
G01Y467785D02*
Y463848D01*
G01Y477628D02*
Y473691D01*
G01X860224Y487667D02*
Y486486D01*
G01X860185Y460305D02*
Y455581D01*
G01Y468179D02*
Y463455D01*
G01Y478022D02*
Y472903D01*
G01X860087Y460108D02*
Y455777D01*
G01Y467982D02*
Y463651D01*
G01Y477825D02*
Y473494D01*
G01X859921Y486486D02*
Y487667D01*
G01X858905Y460108D02*
Y455777D01*
G01Y467982D02*
Y463651D01*
G01Y477825D02*
Y473494D01*
G01X858814Y486486D02*
Y487667D01*
G01X858807D02*
Y486486D01*
G01X858414Y487667D02*
Y486486D01*
G01X858020Y487667D02*
Y486486D01*
G01X857587Y479188D02*
Y480079D01*
G01X857232Y489045D02*
Y486486D01*
G01X856996Y476629D02*
Y470753D01*
G01X856854Y470793D02*
Y476588D01*
G01X856839Y481762D02*
Y481959D01*
G01Y471329D02*
Y476053D01*
G01X856681Y486289D02*
Y485108D01*
G01X856602Y486486D02*
Y487667D01*
G01Y471722D02*
Y475659D01*
G01X856445Y487667D02*
Y486486D01*
G01X856209Y476714D02*
Y470668D01*
G01X856093Y476718D02*
Y470663D01*
G01X855920Y470650D02*
Y476731D01*
G01X855815Y486484D02*
Y487667D01*
G01Y476629D02*
Y470753D01*
G01X855779Y470763D02*
Y476619D01*
G01X855657Y487667D02*
Y486486D01*
G01X855618Y476650D02*
Y470731D01*
G01X855502Y476655D02*
Y470727D01*
G01X855471Y475659D02*
Y471722D01*
G01X855263Y486486D02*
Y487667D01*
G01X854810Y470676D02*
Y476706D01*
G01X854669Y476945D02*
Y470436D01*
G01X854240Y471894D02*
Y475487D01*
G01Y487667D02*
Y486486D01*
G01X853756Y487667D02*
Y486486D01*
G01X853576Y475659D02*
Y471722D01*
G01X853559Y476920D02*
Y470461D01*
G01X853531Y481959D02*
Y486289D01*
G01X853453Y487667D02*
Y486486D01*
G01X853356Y487667D02*
Y486486D01*
G01X853098Y526250D02*
Y523888D01*
G01X852665Y461899D02*
Y483927D01*
G01X852311Y523888D02*
Y535699D01*
G01X852023Y486486D02*
Y487667D01*
G01X851995D02*
Y486486D01*
G01X851957D02*
Y487667D01*
G01X850146Y481959D02*
Y461899D01*
G01X849949Y520935D02*
Y556368D01*
G01X831642Y495637D02*
X831725Y495145D01*
G01X869693Y452431D02*
X871012D01*
G01X856839D02*
X854713D01*
G01X874713D02*
X872587D01*
G01X868846Y452234D02*
X871209D01*
G01X872823Y452037D02*
X875972D01*
G01X856602D02*
X853453D01*
G01X870480Y451545D02*
X865815D01*
G01X870579Y451525D02*
X865500D01*
G01X869693Y451447D02*
X870480D01*
G01Y451329D02*
X869693D01*
G01Y451299D02*
X870480D01*
G01X869693Y451275D02*
X870480D01*
G01X869693Y451187D02*
X870480D01*
G01Y451151D02*
X869693D01*
G01Y451128D02*
X870480D01*
G01X865776Y451092D02*
X864713D01*
G01X870480Y451053D02*
X869693D01*
G01X870480Y450974D02*
X869693D01*
G01X871957Y450955D02*
X865894D01*
G01X865697Y450919D02*
X864713D01*
G01X860185Y450856D02*
X867941D01*
G01X865697Y450832D02*
X864713D01*
G01X865697Y450827D02*
X864713D01*
G01Y450777D02*
X865697D01*
G01X875951Y452682D02*
X874876Y452651D01*
G01X875972Y451887D02*
X875185Y451865D01*
G01X873216Y453092D02*
X873332Y453096D01*
G01X873923Y453032D02*
X873807Y453028D01*
G01X855779Y452997D02*
X853474Y452682D01*
G01X854549Y452651D02*
X856854Y452966D01*
G01X873505Y453109D02*
X874756Y453323D01*
G01X873416Y459450D02*
X872519Y459272D01*
G01X873646Y459250D02*
X874543Y459428D01*
G01X874744Y465185D02*
X872476Y464551D01*
G01X873629Y464535D02*
X875897Y465169D01*
G01X862150Y485129D02*
X862291Y486048D01*
G01X862204Y486980D02*
X862063Y486061D01*
G01X847587Y553415D02*
Y523888D01*
G01X847193Y556368D02*
Y520935D01*
G01X840303Y474790D02*
Y511962D01*
G01Y576053D02*
Y511962D01*
G01X835579Y500230D02*
Y499738D01*
G01Y503019D02*
Y502526D01*
G01X834322Y487681D02*
Y487353D01*
G01Y488993D02*
Y488665D01*
G01Y489813D02*
Y489403D01*
G01Y491372D02*
Y491043D01*
G01Y492684D02*
Y492356D01*
G01Y493504D02*
Y493094D01*
G01Y499082D02*
Y497769D01*
G01X875866Y453298D02*
X874615Y453084D01*
G01X879476Y523888D02*
X881839Y529793D01*
G01X833987Y497769D02*
Y499082D01*
G01Y492520D02*
Y492684D01*
G01Y491208D02*
Y491454D01*
G01Y488829D02*
Y488993D01*
G01Y487517D02*
Y487763D01*
G01Y502526D02*
Y500230D01*
G01X833485D02*
Y502526D01*
G01X833317Y499082D02*
Y497769D01*
G01X832982D02*
Y499082D01*
G01X831642Y502526D02*
Y503019D01*
G01Y499738D02*
Y500230D01*
G01Y493094D02*
Y493504D01*
G01Y491782D02*
Y492192D01*
G01Y489403D02*
Y489813D01*
G01Y490469D02*
Y490879D01*
G01Y488091D02*
Y488501D01*
G01Y486778D02*
Y487188D01*
G01X865500Y459399D02*
X864713Y458297D01*
G01Y466171D02*
X865500Y467273D01*
G01X835076Y495227D02*
X835160Y495637D01*
G01X832144Y496047D02*
X832061Y495637D01*
G01X835495Y495145D02*
X835579Y495637D01*
G01X831725Y496129D02*
X831642Y495637D01*
G01X864713Y474045D02*
X865500Y475147D01*
G01X867462Y484747D02*
X868596Y486486D01*
G01X868583Y487667D02*
X867437Y485908D01*
G01X834322Y487353D02*
X834238Y487106D01*
G01X834322Y488665D02*
X834238Y488419D01*
G01X834322Y491043D02*
X834238Y490797D01*
G01X834322Y492356D02*
X834238Y492110D01*
G01X870461Y481762D02*
X871439Y482740D01*
G01X857232Y526613D02*
X856921Y526111D01*
G01X833903Y487353D02*
X833987Y487517D01*
G01X833903Y488665D02*
X833987Y488829D01*
G01X833903Y491043D02*
X833987Y491208D01*
G01X833903Y492356D02*
X833987Y492520D01*
G01X834909Y494980D02*
X835076Y495227D01*
G01X832312Y496293D02*
X832144Y496047D01*
G01X856839Y526867D02*
X856510Y526376D01*
G01X835244Y494734D02*
X835495Y495145D01*
G01X831977Y496539D02*
X831725Y496129D01*
G01X834238Y487106D02*
X834071Y486942D01*
G01X833820Y487270D02*
X833903Y487353D01*
G01X834238Y488419D02*
X833987Y488173D01*
G01X833820Y488583D02*
X833903Y488665D01*
G01X834238Y490797D02*
X834071Y490633D01*
G01X833820Y490961D02*
X833903Y491043D01*
G01X834238Y492110D02*
X833987Y491864D01*
G01X833820Y492274D02*
X833903Y492356D01*
G01X834992Y494488D02*
X835244Y494734D01*
G01X832228Y496785D02*
X831977Y496539D01*
G01X834071Y486942D02*
X833652Y486778D01*
G01Y487188D02*
X833820Y487270D01*
G01X833652Y488501D02*
X833820Y488583D01*
G01X833652Y490879D02*
X833820Y490961D01*
G01X833652Y492192D02*
X833820Y492274D01*
G01X834657Y494324D02*
X834992Y494488D01*
G01X834406Y494652D02*
X834909Y494980D01*
G01X832814Y496621D02*
X832312Y496293D01*
G01X834406Y494242D02*
X834657Y494324D01*
G01X832814Y497031D02*
X832563Y496949D01*
G01X834071Y490633D02*
X833652Y490469D01*
G01X832563Y496949D02*
X832228Y496785D01*
G01X837611Y508227D02*
X831184Y506084D01*
G01X837611Y508227D02*
X831184Y506084D01*
G01X849118Y546546D02*
X848768Y546525D01*
G01X849442Y546607D02*
X849118Y546546D01*
G01X849709Y546705D02*
X849442Y546607D01*
G01X849886Y546834D02*
X849709Y546705D01*
G01X849949Y546980D02*
X849886Y546834D01*
G01X880307Y531741D02*
X880657Y531762D01*
G01X879983Y531680D02*
X880307Y531741D01*
G01X879716Y531582D02*
X879983Y531680D01*
G01X879539Y531453D02*
X879716Y531582D01*
G01X879476Y531307D02*
X879539Y531453D01*
G01X849886Y530469D02*
X849949Y530323D01*
G01X849709Y530597D02*
X849886Y530469D01*
G01X849443Y530696D02*
X849709Y530597D01*
G01X849118Y530757D02*
X849443Y530696D01*
G01X848768Y530777D02*
X849118Y530757D01*
G01X879539Y545850D02*
X879476Y545995D01*
G01X879716Y545721D02*
X879539Y545850D01*
G01X879982Y545623D02*
X879716Y545721D01*
G01X880307Y545562D02*
X879982Y545623D01*
G01X880657Y545541D02*
X880307Y545562D01*
G01X904870Y576053D02*
G03X900933Y579990I-3937J0D01*
G01X869527Y544783D02*
G03X869040Y544951I-486J-620D01*
G01X869962Y544520D02*
G03X868650Y543053I-656J-734D01*
G01X865697Y546919D02*
G03X863728I-984J0D01*
G01X869040Y532352D02*
G03X869527Y532520I1J788D01*
G01X863728Y538455D02*
G03X865697I985J0D01*
G01X860776Y543053D02*
G03X868650I3937J-4402D01*
G01X869527Y532520D02*
G03X872141Y536289I-4815J6130D01*
G01X857284D02*
G03X859898Y532520I7429J2361D01*
G01X872141Y541014D02*
G03X869527Y544782I-7428J-2363D01*
G01X859897D02*
G03X857284Y541014I4816J-6130D01*
G01X859463Y544520D02*
G03X869962I5250J-5869D01*
G01X856053Y536289D02*
G03X859466Y531368I8660J2362D01*
G01X869960D02*
G03X873372Y536289I-5248J7282D01*
G01X859466Y545935D02*
G03X856053Y541014I5247J-7283D01*
G01X873372D02*
G03X869960Y545935I-8660J-2361D01*
G01X855674Y535516D02*
G03X858494Y531381I9039J3135D01*
G01X870931D02*
G03X873751Y535516I-6218J7270D01*
G01Y541787D02*
G03X870931Y545922I-9039J-3135D01*
G01X858494D02*
G03X855674Y541787I6219J-7270D01*
G01X855672Y535404D02*
G03X858436Y531380I9040J3248D01*
G01X870990D02*
G03X873753Y535404I-6277J7271D01*
G01Y541899D02*
G03X870990Y545923I-9041J-3247D01*
G01X858436D02*
G03X855672Y541899I6276J-7272D01*
G01X872587Y550436D02*
G03X856838I-7874J-11785D01*
G01X860385Y544951D02*
G03X859897Y544782I0J-789D01*
G01X860776Y543053D02*
G03X859463Y544520I-657J733D01*
G01X859898Y532520D02*
G03X860385Y532352I486J620D01*
G01X844240Y579990D02*
G03X840303Y576053I0J-3937D01*
G01X874536Y562044D02*
X874829Y561798D01*
G01X874494D02*
X874201Y562044D01*
G01X875834Y559419D02*
X876044Y559255D01*
G01X875290Y558353D02*
X875164Y558435D01*
G01X875750Y559214D02*
X875834Y559173D01*
G01X875080Y558353D02*
X874997Y558394D01*
G01X875625Y559255D02*
X875750Y559214D01*
G01X875667Y559460D02*
X875834Y559419D01*
G01X900933Y579990D02*
X844240D01*
G01X874457Y549970D02*
X875146Y549281D01*
G01X875122Y560608D02*
X875206Y560526D01*
G01X875038D02*
X874955Y560608D01*
G01X874997Y558394D02*
X874913Y558476D01*
G01X879476Y541604D02*
X881839Y540226D01*
G01X874201Y562290D02*
X876169D01*
G01Y562044D02*
X874536D01*
G01X874829Y561798D02*
X874494D01*
G01X875373Y561470D02*
X876169D01*
G01Y561265D02*
X875373D01*
G01X874829Y560526D02*
X875038D01*
G01X875206D02*
X876169D01*
G01Y560321D02*
X874829D01*
G01Y559993D02*
X876169D01*
G01X874201D02*
X874410D01*
G01Y559788D02*
X874201D01*
G01X876169D02*
X874829D01*
G01X875332Y559460D02*
X875667D01*
G01X875373Y559255D02*
X875625D01*
G01X874913Y558476D02*
X874871Y558558D01*
G01X876044Y559255D02*
X876127Y559132D01*
G01X875038Y560731D02*
X875122Y560608D01*
G01X874955D02*
X874871Y560731D01*
G01X875834Y559173D02*
X875918Y559050D01*
G01X875164Y558435D02*
X875080Y558558D01*
G01X874457Y530285D02*
X875146Y529596D01*
G01X849949Y535699D02*
X847587Y537077D01*
G01X874829Y558353D02*
X875080D01*
G01X875918D02*
X876839D01*
G01X875709D02*
X875290D01*
G01X876839Y558148D02*
X874829D01*
G01X882232Y556368D02*
X847193D01*
G01X882232Y553809D02*
X847193D01*
G01X881839Y553415D02*
X847587D01*
G01X877114Y551053D02*
X852311D01*
G01X849949Y550856D02*
X847193D01*
G01X882232D02*
X879476D01*
G01X856051Y550266D02*
X853689D01*
G01X865894D02*
X863531D01*
G01X875736D02*
X873374D01*
G01X856051Y550133D02*
X853689D01*
G01X865894D02*
X863531D01*
G01X875736D02*
X873374D01*
G01X876720Y549970D02*
X852705D01*
G01X856051Y549168D02*
X853689D01*
G01X865894D02*
X863531D01*
G01X875736D02*
X873374D01*
G01X856051Y549137D02*
X853689D01*
G01X865894D02*
X863531D01*
G01X875736D02*
X873374D01*
G01X856051Y549085D02*
X853689D01*
G01X865894D02*
X863531D01*
G01X875736D02*
X873374D01*
G01X856051Y549053D02*
X853689D01*
G01X865894D02*
X863531D01*
G01X875736D02*
X873374D01*
G01X849949Y548592D02*
X847587D01*
G01X849949Y548494D02*
X847587D01*
G01X856051Y548036D02*
X853689D01*
G01X865894D02*
X863531D01*
G01X875736D02*
X873374D01*
G01X856051Y547903D02*
X853689D01*
G01X865894D02*
X863531D01*
G01X875736D02*
X873374D01*
G01X881839Y547608D02*
X879476D01*
G01Y547510D02*
X881839D01*
G01X873965Y547116D02*
X870224D01*
G01X852705Y547018D02*
X876720D01*
G01X847587Y546525D02*
X848768D01*
G01X870224Y546132D02*
X855461D01*
G01X873768Y545935D02*
X855657D01*
G01X880657Y545541D02*
X881839D01*
G01X869040Y544951D02*
X860385D01*
G01X881839Y547510D02*
X879476Y553415D01*
G01X856921Y551192D02*
X857232Y550690D01*
G01X856510Y550927D02*
X856839Y550436D01*
G01X849949Y542982D02*
X847587D01*
G01X881839D02*
X879476D01*
G01X849949Y542785D02*
X847587D01*
G01X881839D02*
X879476D01*
G01X877114Y542392D02*
X879476D01*
G01X849949D02*
X852311D01*
G01X879476Y541604D02*
X849949D01*
G01X855657Y541014D02*
X873768D01*
G01X878295Y540226D02*
X881839D01*
G01X851130D02*
X847587D01*
G01X844535Y539439D02*
X884890D01*
G01X844535Y537864D02*
X884890D01*
G01X878295Y537077D02*
X881839D01*
G01X847587D02*
X851130D01*
G01X873768Y536289D02*
X855657D01*
G01X879476Y535699D02*
X849949D01*
G01X877114Y534911D02*
X879476D01*
G01X852311D02*
X849949D01*
G01Y534518D02*
X847587D01*
G01X881839D02*
X879476D01*
G01X849949Y534321D02*
X847587D01*
G01X881839D02*
X879476D01*
G01X869040Y532352D02*
X860385D01*
G01X880657Y531762D02*
X881839D01*
G01X855657Y531368D02*
X873768D01*
G01X870224Y531171D02*
X855461D01*
G01X847587Y530777D02*
X848768D01*
G01X876720Y530285D02*
X852705D01*
G01X873965Y530187D02*
X870224D01*
G01X881839Y529793D02*
X879476D01*
G01Y529695D02*
X881839D01*
G01X856051Y529399D02*
X853689D01*
G01X865894D02*
X863531D01*
G01X875736D02*
X873374D01*
G01X856051Y529267D02*
X853689D01*
G01X865894D02*
X863531D01*
G01X875736D02*
X873374D01*
G01X849949Y528809D02*
X847587D01*
G01X849949Y528710D02*
X847587D01*
G01X875164Y561429D02*
X875373Y561470D01*
G01Y561265D02*
X875164Y561224D01*
G01Y559419D02*
X875332Y559460D01*
G01X876127Y559132D02*
X876169Y558968D01*
G01X875918Y559050D02*
X875960Y558886D01*
G01X874997Y560895D02*
X875038Y560731D01*
G01X874871D02*
X874829Y560895D01*
G01X875080Y558558D02*
X875038Y558722D01*
G01X874871Y558558D02*
X874829Y558722D01*
G01X856051Y528249D02*
X853689D01*
G01X865894D02*
X863531D01*
G01X875736D02*
X873374D01*
G01X856051Y528218D02*
X853689D01*
G01X865894D02*
X863531D01*
G01X875736D02*
X873374D01*
G01Y528166D02*
X875736D01*
G01X863531D02*
X865894D01*
G01X853689D02*
X856051D01*
G01Y528135D02*
X853689D01*
G01X865894D02*
X863531D01*
G01X875736D02*
X873374D01*
G01X852705Y527333D02*
X876720D01*
G01X856051Y527170D02*
X853689D01*
G01X865894D02*
X863531D01*
G01X875736D02*
X873374D01*
G01Y527037D02*
X875736D01*
G01X863531D02*
X865894D01*
G01X853689D02*
X856051D01*
G01X884890Y539439D02*
Y537864D01*
G01X883905Y539439D02*
Y537864D01*
G01X883709D02*
Y539439D01*
G01X881839Y529793D02*
Y547510D01*
G01Y553415D02*
Y547608D01*
G01X880657Y531762D02*
Y545541D01*
G01X880461Y539439D02*
Y537864D01*
G01X880393D02*
Y539439D01*
G01X879280Y537864D02*
Y539439D01*
G01X878295Y540226D02*
Y537077D01*
G01X877114Y541604D02*
Y553415D01*
G01X876839Y558353D02*
Y558148D01*
G01X876720Y547018D02*
Y549970D01*
G01Y527333D02*
Y530285D01*
G01X876327D02*
Y527333D01*
G01Y549970D02*
Y547018D01*
G01Y553415D02*
Y551053D01*
G01X876169Y559993D02*
Y559788D01*
G01Y558968D02*
Y558722D01*
G01Y560526D02*
Y560321D01*
G01Y561470D02*
Y561265D01*
G01Y562290D02*
Y562044D01*
G01X875960Y558886D02*
Y558722D01*
G01X875736Y547903D02*
Y550266D01*
G01Y529399D02*
Y527037D01*
G01X875146Y529596D02*
Y528022D01*
G01Y549281D02*
Y547707D01*
G01X875038Y558722D02*
Y558968D01*
G01X874829Y560321D02*
Y560526D01*
G01Y560895D02*
Y561059D01*
G01Y559788D02*
Y559993D01*
G01Y558722D02*
Y558968D01*
G01Y558148D02*
Y558353D01*
G01X874410Y559993D02*
Y559788D01*
G01X874201Y562044D02*
Y562290D01*
G01Y559788D02*
Y559993D01*
G01X873965Y529399D02*
Y528218D01*
G01Y547116D02*
Y530187D01*
G01Y549085D02*
Y547903D01*
G01X873768Y531368D02*
Y545935D01*
G01X873374Y547903D02*
Y550266D01*
G01Y529399D02*
Y527037D01*
G01X870224Y531171D02*
Y530187D01*
G01Y547116D02*
Y546132D01*
G01X869437Y532459D02*
Y531368D01*
G01Y545935D02*
Y544843D01*
G01X869043Y550692D02*
Y552147D01*
G01X865894Y547903D02*
Y550266D01*
G01Y529399D02*
Y527037D01*
G01X865697Y546919D02*
Y538455D01*
G01X865303Y547903D02*
Y549085D01*
G01Y528218D02*
Y529399D01*
G01X864122D02*
Y528218D01*
G01Y549085D02*
Y547903D01*
G01X863728Y546919D02*
Y538455D01*
G01X863531Y547903D02*
Y550266D01*
G01Y529399D02*
Y527037D01*
G01X860382Y552147D02*
Y550692D01*
G01X859988Y544843D02*
Y545935D01*
G01Y532459D02*
Y531368D01*
G01X856051Y547903D02*
Y550266D01*
G01Y529399D02*
Y527037D01*
G01X855657Y545935D02*
Y531368D01*
G01X855461Y547903D02*
Y549085D01*
G01Y528218D02*
Y529399D01*
G01Y546132D02*
Y531171D01*
G01X854280Y529399D02*
Y528218D01*
G01Y549085D02*
Y547903D01*
G01X853689D02*
Y550266D01*
G01Y529399D02*
Y527037D01*
G01X853098Y553415D02*
Y551053D01*
G01X852705Y530285D02*
Y527333D01*
G01Y549970D02*
Y547018D01*
G01X852311Y541604D02*
Y553415D01*
G01X851130Y537077D02*
Y540226D01*
G01X850146Y539439D02*
Y537864D01*
G01X849032Y539439D02*
Y537864D01*
G01X848965D02*
Y539439D01*
G01X848768Y530777D02*
Y546525D01*
G01X845717Y539439D02*
Y537864D01*
G01X845520D02*
Y539439D01*
G01X844535Y537864D02*
Y539439D01*
G01X876169Y558722D02*
X876127Y558558D01*
G01X875960Y558722D02*
X875918Y558558D01*
G01X874829Y558968D02*
X874871Y559132D01*
G01X875038Y561059D02*
X874997Y560895D01*
G01X874829Y561059D02*
X874871Y561183D01*
G01X876127Y558558D02*
X876086Y558476D01*
G01X872193Y550690D02*
X872505Y551192D01*
G01X875038Y558968D02*
X875122Y559132D01*
G01X875080Y561142D02*
X875038Y561059D01*
G01X875918Y558558D02*
X875834Y558435D01*
G01X874871Y559132D02*
X874955Y559255D01*
G01X874871Y561183D02*
X874955Y561306D01*
G01X872915Y550927D02*
X872587Y550436D01*
G01X875146Y528022D02*
X874457Y527333D01*
G01X876086Y558476D02*
X876002Y558394D01*
G01X875146Y547707D02*
X874457Y547018D01*
G01X874955Y559255D02*
X875080Y559378D01*
G01X875164Y561224D02*
X875080Y561142D01*
G01X874955Y561306D02*
X875038Y561388D01*
G01X881839Y537077D02*
X879476Y535699D01*
G01X849949Y541604D02*
X847587Y540226D01*
G01X875834Y558435D02*
X875709Y558353D01*
G01X875122Y559132D02*
X875248Y559214D01*
G01X876002Y558394D02*
X875918Y558353D01*
G01X875080Y559378D02*
X875164Y559419D01*
G01X875248Y559214D02*
X875373Y559255D01*
G01X875038Y561388D02*
X875164Y561429D01*
G01X904804Y656388D02*
X907692D01*
G01X903361Y655900D02*
X904804Y656388D01*
G01X902639Y655413D02*
X903361Y655900D01*
G01X901917Y654439D02*
X902639Y655413D01*
G01Y653464D02*
X901917Y654439D01*
G01X903361Y652977D02*
X902639Y653464D01*
G01X904804Y652490D02*
X903361Y652977D01*
G01X907692Y652490D02*
X904804D01*
G01X902639Y624232D02*
X903361Y624719D01*
G01X901917Y623258D02*
X902639Y624232D01*
G01Y622283D02*
X901917Y623258D01*
G01X903361Y621796D02*
X902639Y622283D01*
G01X904804Y621309D02*
X903361Y621796D01*
G01X907692Y621309D02*
X904804D01*
G01X901917Y646644D02*
X910579D01*
G01X901917Y631053D02*
X910579D01*
G01X963320Y229728D02*
X963807Y229006D01*
G01X963320D02*
Y229728D01*
G01X963807Y229006D02*
X963320D01*
G01X956986Y229728D02*
X956012Y229006D01*
G01X957473Y230449D02*
X956986Y229728D01*
G01X957961Y231893D02*
X957473Y230449D01*
G01X957961Y234780D02*
Y231893D01*
G01X957473Y236224D02*
X957961Y234780D01*
G01X956986Y236945D02*
X957473Y236224D01*
G01X956012Y237667D02*
X956986Y236945D01*
G01X955037D02*
X956012Y237667D01*
G01X954550Y236224D02*
X955037Y236945D01*
G01X954063Y234780D02*
X954550Y236224D01*
G01X954063Y231893D02*
Y234780D01*
G01X954550Y230449D02*
X954063Y231893D01*
G01X955037Y229728D02*
X954550Y230449D01*
G01X956012Y229006D02*
X955037Y229728D01*
G01X980372D02*
X979398Y229006D01*
G01X980859Y230449D02*
X980372Y229728D01*
G01X981346Y231893D02*
X980859Y230449D01*
G01Y236224D02*
X981346Y234780D01*
G01X980372Y236945D02*
X980859Y236224D01*
G01X979398Y237667D02*
X980372Y236945D01*
G01X978423D02*
X979398Y237667D01*
G01X977936Y236224D02*
X978423Y236945D01*
G01X977449Y234780D02*
X977936Y236224D01*
G01X977449Y231893D02*
Y234780D01*
G01X977936Y230449D02*
X977449Y231893D01*
G01X978423Y229728D02*
X977936Y230449D01*
G01X979398Y229006D02*
X978423Y229728D01*
G01X970141D02*
X969654Y230449D01*
G01X971115Y229006D02*
X970141Y229728D01*
G01X972090Y229006D02*
X971115D01*
G01X973064Y229728D02*
X972090Y229006D01*
G01X974038Y231171D02*
X973064Y229728D01*
G01X974038Y231893D02*
Y231171D01*
G01X973551Y232615D02*
X974038Y231893D01*
G01X973064Y233336D02*
X973551Y232615D01*
G01X972090Y234058D02*
X973064Y233336D01*
G01Y234780D02*
X972090Y234058D01*
G01X973551Y235502D02*
X973064Y234780D01*
G01X973551Y236224D02*
Y235502D01*
G01X973064Y236945D02*
X973551Y236224D01*
G01X972090Y237667D02*
X973064Y236945D01*
G01X971115Y237667D02*
X972090D01*
G01X970141Y236945D02*
X971115Y237667D01*
G01Y234058D02*
X972090D01*
G01X929145Y371907D02*
X1215260D01*
G01X925995D02*
X929145D01*
G01X960561Y374794D02*
X961048Y374072D01*
G01X960561D02*
Y374794D01*
G01X961048Y374072D02*
X960561D01*
G01X939411Y300073D02*
X938436Y300795D01*
G01X940385Y300073D02*
X939411D01*
G01X941359Y300795D02*
X940385Y300073D01*
G01X941847Y301517D02*
X941359Y300795D01*
G01X941847Y302960D02*
Y301517D01*
G01X941359Y303682D02*
X941847Y302960D01*
G01X940385Y304404D02*
X941359Y303682D01*
G01X939411Y305125D02*
X940385Y304404D01*
G01X938436Y305847D02*
X939411Y305125D01*
G01X937949Y306569D02*
X938436Y305847D01*
G01X937949Y307291D02*
Y306569D01*
G01X938436Y308013D02*
X937949Y307291D01*
G01X939411Y308734D02*
X938436Y308013D01*
G01X940385Y308734D02*
X939411D01*
G01X941359Y308013D02*
X940385Y308734D01*
G01X941847Y307291D02*
X941359Y308013D01*
G01X977613Y374794D02*
X976638Y374072D01*
G01X978100Y375516D02*
X977613Y374794D01*
G01X975664D02*
X975177Y375516D01*
G01X976638Y374072D02*
X975664Y374794D01*
G01X939972D02*
X938528Y376238D01*
G01X942137Y374072D02*
X939972Y374794D01*
G01X944302D02*
X942137Y374072D01*
G01X945746Y376238D02*
X944302Y374794D01*
G01X966894Y374072D02*
X970792D01*
G01X967381Y376238D02*
X966894Y374072D01*
G01X950129Y308734D02*
Y300073D01*
G01X947693Y301517D02*
X950129Y308734D01*
G01X945257D02*
X947693Y301517D01*
G01X945257Y300073D02*
Y308734D01*
G01X952278Y374794D02*
X951791Y375516D01*
G01X953252Y374072D02*
X952278Y374794D01*
G01X954227D02*
X953252Y374072D01*
G01X954714Y375516D02*
X954227Y374794D01*
G01X980823Y308734D02*
Y300073D01*
G01X976925Y308734D02*
Y300073D01*
G01X971079Y308734D02*
Y300073D01*
G01X955488Y308734D02*
Y300073D01*
G01X938528Y371907D02*
X945746Y384899D01*
G01X938436Y300795D02*
X937462Y302238D01*
G01X968643Y308734D02*
X973515D01*
G01X953052D02*
X957924D01*
G01X976925Y304404D02*
X980823D01*
G01X924189D02*
X936000D01*
G01X912744Y435825D02*
Y615029D01*
G01X978587Y376960D02*
X978100Y375516D01*
G01X978587Y379847D02*
Y376960D01*
G01X978100Y381290D02*
X978587Y379847D01*
G01X977613Y382012D02*
X978100Y381290D01*
G01X976638Y382734D02*
X977613Y382012D01*
G01X975664D02*
X976638Y382734D01*
G01X975177Y381290D02*
X975664Y382012D01*
G01X974689Y379847D02*
X975177Y381290D01*
G01X974689Y376960D02*
Y379847D01*
G01X975177Y375516D02*
X974689Y376960D01*
G01X938528Y376238D02*
X937806Y378403D01*
G01X946468D02*
X945746Y376238D01*
G01Y380569D02*
X946468Y378403D01*
G01X944302Y382012D02*
X945746Y380569D01*
G01X942137Y382734D02*
X944302Y382012D01*
G01X939972D02*
X942137Y382734D01*
G01X938528Y380569D02*
X939972Y382012D01*
G01X937806Y378403D02*
X938528Y380569D01*
G01X968356Y377681D02*
X967381Y376238D01*
G01X969330Y378403D02*
X968356Y377681D01*
G01X970305Y379125D02*
X969330Y378403D01*
G01X970792Y379847D02*
X970305Y379125D01*
G01X970792Y381290D02*
Y379847D01*
G01X970305Y382012D02*
X970792Y381290D01*
G01X969330Y382734D02*
X970305Y382012D01*
G01X968356Y382734D02*
X969330D01*
G01X967381Y382012D02*
X968356Y382734D01*
G01X966894Y381290D02*
X967381Y382012D01*
G01X955201Y376960D02*
X954714Y375516D01*
G01X955201Y379847D02*
Y376960D01*
G01X954714Y381290D02*
X955201Y379847D01*
G01X954227Y382012D02*
X954714Y381290D01*
G01X953252Y382734D02*
X954227Y382012D01*
G01X952278D02*
X953252Y382734D01*
G01X951791Y381290D02*
X952278Y382012D01*
G01X951304Y379847D02*
X951791Y381290D01*
G01Y378403D02*
X951304Y379847D01*
G01X953252Y377681D02*
X951791Y378403D01*
G01X954714D02*
X953252Y377681D01*
G01X955201Y379847D02*
X954714Y378403D01*
G01X912744Y431888D02*
G03X910568Y435409I-3937J0D01*
G01Y409611D02*
G03X912744Y413132I-1761J3521D01*
G01X910568Y409611D02*
G03X912744Y413132I-1761J3521D01*
G01Y431888D02*
G03X910568Y435409I-3937J0D01*
G01X910500Y423196D02*
X910416Y423688D01*
G01X906563Y423196D02*
X906647Y422704D01*
G01X910081Y423196D02*
X909997Y423606D01*
G01X906982Y423196D02*
X907066Y422786D01*
G01X909160Y420489D02*
X909243Y420243D01*
G01X908908D02*
X908825Y420489D01*
G01X909160Y419177D02*
X909243Y418931D01*
G01X909160Y416798D02*
X909243Y416552D01*
G01X908908D02*
X908825Y416798D01*
G01X909160Y415486D02*
X909243Y415240D01*
G01X912744Y413132D02*
Y431888D01*
G01Y413132D02*
Y431888D01*
G01X910500Y427789D02*
Y427297D01*
G01Y430578D02*
Y430085D01*
G01X908908Y419013D02*
X908825Y419177D01*
G01X908908Y415322D02*
X908825Y415486D01*
G01X910416Y423688D02*
X910165Y424098D01*
G01X906647Y422704D02*
X906898Y422293D01*
G01X909997Y423606D02*
X909830Y423852D01*
G01X907066Y422786D02*
X907233Y422540D01*
G01X910165Y424098D02*
X909914Y424344D01*
G01X909997Y422786D02*
X910081Y423196D01*
G01X907066Y423606D02*
X906982Y423196D01*
G01X910416Y422704D02*
X910500Y423196D01*
G01X906647Y423688D02*
X906563Y423196D01*
G01X909243Y415240D02*
Y414912D01*
G01Y416552D02*
Y416224D01*
G01Y417372D02*
Y416962D01*
G01Y418931D02*
Y418603D01*
G01Y420243D02*
Y419915D01*
G01Y421063D02*
Y420653D01*
G01Y426641D02*
Y425328D01*
G01X908908D02*
Y426641D01*
G01Y420079D02*
Y420243D01*
G01Y418767D02*
Y419013D01*
G01Y416388D02*
Y416552D01*
G01Y415076D02*
Y415322D01*
G01Y430085D02*
Y427789D01*
G01X908406D02*
Y430085D01*
G01X908238Y426641D02*
Y425328D01*
G01X907903D02*
Y426641D01*
G01X906563Y430085D02*
Y430578D01*
G01Y427297D02*
Y427789D01*
G01Y420653D02*
Y421063D01*
G01Y419341D02*
Y419751D01*
G01Y418028D02*
Y418438D01*
G01Y416962D02*
Y417372D01*
G01Y415650D02*
Y416060D01*
G01Y414337D02*
Y414748D01*
G01X908992Y420653D02*
X909160Y420489D01*
G01X908825D02*
X908657Y420653D01*
G01X906898Y422293D02*
X907149Y422047D01*
G01X908908Y419423D02*
X909160Y419177D01*
G01X908825D02*
X908741Y419259D01*
G01X908992Y416962D02*
X909160Y416798D01*
G01X908825D02*
X908657Y416962D01*
G01X908908Y415732D02*
X909160Y415486D01*
G01X908825D02*
X908741Y415568D01*
G01X909830Y423852D02*
X909327Y424180D01*
G01X907233Y422540D02*
X907736Y422211D01*
G01X907046Y437170D02*
X910568Y435409D01*
G01D02*
X907046Y437170D01*
G01X908825Y414912D02*
X908908Y415076D01*
G01X908825Y416224D02*
X908908Y416388D01*
G01X908825Y418603D02*
X908908Y418767D01*
G01X908825Y419915D02*
X908908Y420079D01*
G01X909243Y414912D02*
X909160Y414666D01*
G01X909243Y416224D02*
X909160Y415978D01*
G01X909243Y418603D02*
X909160Y418356D01*
G01X909243Y419915D02*
X909160Y419669D01*
G01X909914Y424344D02*
X909579Y424508D01*
G01X907149Y422047D02*
X907484Y421883D01*
G01X908741Y419259D02*
X908573Y419341D01*
G01X909830Y422540D02*
X909997Y422786D01*
G01X907233Y423852D02*
X907066Y423606D01*
G01X910165Y422293D02*
X910416Y422704D01*
G01X906898Y424098D02*
X906647Y423688D01*
G01X908741Y415568D02*
X908573Y415650D01*
G01X909579Y424508D02*
X909327Y424590D01*
G01X907484Y421883D02*
X907736Y421801D01*
G01X909160Y414666D02*
X908992Y414501D01*
G01X908741Y414830D02*
X908825Y414912D01*
G01X909160Y415978D02*
X908908Y415732D01*
G01X908741Y416142D02*
X908825Y416224D01*
G01X909160Y418356D02*
X908992Y418192D01*
G01X908741Y418520D02*
X908825Y418603D01*
G01X909160Y419669D02*
X908908Y419423D01*
G01X908741Y419833D02*
X908825Y419915D01*
G01X909914Y422047D02*
X910165Y422293D01*
G01X909327Y424590D02*
X908908Y424672D01*
G01X907736Y421801D02*
X908155Y421719D01*
G01X909327Y424180D02*
X908825Y424262D01*
G01X907736Y422211D02*
X908238Y422129D01*
G01X907149Y424344D02*
X906898Y424098D01*
G01X906563Y430578D02*
X910500D01*
G01X908406Y430085D02*
X906563D01*
G01X910500D02*
X908908D01*
G01Y427789D02*
X910500D01*
G01X906563D02*
X908406D01*
G01X910500Y427297D02*
X906563D01*
G01X907903Y426641D02*
X908238D01*
G01X908908D02*
X909243D01*
G01X908238Y425328D02*
X907903D01*
G01X909243D02*
X908908D01*
G01Y424672D02*
X908155D01*
G01X908825Y424262D02*
X908238D01*
G01Y422129D02*
X908825D01*
G01X910568Y409611D02*
X907046Y407850D01*
G01X910568Y409611D02*
X907046Y407850D01*
G01X909327Y422211D02*
X909830Y422540D01*
G01X907736Y424180D02*
X907233Y423852D01*
G01X908155Y421719D02*
X908908D01*
G01X906563Y421063D02*
X909243D01*
G01X908657Y420653D02*
X906563D01*
G01X909243D02*
X908992D01*
G01X906563Y419751D02*
X908573D01*
G01Y419341D02*
X906563D01*
G01Y418438D02*
X908573D01*
G01Y418028D02*
X906563D01*
G01Y417372D02*
X909243D01*
G01X908657Y416962D02*
X906563D01*
G01X909243D02*
X908992D01*
G01X906563Y416060D02*
X908573D01*
G01Y415650D02*
X906563D01*
G01Y414748D02*
X908573D01*
G01Y414337D02*
X906563D01*
G01X908992Y414501D02*
X908573Y414337D01*
G01X908992Y418192D02*
X908573Y418028D01*
G01Y414748D02*
X908741Y414830D01*
G01X908573Y416060D02*
X908741Y416142D01*
G01X908573Y418438D02*
X908741Y418520D01*
G01X908573Y419751D02*
X908741Y419833D01*
G01X909579Y421883D02*
X909914Y422047D01*
G01X907484Y424508D02*
X907149Y424344D01*
G01X908238Y424262D02*
X907736Y424180D01*
G01X908825Y422129D02*
X909327Y422211D01*
G01X908155Y424672D02*
X907736Y424590D01*
G01X908908Y421719D02*
X909327Y421801D01*
G01D02*
X909579Y421883D01*
G01X907736Y424590D02*
X907484Y424508D01*
G01X909857Y655413D02*
X910579Y654439D01*
G01X909135Y655900D02*
X909857Y655413D01*
G01X907692Y656388D02*
X909135Y655900D01*
G01Y652977D02*
X907692Y652490D01*
G01X909857Y653464D02*
X909135Y652977D01*
G01X910579Y654439D02*
X909857Y653464D01*
G01Y638361D02*
X910579Y638848D01*
G01Y638361D02*
X909857D01*
G01X910579Y638848D02*
Y638361D01*
G01X909135Y621796D02*
X907692Y621309D01*
G01X909857Y622283D02*
X909135Y621796D01*
G01X910579Y623258D02*
X909857Y622283D01*
G01Y624232D02*
X910579Y623258D01*
G01X909135Y624719D02*
X909857Y624232D01*
G01X907692Y625207D02*
X909135Y624719D01*
G01X906248D02*
X907692Y625207D01*
G01X905526Y623258D02*
X906248Y624719D01*
G01Y621796D02*
X905526Y623258D01*
G01X907692Y621309D02*
X906248Y621796D01*
G01X987272Y-354220D02*
Y-371543D01*
G01X981346Y234780D02*
Y231893D01*
G01X1039288Y308734D02*
X1043185D01*
G01X1039288Y300073D02*
Y308734D01*
G01X1043185Y300073D02*
X1039288D01*
G01X1005871Y374072D02*
Y382734D01*
G01X1007819Y374072D02*
X1005871D01*
G01X1008794Y374794D02*
X1007819Y374072D01*
G01X1009281Y375516D02*
X1008794Y374794D01*
G01X1016389Y300795D02*
X1015415Y302238D01*
G01X1017363Y300073D02*
X1016389Y300795D01*
G01X1018338Y300073D02*
X1017363D01*
G01X1019312Y300795D02*
X1018338Y300073D01*
G01X1019799Y301517D02*
X1019312Y300795D01*
G01X1019799Y302960D02*
Y301517D01*
G01X1019312Y303682D02*
X1019799Y302960D01*
G01X1018338Y304404D02*
X1019312Y303682D01*
G01X1017363Y305125D02*
X1018338Y304404D01*
G01X1016389Y305847D02*
X1017363Y305125D01*
G01X1015902Y306569D02*
X1016389Y305847D01*
G01X1015902Y307291D02*
Y306569D01*
G01X1016389Y308013D02*
X1015902Y307291D01*
G01X1017363Y308734D02*
X1016389Y308013D01*
G01X1018338Y308734D02*
X1017363D01*
G01X1019312Y308013D02*
X1018338Y308734D01*
G01X1019799Y307291D02*
X1019312Y308013D01*
G01X983946Y375516D02*
X984921Y374072D01*
G01X1016102Y375516D02*
X1015127Y374072D01*
G01X984721Y301517D02*
Y308734D01*
G01X985208Y300795D02*
X984721Y301517D01*
G01X986182Y300073D02*
X985208Y300795D01*
G01X987157Y300073D02*
X986182D01*
G01X988131Y300795D02*
X987157Y300073D01*
G01X988618Y301517D02*
X988131Y300795D01*
G01X988618Y308734D02*
Y301517D01*
G01X990280Y374072D02*
Y382734D01*
G01X996901Y308734D02*
Y300073D01*
G01X994465Y301517D02*
X996901Y308734D01*
G01X992029D02*
X994465Y301517D01*
G01X992029Y300073D02*
Y308734D01*
G01X999824Y300073D02*
X1003234D01*
G01X999824Y308734D02*
Y300073D01*
G01X1033154Y374072D02*
Y382734D01*
G01X1029256D02*
X1033154Y374072D01*
G01X1029256D02*
Y382734D01*
G01X1033928Y304404D02*
X1031492D01*
G01X1034903Y305125D02*
X1033928Y304404D01*
G01X1035390Y305847D02*
X1034903Y305125D01*
G01X1035390Y307291D02*
Y305847D01*
G01X1034903Y308013D02*
X1035390Y307291D01*
G01X1033928Y308734D02*
X1034903Y308013D01*
G01X1031492Y308734D02*
X1033928D01*
G01X1031492Y300073D02*
Y308734D01*
G01X1000024Y382734D02*
X1002460Y374072D01*
G01X997588D02*
X1000024Y382734D01*
G01X1022923Y375516D02*
X1023897Y374072D01*
G01X1037539Y374794D02*
X1037052Y375516D01*
G01X1038513Y374072D02*
X1037539Y374794D01*
G01X1039488Y374072D02*
X1038513D01*
G01X1040462Y374794D02*
X1039488Y374072D01*
G01X1040949Y375516D02*
X1040462Y374794D01*
G01X1003234Y308734D02*
X999824D01*
G01X1003722Y308013D02*
X1003234Y308734D01*
G01X1003722Y305847D02*
Y308013D01*
G01X1003234Y305125D02*
X1003722Y305847D01*
G01Y304404D02*
X1003234Y305125D01*
G01X1004209Y303682D02*
X1003722Y304404D01*
G01X1004209Y301517D02*
Y303682D01*
G01X1003234Y300073D02*
X1004209Y301517D01*
G01X1023210Y306569D02*
X1024184Y308013D01*
G01X1022723Y304404D02*
X1023210Y306569D01*
G01Y302238D02*
X1022723Y304404D01*
G01X1023697Y301517D02*
X1023210Y302238D01*
G01X1024184Y300795D02*
X1023697Y301517D01*
G01X1025159Y300073D02*
X1024184Y300795D01*
G01X1026133Y300073D02*
X1025159D01*
G01X1027107Y300795D02*
X1026133Y300073D01*
G01X1027595Y301517D02*
X1027107Y300795D01*
G01Y308013D02*
X1027595Y307291D01*
G01X1026133Y308734D02*
X1027107Y308013D01*
G01X1025159Y308734D02*
X1026133D01*
G01X1024184Y308013D02*
X1025159Y308734D01*
G01X1050493Y300073D02*
X1051955Y308734D01*
G01X1049032D02*
X1050493Y300073D01*
G01X1047570D02*
X1049032Y308734D01*
G01X1046108D02*
X1047570Y300073D01*
G01X1033928Y304404D02*
X1035390Y300073D01*
G01X1054591Y382734D02*
Y374072D01*
G01X999824Y305125D02*
X1003234D01*
G01X1039288Y304404D02*
X1041724D01*
G01X1009768Y376238D02*
X1009281Y375516D01*
G01X1010255Y378403D02*
X1009768Y376238D01*
G01Y380569D02*
X1010255Y378403D01*
G01X1009281Y381290D02*
X1009768Y380569D01*
G01X1008794Y382012D02*
X1009281Y381290D01*
G01X1007819Y382734D02*
X1008794Y382012D01*
G01X1005871Y382734D02*
X1007819D01*
G01X983459Y377681D02*
X983946Y375516D01*
G01X983459Y379125D02*
Y377681D01*
G01X983946Y381290D02*
X983459Y379125D01*
G01X984921Y382734D02*
X983946Y381290D01*
G01X1016589Y377681D02*
X1016102Y375516D01*
G01X1016589Y379125D02*
Y377681D01*
G01X1016102Y381290D02*
X1016589Y379125D01*
G01X1015127Y382734D02*
X1016102Y381290D01*
G01X992716Y378403D02*
X990280D01*
G01X993690Y379125D02*
X992716Y378403D01*
G01X994178Y379847D02*
X993690Y379125D01*
G01X994178Y381290D02*
Y379847D01*
G01X993690Y382012D02*
X994178Y381290D01*
G01X992716Y382734D02*
X993690Y382012D01*
G01X990280Y382734D02*
X992716D01*
G01X1022436Y377681D02*
X1022923Y375516D01*
G01X1022436Y379125D02*
Y377681D01*
G01X1022923Y381290D02*
X1022436Y379125D01*
G01X1023897Y382734D02*
X1022923Y381290D01*
G01X1041437Y376238D02*
X1040949Y375516D01*
G01X1041924Y378403D02*
X1041437Y376238D01*
G01Y380569D02*
X1041924Y378403D01*
G01X1040949Y381290D02*
X1041437Y380569D01*
G01X1040462Y382012D02*
X1040949Y381290D01*
G01X1039488Y382734D02*
X1040462Y382012D01*
G01X1038513Y382734D02*
X1039488D01*
G01X1037539Y382012D02*
X1038513Y382734D01*
G01X1037052Y381290D02*
X1037539Y382012D01*
G01X1036564Y380569D02*
X1037052Y381290D01*
G01X1036077Y378403D02*
X1036564Y380569D01*
G01Y376238D02*
X1036077Y378403D01*
G01X1037052Y375516D02*
X1036564Y376238D01*
G01X1052155Y382734D02*
X1057027D01*
G01X998562Y376960D02*
X1001486D01*
G01X987272Y1006410D02*
Y989087D01*
G01X1214864Y271359D02*
X1108039D01*
G01X1117423Y275690D02*
X1116701Y277855D01*
G01X1118866Y274246D02*
X1117423Y275690D01*
G01X1121031Y273524D02*
X1118866Y274246D01*
G01X1123197D02*
X1121031Y273524D01*
G01X1124640Y275690D02*
X1123197Y274246D01*
G01X1125362Y277855D02*
X1124640Y275690D01*
G01Y280020D02*
X1125362Y277855D01*
G01X1123197Y281464D02*
X1124640Y280020D01*
G01X1121031Y282186D02*
X1123197Y281464D01*
G01X1118866D02*
X1121031Y282186D01*
G01X1117423Y280020D02*
X1118866Y281464D01*
G01X1116701Y277855D02*
X1117423Y280020D01*
G01Y271359D02*
X1124640Y284351D01*
G01X1132147Y282186D02*
Y273524D01*
G01X1095316Y300795D02*
X1095803Y300073D01*
G01X1095316D02*
Y300795D01*
G01X1095803Y300073D02*
X1095316D01*
G01X1083823Y374072D02*
Y382734D01*
G01X1087721Y374072D02*
X1083823D01*
G01X1073392Y300795D02*
X1072417Y300073D01*
G01X1073879Y301517D02*
X1073392Y300795D01*
G01X1074366Y302960D02*
X1073879Y301517D01*
G01X1074366Y305847D02*
Y302960D01*
G01X1073879Y307291D02*
X1074366Y305847D01*
G01X1073392Y308013D02*
X1073879Y307291D01*
G01X1072417Y308734D02*
X1073392Y308013D01*
G01X1071443D02*
X1072417Y308734D01*
G01X1070956Y307291D02*
X1071443Y308013D01*
G01X1070469Y305847D02*
X1070956Y307291D01*
G01X1070469Y302960D02*
Y305847D01*
G01X1070956Y301517D02*
X1070469Y302960D01*
G01X1071443Y300795D02*
X1070956Y301517D01*
G01X1072417Y300073D02*
X1071443Y300795D01*
G01X1077777Y302238D02*
Y302960D01*
G01X1078264Y301517D02*
X1077777Y302238D01*
G01X1078751Y300795D02*
X1078264Y301517D01*
G01X1079726Y300073D02*
X1078751Y300795D01*
G01X1081674Y305847D02*
X1080700Y305125D01*
G01X1082162Y306569D02*
X1081674Y305847D01*
G01X1082162Y307291D02*
Y306569D01*
G01X1081674Y308013D02*
X1082162Y307291D01*
G01X1080700Y308734D02*
X1081674Y308013D01*
G01X1079726Y308734D02*
X1080700D01*
G01X1078751Y308013D02*
X1079726Y308734D01*
G01X1078264Y307291D02*
X1078751Y308013D01*
G01X1078264Y306569D02*
Y307291D01*
G01X1078751Y305847D02*
X1078264Y306569D01*
G01X1079726Y305125D02*
X1078751Y305847D01*
G01X1060437Y374072D02*
Y382734D01*
G01X1130595Y374072D02*
X1134493D01*
G01X1130595Y382734D02*
Y374072D01*
G01X1070182Y382734D02*
X1072618Y374072D01*
G01X1067746D02*
X1070182Y382734D01*
G01X1101363D02*
X1103799Y374072D01*
G01X1098927D02*
X1101363Y382734D01*
G01X1124749D02*
X1127185Y374072D01*
G01X1122312D02*
X1124749Y382734D01*
G01X1111394Y308734D02*
X1113830Y300073D01*
G01X1108958D02*
X1111394Y308734D01*
G01X1088982Y308013D02*
X1089470Y307291D01*
G01X1088008Y308734D02*
X1088982Y308013D01*
G01X1087034D02*
X1088008Y308734D01*
G01X1086546Y307291D02*
X1087034Y308013D01*
G01X1086059Y305847D02*
X1086546Y307291D01*
G01X1086059Y302960D02*
Y305847D01*
G01X1086546Y301517D02*
X1086059Y302960D01*
G01X1087034Y300795D02*
X1086546Y301517D01*
G01X1088008Y300073D02*
X1087034Y300795D01*
G01X1088982D02*
X1088008Y300073D01*
G01X1089470Y301517D02*
X1088982Y300795D01*
G01X1089957Y302960D02*
X1089470Y301517D01*
G01Y304404D02*
X1089957Y302960D01*
G01X1088008Y305125D02*
X1089470Y304404D01*
G01X1086546D02*
X1088008Y305125D01*
G01X1086059Y302960D02*
X1086546Y304404D01*
G01X1077490Y374072D02*
X1076515Y374794D01*
G01X1078464Y374072D02*
X1077490D01*
G01X1079438Y374794D02*
X1078464Y374072D01*
G01X1079926Y375516D02*
X1079438Y374794D01*
G01X1064135Y301517D02*
X1065109Y300073D01*
G01X1063648Y303682D02*
X1064135Y301517D01*
G01X1063648Y305125D02*
Y303682D01*
G01X1064135Y307291D02*
X1063648Y305125D01*
G01X1065109Y308734D02*
X1064135Y307291D01*
G01X1082649Y302960D02*
Y302238D01*
G01X1082162Y303682D02*
X1082649Y302960D01*
G01X1081674Y304404D02*
X1082162Y303682D01*
G01X1080700Y305125D02*
X1081674Y304404D01*
G01X1079726Y305125D02*
X1080700D01*
G01X1078751Y304404D02*
X1079726Y305125D01*
G01X1077777Y302960D02*
X1078751Y304404D01*
G01X1080700Y300073D02*
X1079726D01*
G01X1081674Y300795D02*
X1080700Y300073D01*
G01X1082649Y302238D02*
X1081674Y300795D01*
G01X1105547Y305847D02*
X1105060Y305125D01*
G01X1105547Y307291D02*
Y305847D01*
G01X1105060Y308013D02*
X1105547Y307291D01*
G01X1104086Y308734D02*
X1105060Y308013D01*
G01X1103111Y308734D02*
X1104086D01*
G01X1102137Y308013D02*
X1103111Y308734D01*
G01X1101650Y307291D02*
X1102137Y308013D01*
G01X1125036Y300073D02*
X1128933D01*
G01X1125523Y302238D02*
X1125036Y300073D01*
G01X1126497Y303682D02*
X1125523Y302238D01*
G01X1127472Y304404D02*
X1126497Y303682D01*
G01X1128446Y305125D02*
X1127472Y304404D01*
G01X1128933Y305847D02*
X1128446Y305125D01*
G01X1128933Y307291D02*
Y305847D01*
G01X1128446Y308013D02*
X1128933Y307291D01*
G01X1127472Y308734D02*
X1128446Y308013D01*
G01X1126497Y308734D02*
X1127472D01*
G01X1125523Y308013D02*
X1126497Y308734D01*
G01X1125036Y307291D02*
X1125523Y308013D01*
G01X1101650Y300073D02*
X1105547D01*
G01X1102137Y302238D02*
X1101650Y300073D01*
G01X1103111Y303682D02*
X1102137Y302238D01*
G01X1105060Y305125D02*
X1103111Y303682D01*
G01X1076515Y374794D02*
X1075541Y376238D01*
G01X1062874Y378403D02*
X1064335Y374072D01*
G01X1119189Y308734D02*
Y300073D01*
G01X1109158Y382734D02*
Y374072D01*
G01X1116753Y308734D02*
X1121625D01*
G01X1109932Y302960D02*
X1112855D01*
G01X1083823Y382734D02*
X1087721D01*
G01X1079438Y382012D02*
X1079926Y381290D01*
G01X1078464Y382734D02*
X1079438Y382012D01*
G01X1077490Y382734D02*
X1078464D01*
G01X1076515Y382012D02*
X1077490Y382734D01*
G01X1062874Y378403D02*
X1060437D01*
G01X1063848Y379125D02*
X1062874Y378403D01*
G01X1064335Y379847D02*
X1063848Y379125D01*
G01X1064335Y381290D02*
Y379847D01*
G01X1063848Y382012D02*
X1064335Y381290D01*
G01X1062874Y382734D02*
X1063848Y382012D01*
G01X1060437Y382734D02*
X1062874D01*
G01X1075541Y380569D02*
X1076515Y382012D01*
G01X1075054Y378403D02*
X1075541Y380569D01*
G01Y376238D02*
X1075054Y378403D01*
G01X1106722Y382734D02*
X1111594D01*
G01X1083823Y378403D02*
X1086259D01*
G01X1123287Y376960D02*
X1126210D01*
G01X1099901D02*
X1102824D01*
G01X1068720D02*
X1071643D01*
G01X1160500Y-354220D02*
Y-371543D01*
G01X1173347Y-187764D02*
Y-277893D01*
G01X1177015Y-233082D02*
X1719319D01*
G01X1224923Y214460D02*
X1175846D01*
G01X1168592Y217347D02*
X1167617Y216625D01*
G01X1169079Y218069D02*
X1168592Y217347D01*
G01X1169566Y219512D02*
X1169079Y218069D01*
G01X1169566Y222400D02*
Y219512D01*
G01X1169079Y223843D02*
X1169566Y222400D01*
G01X1165669D02*
X1166156Y223843D01*
G01X1165669Y219512D02*
Y222400D01*
G01X1166156Y218069D02*
X1165669Y219512D01*
G01X1166643Y217347D02*
X1166156Y218069D01*
G01X1167617Y216625D02*
X1166643Y217347D01*
G01X1151540D02*
X1152027Y216625D01*
G01X1151540D02*
Y217347D01*
G01X1152027Y216625D02*
X1151540D01*
G01X1160309Y220234D02*
X1160797Y222400D01*
G01X1159822Y216625D02*
X1160309Y220234D01*
G01X1142283Y222400D02*
X1142770Y223843D01*
G01X1142283Y219512D02*
Y222400D01*
G01X1142770Y218069D02*
X1142283Y219512D01*
G01X1143257Y217347D02*
X1142770Y218069D01*
G01X1144232Y216625D02*
X1143257Y217347D01*
G01X1145206D02*
X1144232Y216625D01*
G01X1145693Y218069D02*
X1145206Y217347D01*
G01X1146180Y219512D02*
X1145693Y218069D01*
G01Y220956D02*
X1146180Y219512D01*
G01X1144232Y221678D02*
X1145693Y220956D01*
G01X1142770D02*
X1144232Y221678D01*
G01X1142283Y219512D02*
X1142770Y220956D01*
G01X1160797Y222400D02*
X1161771Y225287D01*
G01X1252030Y240838D02*
X1175846D01*
G01X1168592Y224565D02*
X1169079Y223843D01*
G01X1167617Y225287D02*
X1168592Y224565D01*
G01X1166643D02*
X1167617Y225287D01*
G01X1166156Y223843D02*
X1166643Y224565D01*
G01X1145206Y243725D02*
X1144232Y243003D01*
G01X1145693Y244447D02*
X1145206Y243725D01*
G01X1146180Y245890D02*
X1145693Y244447D01*
G01X1146180Y248778D02*
Y245890D01*
G01X1145693Y250221D02*
X1146180Y248778D01*
G01X1145206Y250943D02*
X1145693Y250221D01*
G01X1144232Y251665D02*
X1145206Y250943D01*
G01X1143257D02*
X1144232Y251665D01*
G01X1142770Y250221D02*
X1143257Y250943D01*
G01X1142283Y248778D02*
X1142770Y250221D01*
G01X1142283Y245890D02*
Y248778D01*
G01X1142770Y244447D02*
X1142283Y245890D01*
G01X1143257Y243725D02*
X1142770Y244447D01*
G01X1144232Y243003D02*
X1143257Y243725D01*
G01X1160797D02*
X1159822Y243003D01*
G01X1161284Y244447D02*
X1160797Y243725D01*
G01X1161771Y245890D02*
X1161284Y244447D01*
G01X1161771Y248778D02*
Y245890D01*
G01X1161284Y250221D02*
X1161771Y248778D01*
G01X1160797Y250943D02*
X1161284Y250221D01*
G01X1159822Y251665D02*
X1160797Y250943D01*
G01X1158848D02*
X1159822Y251665D01*
G01X1158361Y250221D02*
X1158848Y250943D01*
G01X1157873Y248778D02*
X1158361Y250221D01*
G01X1157873Y245890D02*
Y248778D01*
G01X1158361Y244447D02*
X1157873Y245890D01*
G01X1158848Y243725D02*
X1158361Y244447D01*
G01X1159822Y243003D02*
X1158848Y243725D01*
G01X1168592D02*
X1167617Y243003D01*
G01X1169079Y244447D02*
X1168592Y243725D01*
G01X1169566Y245890D02*
X1169079Y244447D01*
G01X1169566Y248778D02*
Y245890D01*
G01X1169079Y250221D02*
X1169566Y248778D01*
G01X1168592Y250943D02*
X1169079Y250221D01*
G01X1167617Y251665D02*
X1168592Y250943D01*
G01X1166643D02*
X1167617Y251665D01*
G01X1166156Y250221D02*
X1166643Y250943D01*
G01X1165669Y248778D02*
X1166156Y250221D01*
G01X1165669Y245890D02*
Y248778D01*
G01X1166156Y244447D02*
X1165669Y245890D01*
G01X1166643Y243725D02*
X1166156Y244447D01*
G01X1167617Y243003D02*
X1166643Y243725D01*
G01X1150174Y276411D02*
Y275690D01*
G01X1149199Y277855D02*
X1150174Y276411D01*
G01X1202792Y274968D02*
X1201817Y273524D01*
G01X1203279Y277133D02*
X1202792Y274968D01*
G01X1203279Y278577D02*
Y277133D01*
G01X1202792Y280742D02*
X1203279Y278577D01*
G01X1201817Y282186D02*
X1202792Y280742D01*
G01X1173072Y273524D02*
Y282186D01*
G01X1169175D02*
X1173072Y273524D01*
G01X1169175D02*
Y282186D01*
G01X1179406Y277855D02*
X1176970D01*
G01X1180380Y278577D02*
X1179406Y277855D01*
G01X1180867Y279299D02*
X1180380Y278577D01*
G01X1180867Y280742D02*
Y279299D01*
G01X1180380Y281464D02*
X1180867Y280742D01*
G01X1179406Y282186D02*
X1180380Y281464D01*
G01X1176970Y282186D02*
X1179406D01*
G01X1176970Y273524D02*
Y282186D01*
G01X1151540Y243725D02*
X1152027Y243003D01*
G01X1151540D02*
Y243725D01*
G01X1152027Y243003D02*
X1151540D01*
G01X1145206Y224565D02*
X1145693Y223843D01*
G01X1144232Y225287D02*
X1145206Y224565D01*
G01X1143257D02*
X1144232Y225287D01*
G01X1142770Y223843D02*
X1143257Y224565D01*
G01X1139455Y274246D02*
X1139942Y273524D01*
G01X1139455D02*
Y274246D01*
G01X1139942Y273524D02*
X1139455D01*
G01X1154071Y274246D02*
X1153584Y274968D01*
G01X1155046Y273524D02*
X1154071Y274246D01*
G01X1156020Y273524D02*
X1155046D01*
G01X1156994Y274246D02*
X1156020Y273524D01*
G01X1157482Y274968D02*
X1156994Y274246D01*
G01X1157969Y276411D02*
X1157482Y274968D01*
G01Y277855D02*
X1157969Y276411D01*
G01X1156994Y278577D02*
X1157482Y277855D01*
G01X1156020Y279299D02*
X1156994Y278577D01*
G01X1155046Y279299D02*
X1156020D01*
G01X1154071Y278577D02*
X1155046Y279299D01*
G01X1154558Y282186D02*
X1154071Y278577D01*
G01X1157482Y282186D02*
X1154558D01*
G01X1161771Y225287D02*
X1157873D01*
G01X1146276Y274246D02*
X1145789Y274968D01*
G01X1147250Y273524D02*
X1146276Y274246D01*
G01X1148225Y273524D02*
X1147250D01*
G01X1149199Y274246D02*
X1148225Y273524D01*
G01X1150174Y275690D02*
X1149199Y274246D01*
G01X1162841Y274968D02*
X1163815Y273524D01*
G01X1162354Y277133D02*
X1162841Y274968D01*
G01X1162354Y278577D02*
Y277133D01*
G01X1162841Y280742D02*
X1162354Y278577D01*
G01X1163815Y282186D02*
X1162841Y280742D01*
G01X1148225Y278577D02*
X1149199Y277855D01*
G01Y279299D02*
X1148225Y278577D01*
G01X1149686Y280020D02*
X1149199Y279299D01*
G01X1149686Y280742D02*
Y280020D01*
G01X1149199Y281464D02*
X1149686Y280742D01*
G01X1148225Y282186D02*
X1149199Y281464D01*
G01X1147250Y282186D02*
X1148225D01*
G01X1146276Y281464D02*
X1147250Y282186D01*
G01X1184278D02*
X1189150D01*
G01X1147250Y278577D02*
X1148225D01*
G01X1192560Y277855D02*
X1196458D01*
G01Y282186D02*
Y273524D01*
G01X1192560Y282186D02*
Y273524D01*
G01X1186714Y282186D02*
Y273524D01*
G01X1142088Y300795D02*
X1142575Y300073D01*
G01X1142088D02*
Y300795D01*
G01X1142575Y300073D02*
X1142088D01*
G01X1177367Y374072D02*
Y382734D01*
G01X1181264Y374072D02*
X1177367D01*
G01X1151345Y300795D02*
X1150370Y300073D01*
G01X1151832Y301517D02*
X1151345Y300795D01*
G01X1152319Y302960D02*
X1151832Y301517D01*
G01X1152319Y305847D02*
Y302960D01*
G01X1151832Y307291D02*
X1152319Y305847D01*
G01X1151345Y308013D02*
X1151832Y307291D01*
G01X1150370Y308734D02*
X1151345Y308013D01*
G01X1149396D02*
X1150370Y308734D01*
G01X1148909Y307291D02*
X1149396Y308013D01*
G01X1148421Y305847D02*
X1148909Y307291D01*
G01X1148421Y302960D02*
Y305847D01*
G01X1148909Y301517D02*
X1148421Y302960D01*
G01X1149396Y300795D02*
X1148909Y301517D01*
G01X1150370Y300073D02*
X1149396Y300795D01*
G01X1132831Y302238D02*
X1137216D01*
G01X1136241Y308734D02*
X1132831Y302238D01*
G01X1136241Y300073D02*
Y308734D01*
G01X1138390Y374072D02*
X1142288D01*
G01X1138390Y382734D02*
Y374072D01*
G01X1153981D02*
X1157878D01*
G01X1153981Y382734D02*
Y374072D01*
G01X1156217Y302238D02*
X1160602D01*
G01X1159627Y308734D02*
X1156217Y302238D01*
G01X1159627Y300073D02*
Y308734D01*
G01X1166448Y304404D02*
X1164012D01*
G01X1167422Y305125D02*
X1166448Y304404D01*
G01X1167910Y305847D02*
X1167422Y305125D01*
G01X1167910Y307291D02*
Y305847D01*
G01X1167422Y308013D02*
X1167910Y307291D01*
G01X1166448Y308734D02*
X1167422Y308013D01*
G01X1164012Y308734D02*
X1166448D01*
G01X1164012Y300073D02*
Y308734D01*
G01X1185162Y374072D02*
Y382734D01*
G01X1163725D02*
X1166161Y374072D01*
G01X1161289D02*
X1163725Y382734D01*
G01X1174730Y308013D02*
X1175218Y307291D01*
G01X1173756Y308734D02*
X1174730Y308013D01*
G01X1172782D02*
X1173756Y308734D01*
G01X1172294Y307291D02*
X1172782Y308013D01*
G01X1171807Y305847D02*
X1172294Y307291D01*
G01X1171807Y302960D02*
Y305847D01*
G01X1172294Y301517D02*
X1171807Y302960D01*
G01X1172782Y300795D02*
X1172294Y301517D01*
G01X1173756Y300073D02*
X1172782Y300795D01*
G01X1174730D02*
X1173756Y300073D01*
G01X1175218Y301517D02*
X1174730Y300795D01*
G01X1175705Y302960D02*
X1175218Y301517D01*
G01Y304404D02*
X1175705Y302960D01*
G01X1173756Y305125D02*
X1175218Y304404D01*
G01X1172294D02*
X1173756Y305125D01*
G01X1171807Y302960D02*
X1172294Y304404D01*
G01X1182039Y301517D02*
X1181064Y300073D01*
G01X1182526Y303682D02*
X1182039Y301517D01*
G01X1182526Y305125D02*
Y303682D01*
G01X1182039Y307291D02*
X1182526Y305125D01*
G01X1181064Y308734D02*
X1182039Y307291D01*
G01X1203189Y375516D02*
X1202214Y374072D01*
G01X1193444Y374794D02*
X1192957Y375516D01*
G01X1194419Y374072D02*
X1193444Y374794D01*
G01X1195393Y374072D02*
X1194419D01*
G01X1196368Y374794D02*
X1195393Y374072D01*
G01X1196855Y375516D02*
X1196368Y374794D01*
G01X1171520Y378403D02*
Y374072D01*
G01X1187598Y378403D02*
X1189060Y374072D01*
G01X1166448Y304404D02*
X1167910Y300073D01*
G01X1177367Y382734D02*
X1181264D01*
G01X1187598Y378403D02*
X1185162D01*
G01X1188572Y379125D02*
X1187598Y378403D01*
G01X1189060Y379847D02*
X1188572Y379125D01*
G01X1189060Y381290D02*
Y379847D01*
G01X1188572Y382012D02*
X1189060Y381290D01*
G01X1187598Y382734D02*
X1188572Y382012D01*
G01X1185162Y382734D02*
X1187598D01*
G01X1203676Y377681D02*
X1203189Y375516D01*
G01X1203676Y379125D02*
Y377681D01*
G01X1203189Y381290D02*
X1203676Y379125D01*
G01X1202214Y382734D02*
X1203189Y381290D01*
G01X1192957Y375516D02*
X1192470Y376238D01*
G01X1196855Y376960D02*
Y375516D01*
G01X1196368Y377681D02*
X1196855Y376960D01*
G01X1195393Y378403D02*
X1196368Y377681D01*
G01X1194419Y379125D02*
X1195393Y378403D01*
G01X1193444Y379847D02*
X1194419Y379125D01*
G01X1192957Y380569D02*
X1193444Y379847D01*
G01X1192957Y381290D02*
Y380569D01*
G01X1193444Y382012D02*
X1192957Y381290D01*
G01X1194419Y382734D02*
X1193444Y382012D01*
G01X1195393Y382734D02*
X1194419D01*
G01X1196368Y382012D02*
X1195393Y382734D01*
G01X1196855Y381290D02*
X1196368Y382012D01*
G01X1169571Y382734D02*
X1171520Y378403D01*
G01D02*
X1173469Y382734D01*
G01X1177367Y378403D02*
X1179803D01*
G01X1162263Y376960D02*
X1165186D01*
G01X1160500Y1006410D02*
Y989087D01*
G01X1282234Y142392D02*
X1283209Y143835D01*
G01X1281747Y140226D02*
X1282234Y142392D01*
G01Y138061D02*
X1281747Y140226D01*
G01X1282722Y137339D02*
X1282234Y138061D01*
G01X1283209Y136617D02*
X1282722Y137339D01*
G01X1284183Y135896D02*
X1283209Y136617D01*
G01Y143835D02*
X1284183Y144557D01*
G01X1276388Y135896D02*
X1275414Y136617D01*
G01X1277362Y135896D02*
X1276388D01*
G01X1278337Y136617D02*
X1277362Y135896D01*
G01X1278824Y137339D02*
X1278337Y136617D01*
G01X1278824Y138783D02*
Y137339D01*
G01X1278337Y139504D02*
X1278824Y138783D01*
G01X1277362Y140226D02*
X1278337Y139504D01*
G01X1276388Y140948D02*
X1277362Y140226D01*
G01X1275414Y141670D02*
X1276388Y140948D01*
G01X1274926Y142392D02*
X1275414Y141670D01*
G01X1274926Y143113D02*
Y142392D01*
G01X1275414Y143835D02*
X1274926Y143113D01*
G01X1276388Y144557D02*
X1275414Y143835D01*
G01X1277362Y144557D02*
X1276388D01*
G01X1278337Y143835D02*
X1277362Y144557D01*
G01X1278824Y143113D02*
X1278337Y143835D01*
G01X1222036Y148781D02*
X1222758Y147806D01*
G01X1214097D02*
X1214818Y148781D01*
G01Y146832D02*
X1214097Y147806D01*
G01X1215540Y146345D02*
X1214818Y146832D01*
G01X1216984Y145858D02*
X1215540Y146345D01*
G01X1219871Y145858D02*
X1216984D01*
G01X1221314Y146345D02*
X1219871Y145858D01*
G01X1222036Y146832D02*
X1221314Y146345D01*
G01X1222758Y147806D02*
X1222036Y146832D01*
G01X1263769Y148781D02*
X1264490Y147806D01*
G01X1255829D02*
X1256551Y148781D01*
G01Y146832D02*
X1255829Y147806D01*
G01X1257272Y146345D02*
X1256551Y146832D01*
G01X1258716Y145858D02*
X1257272Y146345D01*
G01X1261603Y145858D02*
X1258716D01*
G01X1263047Y146345D02*
X1261603Y145858D01*
G01X1263769Y146832D02*
X1263047Y146345D01*
G01X1264490Y147806D02*
X1263769Y146832D01*
G01X1255829Y140011D02*
X1264490D01*
G01X1275414Y136617D02*
X1274439Y138061D01*
G01X1224923Y214460D02*
Y179421D01*
G01X1266656Y242019D02*
Y179421D01*
G01X1256551Y164371D02*
X1257272Y164859D01*
G01X1255829Y163397D02*
X1256551Y164371D01*
G01Y162423D02*
X1255829Y163397D01*
G01X1257272Y161935D02*
X1256551Y162423D01*
G01X1258716Y161448D02*
X1257272Y161935D01*
G01X1261603Y161448D02*
X1258716D01*
G01X1263047Y161935D02*
X1261603Y161448D01*
G01X1263769Y162423D02*
X1263047Y161935D01*
G01X1264490Y163397D02*
X1263769Y162423D01*
G01Y164371D02*
X1264490Y163397D01*
G01X1263047Y164859D02*
X1263769Y164371D01*
G01X1261603Y165346D02*
X1263047Y164859D01*
G01X1260160D02*
X1261603Y165346D01*
G01X1259438Y163397D02*
X1260160Y164859D01*
G01Y161935D02*
X1259438Y163397D01*
G01X1261603Y161448D02*
X1260160Y161935D01*
G01X1222036Y155114D02*
X1222758Y155602D01*
G01Y155114D02*
X1222036D01*
G01X1222758Y155602D02*
Y155114D01*
G01X1263769D02*
X1264490Y155602D01*
G01Y155114D02*
X1263769D01*
G01X1264490Y155602D02*
Y155114D01*
G01X1222036Y172167D02*
X1222758Y171192D01*
G01X1221314Y172654D02*
X1222036Y172167D01*
G01X1219871Y173141D02*
X1221314Y172654D01*
G01X1216984Y173141D02*
X1219871D01*
G01X1215540Y172654D02*
X1216984Y173141D01*
G01X1214818Y172167D02*
X1215540Y172654D01*
G01X1214097Y171192D02*
X1214818Y172167D01*
G01Y170218D02*
X1214097Y171192D01*
G01X1215540Y169731D02*
X1214818Y170218D01*
G01X1216984Y169243D02*
X1215540Y169731D01*
G01X1219871Y169243D02*
X1216984D01*
G01X1221314Y169731D02*
X1219871Y169243D01*
G01X1222036Y170218D02*
X1221314Y169731D01*
G01X1222758Y171192D02*
X1222036Y170218D01*
G01Y164371D02*
X1222758Y163397D01*
G01X1221314Y164859D02*
X1222036Y164371D01*
G01X1219871Y165346D02*
X1221314Y164859D01*
G01X1216984Y165346D02*
X1219871D01*
G01X1215540Y164859D02*
X1216984Y165346D01*
G01X1214818Y164371D02*
X1215540Y164859D01*
G01X1214097Y163397D02*
X1214818Y164371D01*
G01Y162423D02*
X1214097Y163397D01*
G01X1215540Y161935D02*
X1214818Y162423D01*
G01X1216984Y161448D02*
X1215540Y161935D01*
G01X1219871Y161448D02*
X1216984D01*
G01X1221314Y161935D02*
X1219871Y161448D01*
G01X1222036Y162423D02*
X1221314Y161935D01*
G01X1222758Y163397D02*
X1222036Y162423D01*
G01X1221314Y149268D02*
X1222036Y148781D01*
G01X1219871Y149755D02*
X1221314Y149268D01*
G01X1216984Y149755D02*
X1219871D01*
G01X1215540Y149268D02*
X1216984Y149755D01*
G01X1214818Y148781D02*
X1215540Y149268D01*
G01X1263769Y172167D02*
X1264490Y171192D01*
G01X1263047Y172654D02*
X1263769Y172167D01*
G01X1261603Y173141D02*
X1263047Y172654D01*
G01X1258716Y173141D02*
X1261603D01*
G01X1257272Y172654D02*
X1258716Y173141D01*
G01X1256551Y172167D02*
X1257272Y172654D01*
G01X1255829Y171192D02*
X1256551Y172167D01*
G01Y170218D02*
X1255829Y171192D01*
G01X1257272Y169731D02*
X1256551Y170218D01*
G01X1258716Y169243D02*
X1257272Y169731D01*
G01X1261603Y169243D02*
X1258716D01*
G01X1263047Y169731D02*
X1261603Y169243D01*
G01X1263769Y170218D02*
X1263047Y169731D01*
G01X1264490Y171192D02*
X1263769Y170218D01*
G01X1263047Y149268D02*
X1263769Y148781D01*
G01X1261603Y149755D02*
X1263047Y149268D01*
G01X1258716Y149755D02*
X1261603D01*
G01X1257272Y149268D02*
X1258716Y149755D01*
G01X1256551Y148781D02*
X1257272Y149268D01*
G01X1253998Y214460D02*
G03X1255967Y216428I0J1969D01*
G01X1253998Y214460D02*
G03X1255967Y216428I0J1969D01*
G01X1224923Y218397D02*
G03X1228860Y214460I3937J0D01*
G01X1224923Y218397D02*
G03X1228860Y214460I3937J0D01*
G01X1255967Y216428D02*
Y240050D01*
G01Y216428D02*
Y240050D01*
G01X1224923Y218397D02*
Y591232D01*
G01Y419103D02*
Y218397D01*
G01X1228860Y214460D02*
X1253998D01*
G01X1228860D02*
X1253998D01*
G01X1218013Y271359D02*
X1214864D01*
G01X1264300Y247186D02*
X1218013Y271359D01*
G01X1257935Y242019D02*
G03X1255967Y240050I0J-1968D01*
G01X1257935Y242019D02*
G03X1255967Y240050I0J-1968D01*
G01X1269313Y245956D02*
G03I-2657J0D01*
G01X1275691Y294632D02*
X1276921Y295386D01*
G01X1275445Y295889D02*
X1276183Y296392D01*
G01X1276921Y295386D02*
X1277660Y296140D01*
G01X1276183Y296392D02*
X1277168Y297899D01*
G01X1277660Y296140D02*
X1278152Y297145D01*
G01D02*
X1278398Y297899D01*
G01D02*
X1278644Y299156D01*
G01X1277168Y297899D02*
X1277414Y299407D01*
G01X1281843Y300664D02*
Y294381D01*
G01X1280612D02*
Y302423D01*
G01X1278644Y299156D02*
Y301418D01*
G01X1269786D02*
Y299156D01*
G01X1267817Y299407D02*
Y298402D01*
G01X1271016Y299407D02*
X1271262Y297899D01*
G01X1269786Y299156D02*
X1270032Y297899D01*
G01X1263880Y298402D02*
Y299407D01*
G01X1261912Y306192D02*
Y294381D01*
G01X1260435D02*
Y299910D01*
G01X1253545D02*
Y294381D01*
G01X1252069D02*
Y306192D01*
G01X1270032Y297899D02*
X1270278Y297145D01*
G01X1274215Y294381D02*
X1275691Y294632D01*
G01X1274215Y295638D02*
X1275445Y295889D01*
G01X1270278Y297145D02*
X1270770Y296140D01*
G01X1271262Y297899D02*
X1272246Y296392D01*
G01X1267817Y298402D02*
X1263880D01*
G01X1253545Y294381D02*
X1252069D01*
G01X1261912D02*
X1260435D01*
G01X1281843D02*
X1280612D01*
G01X1270770Y296140D02*
X1271508Y295386D01*
G01X1272246Y296392D02*
X1272984Y295889D01*
G01X1271508Y295386D02*
X1272738Y294632D01*
G01X1272984Y295889D02*
X1274215Y295638D01*
G01X1272738Y294632D02*
X1274215Y294381D01*
G01X1257935Y242019D02*
X1424589D01*
G01X1257935D02*
X1424589D01*
G01X1283073Y301418D02*
X1282335Y301166D01*
G01Y302171D02*
X1283073Y302423D01*
G01X1272738Y305941D02*
X1271508Y305187D01*
G01X1272984Y304684D02*
X1272246Y304182D01*
G01X1282335Y301166D02*
X1281843Y300664D01*
G01Y301669D02*
X1282335Y302171D01*
G01X1271508Y305187D02*
X1270770Y304433D01*
G01X1272246Y304182D02*
X1271262Y302674D01*
G01X1270770Y304433D02*
X1270278Y303428D01*
G01D02*
X1270032Y302674D01*
G01D02*
X1269786Y301418D01*
G01X1271262Y302674D02*
X1271016Y301166D01*
G01X1281843Y302423D02*
Y301669D01*
G01X1277414Y299407D02*
Y301166D01*
G01X1271016D02*
Y299407D01*
G01X1267817Y302423D02*
Y301418D01*
G01X1277414Y301166D02*
X1277168Y302674D01*
G01X1278644Y301418D02*
X1278398Y302674D01*
G01X1274215Y306192D02*
X1272738Y305941D01*
G01X1274215Y304936D02*
X1272984Y304684D01*
G01X1263880Y301418D02*
Y302423D01*
G01X1260435Y301418D02*
Y306192D01*
G01X1253545D02*
Y301418D01*
G01X1278398Y302674D02*
X1278152Y303428D01*
G01D02*
X1277660Y304433D01*
G01X1260435Y306192D02*
X1261912D01*
G01X1252069D02*
X1253545D01*
G01X1283073Y302423D02*
X1284057D01*
G01X1280612D02*
X1281843D01*
G01X1263880D02*
X1267817D01*
G01X1253545Y301418D02*
X1260435D01*
G01X1267817D02*
X1263880D01*
G01X1283565D02*
X1283073D01*
G01X1277168Y302674D02*
X1276183Y304182D01*
G01X1277660Y304433D02*
X1276921Y305187D01*
G01X1276183Y304182D02*
X1275445Y304684D01*
G01X1276921Y305187D02*
X1275691Y305941D01*
G01X1284057Y301166D02*
X1283565Y301418D01*
G01X1275445Y304684D02*
X1274215Y304936D01*
G01X1275691Y305941D02*
X1274215Y306192D01*
G01X1260435Y299910D02*
X1253545D01*
G01X1263880Y299407D02*
X1267817D01*
G01X1215805Y450397D02*
G03X1213112Y446662I1244J-3735D01*
G01Y428715D02*
G03X1215805Y424980I3937J0D01*
G01X1224923Y419103D02*
G03X1222231Y422838I-3937J0D01*
G01X1224923Y419103D02*
G03X1222231Y422838I-3937J0D01*
G01X1215805Y450397D02*
G03X1213112Y446662I1244J-3735D01*
G01Y428715D02*
G03X1215805Y424980I3937J0D01*
G01X1220073Y437787D02*
X1220575Y437869D01*
G01X1221664Y435818D02*
X1221161Y435736D01*
G01X1220073Y438197D02*
X1220491Y438279D01*
G01X1221664Y435408D02*
X1221245Y435326D01*
G01X1222837Y444184D02*
X1218900D01*
G01X1220994Y443692D02*
X1222837D01*
G01X1218900D02*
X1220491D01*
G01Y441396D02*
X1218900D01*
G01X1222837D02*
X1220994D01*
G01X1218900Y440903D02*
X1222837D01*
G01X1220491Y440247D02*
X1220156D01*
G01X1221497D02*
X1221161D01*
G01Y438935D02*
X1221497D01*
G01X1220156D02*
X1220491D01*
G01Y438279D02*
X1221245D01*
G01X1220575Y437869D02*
X1221161D01*
G01Y435736D02*
X1220575D01*
G01X1221245Y435326D02*
X1220491D01*
G01X1222837Y434670D02*
X1220156D01*
G01X1220743Y434260D02*
X1222837D01*
G01X1220156D02*
X1220408D01*
G01X1222837Y433358D02*
X1220826D01*
G01Y432947D02*
X1222837D01*
G01Y432045D02*
X1220826D01*
G01Y431635D02*
X1222837D01*
G01Y430979D02*
X1220156D01*
G01X1220743Y430569D02*
X1222837D01*
G01X1220156D02*
X1220408D01*
G01X1222837Y429667D02*
X1220826D01*
G01Y429257D02*
X1222837D01*
G01Y428354D02*
X1220826D01*
G01Y427944D02*
X1222837D01*
G01X1221245Y438279D02*
X1221664Y438197D01*
G01X1220491Y435326D02*
X1220073Y435408D01*
G01X1221161Y437869D02*
X1221664Y437787D01*
G01X1220575Y435736D02*
X1220073Y435818D01*
G01X1221664Y438197D02*
X1221915Y438115D01*
G01X1220073Y435408D02*
X1219821Y435490D01*
G01X1221915Y438115D02*
X1222250Y437951D01*
G01X1219821Y435490D02*
X1219486Y435654D01*
G01X1220826Y433358D02*
X1220659Y433440D01*
G01X1220826Y432045D02*
X1220659Y432127D01*
G01X1220408Y431799D02*
X1220826Y431635D01*
G01X1220408Y428108D02*
X1220826Y427944D01*
G01X1222231Y422838D02*
X1215804Y424980D01*
G01X1222231Y422838D02*
X1215804Y424980D01*
G01X1221664Y437787D02*
X1222167Y437459D01*
G01X1220073Y435818D02*
X1219570Y436146D01*
G01X1220826Y429667D02*
X1220659Y429749D01*
G01X1220826Y428354D02*
X1220659Y428436D01*
G01X1222250Y437951D02*
X1222502Y437705D01*
G01X1219486Y435654D02*
X1219235Y435900D01*
G01X1220659Y433440D02*
X1220575Y433522D01*
G01X1220240Y433276D02*
X1220491Y433029D01*
G01X1220659Y432127D02*
X1220575Y432209D01*
G01X1220240Y431963D02*
X1220408Y431799D01*
G01X1220659Y429749D02*
X1220575Y429831D01*
G01X1220240Y429585D02*
X1220491Y429339D01*
G01X1220659Y428436D02*
X1220575Y428518D01*
G01X1220240Y428272D02*
X1220408Y428108D01*
G01X1221915Y435490D02*
X1221664Y435408D01*
G01X1219821Y438115D02*
X1220073Y438197D01*
G01X1220659Y429174D02*
X1220826Y429257D01*
G01X1222502Y437705D02*
X1222753Y437295D01*
G01X1219235Y435900D02*
X1218984Y436310D01*
G01X1222167Y437459D02*
X1222334Y437213D01*
G01X1219570Y436146D02*
X1219402Y436392D01*
G01X1215804Y450397D02*
X1222231Y452539D01*
G01D02*
X1215804Y450397D01*
G01X1220659Y432865D02*
X1220826Y432947D01*
G01X1222250Y435654D02*
X1221915Y435490D01*
G01X1219486Y437951D02*
X1219821Y438115D01*
G01X1220156Y433522D02*
X1220240Y433276D01*
G01X1220156Y432209D02*
X1220240Y431963D01*
G01X1220575Y433522D02*
X1220491Y433686D01*
G01X1220575Y432209D02*
X1220491Y432373D01*
G01X1220575Y429831D02*
X1220491Y429995D01*
G01X1220575Y428518D02*
X1220491Y428682D01*
G01X1222167Y436146D02*
X1221664Y435818D01*
G01X1219570Y437459D02*
X1220073Y437787D01*
G01X1220575Y429092D02*
X1220659Y429174D01*
G01X1220491Y429339D02*
X1220240Y429092D01*
G01X1220575Y430405D02*
X1220743Y430569D01*
G01X1220408D02*
X1220240Y430405D01*
G01X1220575Y432783D02*
X1220659Y432865D01*
G01X1220491Y433029D02*
X1220240Y432783D01*
G01X1222502Y435900D02*
X1222250Y435654D01*
G01X1220575Y434096D02*
X1220743Y434260D01*
G01X1220408D02*
X1220240Y434096D01*
G01X1222753Y437295D02*
X1222837Y436802D01*
G01X1218984Y436310D02*
X1218900Y436802D01*
G01X1222334Y437213D02*
X1222418Y436802D01*
G01X1219402Y436392D02*
X1219319Y436802D01*
G01X1220156Y429831D02*
X1220240Y429585D01*
G01X1220156Y428518D02*
X1220240Y428272D01*
G01X1219235Y437705D02*
X1219486Y437951D01*
G01X1222334Y436392D02*
X1222167Y436146D01*
G01X1219402Y437213D02*
X1219570Y437459D01*
G01X1222753Y436310D02*
X1222502Y435900D01*
G01X1218984Y437295D02*
X1219235Y437705D01*
G01X1220491Y428928D02*
X1220575Y429092D01*
G01X1220491Y432619D02*
X1220575Y432783D01*
G01X1222837Y443692D02*
Y444184D01*
G01Y440903D02*
Y441396D01*
G01Y432947D02*
Y433358D01*
G01Y434260D02*
Y434670D01*
G01Y431635D02*
Y432045D01*
G01Y430569D02*
Y430979D01*
G01Y429257D02*
Y429667D01*
G01Y427944D02*
Y428354D01*
G01X1221497Y438935D02*
Y440247D01*
G01X1221161D02*
Y438935D01*
G01X1220994Y441396D02*
Y443692D01*
G01X1220491Y438935D02*
Y440247D01*
G01Y433686D02*
Y433850D01*
G01Y432373D02*
Y432619D01*
G01Y429995D02*
Y430159D01*
G01Y428682D02*
Y428928D01*
G01Y443692D02*
Y441396D01*
G01X1220156Y428846D02*
Y428518D01*
G01Y430159D02*
Y429831D01*
G01Y430979D02*
Y430569D01*
G01Y432537D02*
Y432209D01*
G01Y433850D02*
Y433522D01*
G01Y434670D02*
Y434260D01*
G01Y440247D02*
Y438935D01*
G01X1220240Y429092D02*
X1220156Y428846D01*
G01X1220491Y430159D02*
X1220575Y430405D01*
G01X1220240D02*
X1220156Y430159D01*
G01X1220240Y432783D02*
X1220156Y432537D01*
G01X1220491Y433850D02*
X1220575Y434096D01*
G01X1220240D02*
X1220156Y433850D01*
G01X1222418Y436802D02*
X1222334Y436392D01*
G01X1219319Y436802D02*
X1219402Y437213D01*
G01X1222837Y436802D02*
X1222753Y436310D01*
G01X1218900Y436802D02*
X1218984Y437295D01*
G01X1218900Y441396D02*
Y440903D01*
G01Y444184D02*
Y443692D01*
G01X1213112Y446662D02*
Y428715D01*
G01Y446662D02*
Y428715D01*
G01X1222231Y452539D02*
G03X1224923Y456274I-1245J3735D01*
G01X1222231Y452539D02*
G03X1224923Y456274I-1245J3735D01*
G01Y591232D02*
Y456274D01*
G01X1228860Y595169D02*
G03X1224923Y591232I0J-3937D01*
G01X1228860Y595169D02*
G03X1224923Y591232I0J-3937D01*
G01X1285553Y595169D02*
X1228860D01*
G01X1285553D02*
X1228860D01*
G01X1333729Y-354220D02*
Y-371543D01*
G01X1352879Y144557D02*
X1356777D01*
G01X1352879Y135896D02*
Y144557D01*
G01X1356777Y135896D02*
X1352879D01*
G01X1306107Y144557D02*
X1310005D01*
G01X1306107Y135896D02*
Y144557D01*
G01X1310005Y135896D02*
X1306107D01*
G01X1302697Y140226D02*
X1302210Y138061D01*
G01Y142392D02*
X1302697Y140226D01*
G01X1301723Y143113D02*
X1302210Y142392D01*
G01X1301235Y143835D02*
X1301723Y143113D01*
G01X1300261Y144557D02*
X1301235Y143835D01*
G01X1298312Y144557D02*
X1300261D01*
G01X1349469Y140226D02*
X1348981Y138061D01*
G01Y142392D02*
X1349469Y140226D01*
G01X1348494Y143113D02*
X1348981Y142392D01*
G01X1348007Y143835D02*
X1348494Y143113D01*
G01X1347033Y144557D02*
X1348007Y143835D01*
G01X1345084Y144557D02*
X1347033D01*
G01X1290517Y135896D02*
X1294415D01*
G01X1290517Y144557D02*
Y135896D01*
G01X1316339Y140226D02*
X1313903D01*
G01X1317313Y140948D02*
X1316339Y140226D01*
G01X1317800Y141670D02*
X1317313Y140948D01*
G01X1317800Y143113D02*
Y141670D01*
G01X1317313Y143835D02*
X1317800Y143113D01*
G01X1316339Y144557D02*
X1317313Y143835D01*
G01X1313903Y144557D02*
X1316339D01*
G01X1313903Y135896D02*
Y144557D01*
G01X1285158Y135896D02*
X1284183D01*
G01X1286132Y136617D02*
X1285158Y135896D01*
G01X1286619Y137339D02*
X1286132Y136617D01*
G01X1298312Y135896D02*
Y144557D01*
G01X1300261Y135896D02*
X1298312D01*
G01X1301235Y136617D02*
X1300261Y135896D01*
G01X1302210Y138061D02*
X1301235Y136617D01*
G01X1345084Y135896D02*
Y144557D01*
G01X1347033Y135896D02*
X1345084D01*
G01X1348007Y136617D02*
X1347033Y135896D01*
G01X1348981Y138061D02*
X1348007Y136617D01*
G01X1286132Y143835D02*
X1287107Y142392D01*
G01X1285158Y144557D02*
X1286132Y143835D01*
G01X1284183Y144557D02*
X1285158D01*
G01X1330955Y135896D02*
X1329980Y136617D01*
G01X1331929Y135896D02*
X1330955D01*
G01X1332904Y136617D02*
X1331929Y135896D01*
G01X1333391Y137339D02*
X1332904Y136617D01*
G01X1333391Y138783D02*
Y137339D01*
G01X1332904Y139504D02*
X1333391Y138783D01*
G01X1331929Y140226D02*
X1332904Y139504D01*
G01X1330955Y140948D02*
X1331929Y140226D01*
G01X1329980Y141670D02*
X1330955Y140948D01*
G01X1329493Y142392D02*
X1329980Y141670D01*
G01X1329493Y143113D02*
Y142392D01*
G01X1329980Y143835D02*
X1329493Y143113D01*
G01X1330955Y144557D02*
X1329980Y143835D01*
G01X1331929Y144557D02*
X1330955D01*
G01X1332904Y143835D02*
X1331929Y144557D01*
G01X1333391Y143113D02*
X1332904Y143835D01*
G01X1287107Y138061D02*
X1286619Y137339D01*
G01X1287594Y140226D02*
X1287107Y138061D01*
G01Y142392D02*
X1287594Y140226D01*
G01X1316339D02*
X1317800Y135896D01*
G01X1329980Y136617D02*
X1329006Y138061D01*
G01X1339237Y144557D02*
Y135896D01*
G01X1352879Y140226D02*
X1355315D01*
G01X1306107D02*
X1308544D01*
G01X1362916Y319578D02*
G03I-21654J0D01*
G01X1300790Y300412D02*
Y294381D01*
G01X1299559D02*
Y300412D01*
G01X1296853D02*
Y294381D01*
G01X1295622D02*
Y300412D01*
G01X1292916Y300664D02*
Y294381D01*
G01X1291685D02*
Y302423D01*
G01X1289717Y300412D02*
Y294381D01*
G01X1288486D02*
Y300412D01*
G01X1285780D02*
Y294381D01*
G01X1284549D02*
Y300412D01*
G01X1285780Y294381D02*
X1284549D01*
G01X1289717D02*
X1288486D01*
G01X1292916D02*
X1291685D01*
G01X1296853D02*
X1295622D01*
G01X1300790D02*
X1299559D01*
G01X1352069Y317404D02*
X1492862Y289080D01*
G01X1358591Y324840D02*
X1439625Y359465D01*
G01X1352286Y319578D02*
G03I-11024J0D01*
G01X1359372D02*
G03I-18110J0D01*
G01X1319833Y346322D02*
G03X1322617Y345169I2784J2785D01*
G01X1319833Y346322D02*
G03X1322617Y345169I2784J2785D01*
G01X1297345Y302171D02*
X1298083Y302423D01*
G01X1294146Y301418D02*
X1293408Y301166D01*
G01Y302171D02*
X1294146Y302423D01*
G01X1286272Y302171D02*
X1287010Y302423D01*
G01X1297837Y301418D02*
X1297345Y301166D01*
G01X1286764Y301418D02*
X1286272Y301166D01*
G01X1297345D02*
X1297099Y300915D01*
G01X1296607Y301418D02*
X1297345Y302171D01*
G01X1293408Y301166D02*
X1292916Y300664D01*
G01Y301669D02*
X1293408Y302171D01*
G01X1286272Y301166D02*
X1286026Y300915D01*
G01X1285534Y301418D02*
X1286272Y302171D01*
G01X1297099Y300915D02*
X1296853Y300412D01*
G01X1286026Y300915D02*
X1285780Y300412D01*
G01X1319833Y346322D02*
X1290643Y375512D01*
G01X1319833Y346322D02*
X1290643Y375512D01*
G01X1292916Y302423D02*
Y301669D01*
G01X1300297D02*
X1300790Y300412D01*
G01X1359907Y345169D02*
X1322617D01*
G01X1359907D02*
X1322617D01*
G01X1289225Y301669D02*
X1289717Y300412D01*
G01X1299559D02*
X1299313Y300915D01*
G01X1295622Y300412D02*
X1295376Y300915D01*
G01X1288486Y300412D02*
X1288240Y300915D01*
G01X1284549Y300412D02*
X1284303Y300915D01*
G01X1299805Y302171D02*
X1300297Y301669D01*
G01X1299313Y300915D02*
X1299067Y301166D01*
G01X1295868Y302171D02*
X1296607Y301418D01*
G01X1295376Y300915D02*
X1295130Y301166D01*
G01X1298083Y302423D02*
X1299067D01*
G01X1294146D02*
X1295130D01*
G01X1291685D02*
X1292916D01*
G01X1287010D02*
X1287994D01*
G01X1287502Y301418D02*
X1286764D01*
G01X1294638D02*
X1294146D01*
G01X1298575D02*
X1297837D01*
G01X1288732Y302171D02*
X1289225Y301669D01*
G01X1288240Y300915D02*
X1287994Y301166D01*
G01X1284795Y302171D02*
X1285534Y301418D01*
G01X1284303Y300915D02*
X1284057Y301166D01*
G01X1299067D02*
X1298575Y301418D01*
G01X1295130Y301166D02*
X1294638Y301418D01*
G01X1287994Y301166D02*
X1287502Y301418D01*
G01X1299067Y302423D02*
X1299805Y302171D01*
G01X1295130Y302423D02*
X1295868Y302171D01*
G01X1287994Y302423D02*
X1288732Y302171D01*
G01X1284057Y302423D02*
X1284795Y302171D01*
G01X1289490Y378295D02*
G03X1290643Y375512I3937J1D01*
G01X1289490Y378295D02*
G03X1290643Y375512I3937J1D01*
G01X1289490Y378295D02*
Y591232D01*
G01Y378295D02*
Y489969D01*
G01X1292183Y493704D02*
G03X1289490Y489969I1244J-3735D01*
G01X1298609Y495846D02*
G03X1301301Y499581I-1245J3735D01*
G01Y517528D02*
G03X1298609Y521263I-3937J0D01*
G01X1289490Y527140D02*
G03X1292183Y523405I3937J0D01*
G01X1289490Y527140D02*
G03X1292183Y523405I3937J0D01*
G01Y493704D02*
G03X1289490Y489969I1244J-3735D01*
G01X1298609Y495846D02*
G03X1301301Y499581I-1245J3735D01*
G01Y517528D02*
G03X1298609Y521263I-3937J0D01*
G01X1295908Y515995D02*
X1291971D01*
G01X1294065Y515503D02*
X1295908D01*
G01X1291971D02*
X1293562D01*
G01X1293143Y509598D02*
X1293646Y509680D01*
G01X1294735Y507629D02*
X1294232Y507547D01*
G01X1293143Y510008D02*
X1293562Y510090D01*
G01X1294735Y507219D02*
X1294316Y507137D01*
G01X1292182Y523405D02*
X1298609Y521263D01*
G01D02*
X1292182Y523405D01*
G01X1294316Y510090D02*
X1294735Y510008D01*
G01X1294232Y509680D02*
X1294735Y509598D01*
G01X1293646Y507547D02*
X1293143Y507629D01*
G01X1293562Y513207D02*
X1291971D01*
G01X1295908D02*
X1294065D01*
G01X1291971Y512715D02*
X1295908D01*
G01X1293562Y512058D02*
X1293227D01*
G01X1294567D02*
X1294232D01*
G01Y510746D02*
X1294567D01*
G01X1293227D02*
X1293562D01*
G01Y510090D02*
X1294316D01*
G01X1293646Y509680D02*
X1294232D01*
G01Y507547D02*
X1293646D01*
G01X1294316Y507137D02*
X1293562D01*
G01X1295908Y506481D02*
X1293227D01*
G01X1293814Y506071D02*
X1295908D01*
G01X1293227D02*
X1293478D01*
G01X1295908Y505169D02*
X1293897D01*
G01Y504758D02*
X1295908D01*
G01Y503856D02*
X1293897D01*
G01Y503446D02*
X1295908D01*
G01Y502790D02*
X1293227D01*
G01X1293814Y502380D02*
X1295908D01*
G01X1293227D02*
X1293478D01*
G01X1295908Y501478D02*
X1293897D01*
G01Y501068D02*
X1295908D01*
G01Y500165D02*
X1293897D01*
G01Y499755D02*
X1295908D01*
G01X1294735Y510008D02*
X1294986Y509926D01*
G01X1293143Y507219D02*
X1292892Y507301D01*
G01X1293562Y507137D02*
X1293143Y507219D01*
G01X1294735Y509598D02*
X1295238Y509270D01*
G01X1294986Y509926D02*
X1295321Y509762D01*
G01X1292892Y507301D02*
X1292557Y507465D01*
G01X1293897Y505169D02*
X1293730Y505251D01*
G01X1293897Y503856D02*
X1293730Y503938D01*
G01X1293897Y501478D02*
X1293730Y501560D01*
G01X1293897Y500165D02*
X1293730Y500247D01*
G01X1293478Y503610D02*
X1293897Y503446D01*
G01X1293478Y499919D02*
X1293897Y499755D01*
G01X1293143Y507629D02*
X1292641Y507957D01*
G01X1295321Y509762D02*
X1295573Y509516D01*
G01X1292557Y507465D02*
X1292306Y507711D01*
G01X1293730Y505251D02*
X1293646Y505333D01*
G01X1293311Y505087D02*
X1293562Y504840D01*
G01X1293730Y503938D02*
X1293646Y504020D01*
G01X1293311Y503774D02*
X1293478Y503610D01*
G01X1293730Y501560D02*
X1293646Y501642D01*
G01X1293311Y501396D02*
X1293562Y501150D01*
G01X1293730Y500247D02*
X1293646Y500329D01*
G01X1293311Y500083D02*
X1293478Y499919D01*
G01X1295573Y509516D02*
X1295824Y509106D01*
G01X1295238Y509270D02*
X1295405Y509024D01*
G01X1292641Y507957D02*
X1292473Y508203D01*
G01X1293646Y505333D02*
X1293562Y505497D01*
G01X1293646Y504020D02*
X1293562Y504184D01*
G01X1293646Y501642D02*
X1293562Y501806D01*
G01X1293646Y500329D02*
X1293562Y500493D01*
G01X1292306Y507711D02*
X1292054Y508121D01*
G01X1293227Y505333D02*
X1293311Y505087D01*
G01X1293227Y504020D02*
X1293311Y503774D01*
G01X1293227Y501642D02*
X1293311Y501396D01*
G01X1293227Y500329D02*
X1293311Y500083D01*
G01X1295824Y509106D02*
X1295908Y508613D01*
G01X1295405Y509024D02*
X1295489Y508613D01*
G01X1292473Y508203D02*
X1292390Y508613D01*
G01X1292054Y508121D02*
X1291971Y508613D01*
G01X1301301Y499581D02*
Y517528D01*
G01Y499581D02*
Y517528D01*
G01X1295908Y515503D02*
Y515995D01*
G01Y512715D02*
Y513207D01*
G01Y506071D02*
Y506481D01*
G01Y504758D02*
Y505169D01*
G01Y502380D02*
Y502790D01*
G01Y503446D02*
Y503856D01*
G01Y501068D02*
Y501478D01*
G01Y499755D02*
Y500165D01*
G01X1294567Y510746D02*
Y512058D01*
G01X1294232D02*
Y510746D01*
G01X1294065Y513207D02*
Y515503D01*
G01X1293562Y510746D02*
Y512058D01*
G01Y505497D02*
Y505661D01*
G01Y504184D02*
Y504430D01*
G01Y501806D02*
Y501970D01*
G01Y500493D02*
Y500739D01*
G01Y515503D02*
Y513207D01*
G01X1293227Y500657D02*
Y500329D01*
G01Y501970D02*
Y501642D01*
G01Y502790D02*
Y502380D01*
G01Y504348D02*
Y504020D01*
G01Y505661D02*
Y505333D01*
G01Y506481D02*
Y506071D01*
G01Y512058D02*
Y510746D01*
G01X1291971Y513207D02*
Y512715D01*
G01Y515995D02*
Y515503D01*
G01X1295489Y508613D02*
X1295405Y508203D01*
G01X1292390Y508613D02*
X1292473Y509024D01*
G01X1295908Y508613D02*
X1295824Y508121D01*
G01X1291971Y508613D02*
X1292054Y509106D01*
G01X1293562Y500739D02*
X1293646Y500903D01*
G01X1293562Y504430D02*
X1293646Y504594D01*
G01X1293311Y500903D02*
X1293227Y500657D01*
G01X1293562Y501970D02*
X1293646Y502216D01*
G01X1293311D02*
X1293227Y501970D01*
G01X1293311Y504594D02*
X1293227Y504348D01*
G01X1293562Y505661D02*
X1293646Y505907D01*
G01X1293311D02*
X1293227Y505661D01*
G01X1298609Y495846D02*
X1292182Y493704D01*
G01X1298609Y495846D02*
X1292182Y493704D01*
G01X1293646Y500903D02*
X1293730Y500986D01*
G01X1293562Y501150D02*
X1293311Y500903D01*
G01X1293646Y502216D02*
X1293814Y502380D01*
G01X1293478D02*
X1293311Y502216D01*
G01X1293646Y504594D02*
X1293730Y504676D01*
G01X1293562Y504840D02*
X1293311Y504594D01*
G01X1295573Y507711D02*
X1295321Y507465D01*
G01X1293646Y505907D02*
X1293814Y506071D01*
G01X1293478D02*
X1293311Y505907D01*
G01X1295405Y508203D02*
X1295238Y507957D01*
G01X1292473Y509024D02*
X1292641Y509270D01*
G01X1295824Y508121D02*
X1295573Y507711D01*
G01X1292054Y509106D02*
X1292306Y509516D01*
G01X1294986Y507301D02*
X1294735Y507219D01*
G01X1292892Y509926D02*
X1293143Y510008D01*
G01X1293730Y500986D02*
X1293897Y501068D01*
G01X1293730Y504676D02*
X1293897Y504758D01*
G01X1295321Y507465D02*
X1294986Y507301D01*
G01X1292557Y509762D02*
X1292892Y509926D01*
G01X1295238Y507957D02*
X1294735Y507629D01*
G01X1292641Y509270D02*
X1293143Y509598D01*
G01X1292306Y509516D02*
X1292557Y509762D01*
G01X1289490Y591232D02*
G03X1285553Y595169I-3937J0D01*
G01X1289490Y591232D02*
G03X1285553Y595169I-3937J0D01*
G01X1289490Y527140D02*
Y591232D01*
G01X1333729Y1006410D02*
Y989087D01*
G01X1362324Y-187764D02*
Y-277893D01*
G01X1411538Y138062D02*
Y142447D01*
G01X1405042Y141473D02*
X1411538Y138062D01*
G01X1413703Y141473D02*
X1405042D01*
G01X1408650Y147319D02*
Y148294D01*
G01X1409372Y146345D02*
X1408650Y147319D01*
G01X1410816Y145370D02*
X1409372Y146345D01*
G01X1413703Y148294D02*
Y147319D01*
G01X1405042D02*
Y148294D01*
G01X1405763Y146345D02*
X1405042Y147319D01*
G01X1406485Y145858D02*
X1405763Y146345D01*
G01X1407207Y145858D02*
X1406485D01*
G01X1407929Y146345D02*
X1407207Y145858D01*
G01X1408650Y147319D02*
X1407929Y146345D01*
G01X1411538Y145370D02*
X1410816D01*
G01X1412981Y146345D02*
X1411538Y145370D01*
G01X1413703Y147319D02*
X1412981Y146345D01*
G01X1415868Y242019D02*
Y179421D01*
G01X1408650Y148294D02*
X1409372Y149268D01*
G01X1412981D02*
X1413703Y148294D01*
G01X1411538Y150242D02*
X1412981Y149268D01*
G01Y161935D02*
X1412259Y161448D01*
G01X1413703Y162910D02*
X1412981Y161935D01*
G01X1413703Y163884D02*
Y162910D01*
G01X1412981Y164859D02*
X1413703Y163884D01*
G01X1412259Y165346D02*
X1412981Y164859D01*
G01X1410816Y165833D02*
X1412259Y165346D01*
G01X1409372D02*
X1410816Y165833D01*
G01X1408650Y164859D02*
X1409372Y165346D01*
G01X1407929Y163884D02*
X1408650Y164859D01*
G01X1407929Y162910D02*
Y163884D01*
G01X1408650Y161935D02*
X1407929Y162910D01*
G01X1405042Y162423D02*
X1408650Y161935D01*
G01X1405042Y165346D02*
Y162423D01*
G01X1412981Y155114D02*
X1413703Y155602D01*
G01Y155114D02*
X1412981D01*
G01X1413703Y155602D02*
Y155114D01*
G01X1412981Y172167D02*
X1413703Y171192D01*
G01X1412259Y172654D02*
X1412981Y172167D01*
G01X1410816Y173141D02*
X1412259Y172654D01*
G01X1407929Y173141D02*
X1410816D01*
G01X1406485Y172654D02*
X1407929Y173141D01*
G01X1405763Y172167D02*
X1406485Y172654D01*
G01X1405042Y171192D02*
X1405763Y172167D01*
G01Y170218D02*
X1405042Y171192D01*
G01X1406485Y169731D02*
X1405763Y170218D01*
G01X1407929Y169243D02*
X1406485Y169731D01*
G01X1410816Y169243D02*
X1407929D01*
G01X1412259Y169731D02*
X1410816Y169243D01*
G01X1412981Y170218D02*
X1412259Y169731D01*
G01X1413703Y171192D02*
X1412981Y170218D01*
G01X1407929Y149268D02*
X1408650Y148294D01*
G01X1407207Y149755D02*
X1407929Y149268D01*
G01X1406485Y149755D02*
X1407207D01*
G01X1405763Y149268D02*
X1406485Y149755D01*
G01X1405042Y148294D02*
X1405763Y149268D01*
G01X1410816Y150242D02*
X1411538D01*
G01X1409372Y149268D02*
X1410816Y150242D01*
G01X1426557Y216428D02*
G03X1428526Y214460I1968J0D01*
G01X1426557Y216428D02*
G03X1428526Y214460I1968J0D01*
G01X1426557Y240050D02*
Y216428D01*
G01Y240050D02*
Y216428D01*
G01X1428526Y214460D02*
X1453664D01*
G01X1428526D02*
X1453664D01*
G01X1419805Y245956D02*
X1479223D01*
G01X1418067Y244463D02*
X1482058Y201026D01*
G01X1428526Y242019D02*
X1495402D01*
G01X1426557Y240050D02*
G03X1424589Y242019I-1969J0D01*
G01X1426557Y240050D02*
G03X1424589Y242019I-1969J0D01*
G01X1418526Y245956D02*
G03I-2658J0D01*
G01X1359907Y345169D02*
G03X1362691Y346322I0J3938D01*
G01X1391881Y375512D02*
X1362691Y346322D01*
G01X1391881Y375512D02*
X1362691Y346322D01*
G01X1391881Y375512D02*
G03X1393034Y378295I-2784J2784D01*
G01D02*
Y591232D01*
G01Y489969D02*
Y378295D01*
G01X1390341Y523405D02*
G03X1393034Y527140I-1244J3735D01*
G01X1383915Y521263D02*
G03X1381223Y517528I1245J-3735D01*
G01Y499581D02*
G03X1383915Y495846I3937J0D01*
G01X1393034Y489969D02*
G03X1390341Y493704I-3937J0D01*
G01X1393034Y489969D02*
G03X1390341Y493704I-3937J0D01*
G01Y523405D02*
G03X1393034Y527140I-1244J3735D01*
G01X1383915Y521263D02*
G03X1381223Y517528I1245J-3735D01*
G01Y499581D02*
G03X1383915Y495846I3937J0D01*
G01X1389101Y512242D02*
X1389352Y511996D01*
G01X1388514Y512078D02*
X1389017Y511750D01*
G01X1386923Y510110D02*
X1386420Y510438D01*
G01X1388766Y512406D02*
X1389101Y512242D01*
G01X1386672Y509781D02*
X1386337Y509945D01*
G01X1387677Y507649D02*
X1387509Y507731D01*
G01X1387677Y506337D02*
X1387509Y506419D01*
G01X1387677Y503958D02*
X1387509Y504040D01*
G01X1387677Y502646D02*
X1387509Y502728D01*
G01X1387258Y506090D02*
X1387677Y505926D01*
G01X1388514Y512488D02*
X1388766Y512406D01*
G01X1386923Y509699D02*
X1386672Y509781D01*
G01X1388096Y512570D02*
X1388514Y512488D01*
G01X1387342Y509617D02*
X1386923Y509699D01*
G01X1388012Y512160D02*
X1388514Y512078D01*
G01X1387426Y510028D02*
X1386923Y510110D01*
G01X1389687Y518476D02*
X1385750D01*
G01X1387844Y517984D02*
X1389687D01*
G01X1385750D02*
X1387342D01*
G01Y515687D02*
X1385750D01*
G01X1389687D02*
X1387844D01*
G01X1385750Y515195D02*
X1389687D01*
G01X1388347Y514539D02*
X1388012D01*
G01X1387342D02*
X1387007D01*
G01X1389352Y511996D02*
X1389603Y511586D01*
G01X1386085Y510192D02*
X1385834Y510602D01*
G01X1389017Y511750D02*
X1389185Y511504D01*
G01X1386420Y510438D02*
X1386253Y510684D01*
G01X1386337Y509945D02*
X1386085Y510192D01*
G01X1387509Y507731D02*
X1387426Y507813D01*
G01X1387090Y507567D02*
X1387342Y507321D01*
G01X1387509Y506419D02*
X1387426Y506501D01*
G01X1387090Y506255D02*
X1387258Y506090D01*
G01X1387509Y504040D02*
X1387426Y504122D01*
G01X1387090Y503876D02*
X1387342Y503630D01*
G01X1387509Y502728D02*
X1387426Y502810D01*
G01X1387090Y502564D02*
X1387258Y502400D01*
G01D02*
X1387677Y502236D01*
G01X1390342Y493704D02*
X1383915Y495846D01*
G01X1390342Y493704D02*
X1383915Y495846D01*
G01X1388012Y513226D02*
X1388347D01*
G01X1387007D02*
X1387342D01*
G01Y512570D02*
X1388096D01*
G01X1387426Y512160D02*
X1388012D01*
G01Y510028D02*
X1387426D01*
G01X1388096Y509617D02*
X1387342D01*
G01X1389687Y508961D02*
X1387007D01*
G01X1387593Y508551D02*
X1389687D01*
G01X1387007D02*
X1387258D01*
G01X1389687Y507649D02*
X1387677D01*
G01Y507239D02*
X1389687D01*
G01Y506337D02*
X1387677D01*
G01Y505926D02*
X1389687D01*
G01Y505270D02*
X1387007D01*
G01X1387593Y504860D02*
X1389687D01*
G01X1387007D02*
X1387258D01*
G01X1389687Y503958D02*
X1387677D01*
G01Y503548D02*
X1389687D01*
G01Y502646D02*
X1387677D01*
G01Y502236D02*
X1389687D01*
G01X1386923Y512078D02*
X1387426Y512160D01*
G01X1388514Y510110D02*
X1388012Y510028D01*
G01X1386923Y512488D02*
X1387342Y512570D01*
G01X1388514Y509699D02*
X1388096Y509617D01*
G01X1387007Y507813D02*
X1387090Y507567D01*
G01X1387426Y507813D02*
X1387342Y507977D01*
G01X1387426Y506501D02*
X1387342Y506665D01*
G01X1387426Y504122D02*
X1387342Y504286D01*
G01X1387426Y502810D02*
X1387342Y502974D01*
G01X1389603Y511586D02*
X1389687Y511094D01*
G01X1385834Y510602D02*
X1385750Y511094D01*
G01X1389185Y511504D02*
X1389268Y511094D01*
G01X1386253Y510684D02*
X1386169Y511094D01*
G01X1387007Y506501D02*
X1387090Y506255D01*
G01X1387007Y504122D02*
X1387090Y503876D01*
G01X1387007Y502810D02*
X1387090Y502564D01*
G01X1389687Y517984D02*
Y518476D01*
G01Y515195D02*
Y515687D01*
G01Y507239D02*
Y507649D01*
G01Y508551D02*
Y508961D01*
G01Y505926D02*
Y506337D01*
G01Y504860D02*
Y505270D01*
G01Y503548D02*
Y503958D01*
G01Y502236D02*
Y502646D01*
G01X1388347Y513226D02*
Y514539D01*
G01X1388012D02*
Y513226D01*
G01X1387844Y515687D02*
Y517984D01*
G01X1387342Y513226D02*
Y514539D01*
G01Y507977D02*
Y508141D01*
G01Y506665D02*
Y506911D01*
G01Y504286D02*
Y504450D01*
G01Y502974D02*
Y503220D01*
G01Y517984D02*
Y515687D01*
G01X1387007Y503138D02*
Y502810D01*
G01Y504450D02*
Y504122D01*
G01Y505270D02*
Y504860D01*
G01Y506829D02*
Y506501D01*
G01Y508141D02*
Y507813D01*
G01Y508961D02*
Y508551D01*
G01Y514539D02*
Y513226D01*
G01X1385750Y515687D02*
Y515195D01*
G01Y518476D02*
Y517984D01*
G01X1381223Y517528D02*
Y499581D01*
G01Y517528D02*
Y499581D01*
G01X1389268Y511094D02*
X1389185Y510684D01*
G01X1386169Y511094D02*
X1386253Y511504D01*
G01X1389687Y511094D02*
X1389603Y510602D01*
G01X1385750Y511094D02*
X1385834Y511586D01*
G01X1387090Y503384D02*
X1387007Y503138D01*
G01X1387342Y504450D02*
X1387426Y504696D01*
G01X1387090D02*
X1387007Y504450D01*
G01X1387090Y507075D02*
X1387007Y506829D01*
G01X1387342Y508141D02*
X1387426Y508387D01*
G01X1387090D02*
X1387007Y508141D01*
G01X1389603Y510602D02*
X1389352Y510192D01*
G01X1387342Y503220D02*
X1387426Y503384D01*
G01X1387342Y506911D02*
X1387426Y507075D01*
G01X1389185Y510684D02*
X1389017Y510438D01*
G01X1386253Y511504D02*
X1386420Y511750D01*
G01X1385834Y511586D02*
X1386085Y511996D01*
G01X1387426Y503384D02*
X1387509Y503466D01*
G01X1387342Y503630D02*
X1387090Y503384D01*
G01X1387426Y504696D02*
X1387593Y504860D01*
G01X1387258D02*
X1387090Y504696D01*
G01X1387426Y507075D02*
X1387509Y507157D01*
G01X1387342Y507321D02*
X1387090Y507075D01*
G01X1389352Y510192D02*
X1389101Y509945D01*
G01X1387426Y508387D02*
X1387593Y508551D01*
G01X1387258D02*
X1387090Y508387D01*
G01X1386085Y511996D02*
X1386337Y512242D01*
G01X1387509Y503466D02*
X1387677Y503548D01*
G01X1387509Y507157D02*
X1387677Y507239D01*
G01X1389101Y509945D02*
X1388766Y509781D01*
G01X1389017Y510438D02*
X1388514Y510110D01*
G01X1386420Y511750D02*
X1386923Y512078D01*
G01X1388766Y509781D02*
X1388514Y509699D01*
G01X1386672Y512406D02*
X1386923Y512488D01*
G01X1386337Y512242D02*
X1386672Y512406D01*
G01X1383915Y521263D02*
X1390342Y523405D01*
G01D02*
X1383915Y521263D01*
G01X1396971Y595169D02*
G03X1393034Y591232I0J-3937D01*
G01X1396971Y595169D02*
G03X1393034Y591232I0J-3937D01*
G01X1453664Y595169D02*
X1396971D01*
G01X1453664D02*
X1396971D01*
G01X1393034Y591232D02*
Y527140D01*
G01X1506957Y-354220D02*
Y-371543D01*
G01X1454713Y146832D02*
X1453992Y146345D01*
G01X1455435Y147806D02*
X1454713Y146832D01*
G01Y148781D02*
X1455435Y147806D01*
G01X1446774D02*
X1447496Y148781D01*
G01Y146832D02*
X1446774Y147806D01*
G01X1448217Y146345D02*
X1447496Y146832D01*
G01X1449661Y145858D02*
X1448217Y146345D01*
G01X1451105D02*
X1449661Y145858D01*
G01X1451826Y147806D02*
X1451105Y146345D01*
G01Y149268D02*
X1451826Y147806D01*
G01X1454713Y138549D02*
X1453992Y138062D01*
G01X1455435Y139524D02*
X1454713Y138549D01*
G01X1455435Y140498D02*
Y139524D01*
G01X1454713Y141473D02*
X1455435Y140498D01*
G01X1453992Y141960D02*
X1454713Y141473D01*
G01X1452548Y142447D02*
X1453992Y141960D01*
G01X1451105D02*
X1452548Y142447D01*
G01X1450383Y141473D02*
X1451105Y141960D01*
G01X1449661Y140498D02*
X1450383Y141473D01*
G01X1449661Y139524D02*
Y140498D01*
G01X1450383Y138549D02*
X1449661Y139524D01*
G01X1446774Y139037D02*
X1450383Y138549D01*
G01X1446774Y141960D02*
Y139037D01*
G01X1457601Y214460D02*
Y179421D01*
G01X1485208Y201026D02*
X1592032D01*
G01X1482058D02*
X1485208D01*
G01X1453992Y149268D02*
X1454713Y148781D01*
G01X1452548Y149755D02*
X1453992Y149268D01*
G01X1449661Y149755D02*
X1452548D01*
G01X1448217Y149268D02*
X1449661Y149755D01*
G01X1447496Y148781D02*
X1448217Y149268D01*
G01X1449661Y149755D02*
X1451105Y149268D01*
G01X1454713Y155114D02*
X1455435Y155602D01*
G01Y155114D02*
X1454713D01*
G01X1455435Y155602D02*
Y155114D01*
G01X1494591Y205357D02*
X1493869Y207522D01*
G01X1496034Y203913D02*
X1494591Y205357D01*
G01X1498200Y203192D02*
X1496034Y203913D01*
G01X1500365D02*
X1498200Y203192D01*
G01X1501809Y205357D02*
X1500365Y203913D01*
G01X1502531Y207522D02*
X1501809Y205357D01*
G01Y209688D02*
X1502531Y207522D01*
G01X1500365Y211131D02*
X1501809Y209688D01*
G01X1498200Y211853D02*
X1500365Y211131D01*
G01X1496034D02*
X1498200Y211853D01*
G01X1494591Y209688D02*
X1496034Y211131D01*
G01X1493869Y207522D02*
X1494591Y209688D01*
G01X1454713Y172167D02*
X1455435Y171192D01*
G01X1453992Y172654D02*
X1454713Y172167D01*
G01X1452548Y173141D02*
X1453992Y172654D01*
G01X1449661Y173141D02*
X1452548D01*
G01X1448217Y172654D02*
X1449661Y173141D01*
G01X1447496Y172167D02*
X1448217Y172654D01*
G01X1446774Y171192D02*
X1447496Y172167D01*
G01Y170218D02*
X1446774Y171192D01*
G01X1448217Y169731D02*
X1447496Y170218D01*
G01X1449661Y169243D02*
X1448217Y169731D01*
G01X1452548Y169243D02*
X1449661D01*
G01X1453992Y169731D02*
X1452548Y169243D01*
G01X1454713Y170218D02*
X1453992Y169731D01*
G01X1455435Y171192D02*
X1454713Y170218D01*
G01X1453664Y214460D02*
G03X1457601Y218397I0J3937D01*
G01X1453664Y214460D02*
G03X1457601Y218397I0J3937D01*
G01X1494591Y201026D02*
X1501809Y214018D01*
G01X1509315Y211853D02*
Y203192D01*
G01X1457601Y218397D02*
Y591232D01*
G01Y218397D02*
Y419507D01*
G01X1446774Y163397D02*
X1455435D01*
G01X1496012Y289080D02*
X1595041D01*
G01X1492862D02*
X1496012D01*
G01X1491815Y264406D02*
X1500514D01*
G01X1489377Y264526D02*
X1491815Y264406D01*
G01X1479223Y245956D02*
X1489377Y264526D01*
G01X1510939Y244906D02*
X1511426Y244184D01*
G01X1510939D02*
Y244906D01*
G01X1511426Y244184D02*
X1510939D01*
G01X1504605Y244906D02*
X1503630Y244184D01*
G01X1505092Y245628D02*
X1504605Y244906D01*
G01X1505579Y247071D02*
X1505092Y245628D01*
G01X1505579Y249959D02*
Y247071D01*
G01X1505092Y251402D02*
X1505579Y249959D01*
G01X1504605Y252124D02*
X1505092Y251402D01*
G01X1503630Y252846D02*
X1504605Y252124D01*
G01X1502656D02*
X1503630Y252846D01*
G01X1502169Y251402D02*
X1502656Y252124D01*
G01X1501682Y249959D02*
X1502169Y251402D01*
G01X1501682Y247071D02*
Y249959D01*
G01X1502169Y245628D02*
X1501682Y247071D01*
G01X1502656Y244906D02*
X1502169Y245628D01*
G01X1503630Y244184D02*
X1502656Y244906D01*
G01X1505395Y293410D02*
X1504673Y295576D01*
G01X1506839Y291967D02*
X1505395Y293410D01*
G01X1509004Y291245D02*
X1506839Y291967D01*
G01X1511169D02*
X1509004Y291245D01*
G01X1506839Y299185D02*
X1509004Y299906D01*
G01X1505395Y297741D02*
X1506839Y299185D01*
G01X1504673Y295576D02*
X1505395Y297741D01*
G01X1510691Y272346D02*
X1510204Y271624D01*
G01X1510691Y273789D02*
Y272346D01*
G01X1510204Y274511D02*
X1510691Y273789D01*
G01X1509230Y275233D02*
X1510204Y274511D01*
G01X1508255Y275233D02*
X1509230D01*
G01X1507281Y274511D02*
X1508255Y275233D01*
G01X1506794Y273789D02*
X1507281Y274511D01*
G01X1506794Y266572D02*
X1510691D01*
G01X1507281Y268737D02*
X1506794Y266572D01*
G01X1508255Y270180D02*
X1507281Y268737D01*
G01X1510204Y271624D02*
X1508255Y270180D01*
G01X1505395Y289080D02*
X1512613Y302072D01*
G01X1475769Y359465D02*
X1690931D01*
G01X1439625D02*
X1475769D01*
G01X1485160Y362352D02*
X1485647Y361630D01*
G01X1485160D02*
Y362352D01*
G01X1485647Y361630D02*
X1485160D01*
G01X1502212Y362352D02*
X1501238Y361630D01*
G01X1502699Y363074D02*
X1502212Y362352D01*
G01X1503186Y364518D02*
X1502699Y363074D01*
G01X1503186Y367405D02*
Y364518D01*
G01X1502699Y368848D02*
X1503186Y367405D01*
G01X1502212Y369570D02*
X1502699Y368848D01*
G01X1501238Y370292D02*
X1502212Y369570D01*
G01X1500263D02*
X1501238Y370292D01*
G01X1499776Y368848D02*
X1500263Y369570D01*
G01X1499289Y367405D02*
X1499776Y368848D01*
G01X1499289Y364518D02*
Y367405D01*
G01X1499776Y363074D02*
X1499289Y364518D01*
G01X1500263Y362352D02*
X1499776Y363074D01*
G01X1501238Y361630D02*
X1500263Y362352D01*
G01X1491493Y361630D02*
X1495391D01*
G01X1491981Y363796D02*
X1491493Y361630D01*
G01X1492955Y365239D02*
X1491981Y363796D01*
G01X1494904Y366683D02*
X1492955Y365239D01*
G01X1463127Y363796D02*
X1462406Y365961D01*
G01X1464571Y362352D02*
X1463127Y363796D01*
G01X1466736Y361630D02*
X1464571Y362352D01*
G01X1468902D02*
X1466736Y361630D01*
G01X1470345Y363796D02*
X1468902Y362352D01*
G01X1471067Y365961D02*
X1470345Y363796D01*
G01Y368127D02*
X1471067Y365961D01*
G01X1468902Y369570D02*
X1470345Y368127D01*
G01X1466736Y370292D02*
X1468902Y369570D01*
G01X1464571D02*
X1466736Y370292D01*
G01X1463127Y368127D02*
X1464571Y369570D01*
G01X1462406Y365961D02*
X1463127Y368127D01*
G01X1476877Y362352D02*
X1476390Y363074D01*
G01X1477852Y361630D02*
X1476877Y362352D01*
G01X1478826D02*
X1477852Y361630D01*
G01X1479313Y363074D02*
X1478826Y362352D01*
G01X1479801Y364518D02*
X1479313Y363074D01*
G01X1479801Y367405D02*
Y364518D01*
G01X1479313Y368848D02*
X1479801Y367405D01*
G01X1478826Y369570D02*
X1479313Y368848D01*
G01X1477852Y370292D02*
X1478826Y369570D01*
G01X1476877D02*
X1477852Y370292D01*
G01X1476390Y368848D02*
X1476877Y369570D01*
G01X1475903Y367405D02*
X1476390Y368848D01*
G01Y365961D02*
X1475903Y367405D01*
G01X1477852Y365239D02*
X1476390Y365961D01*
G01X1479313D02*
X1477852Y365239D01*
G01X1479801Y367405D02*
X1479313Y365961D01*
G01X1495391Y367405D02*
X1494904Y366683D01*
G01X1495391Y368848D02*
Y367405D01*
G01X1494904Y369570D02*
X1495391Y368848D01*
G01X1493929Y370292D02*
X1494904Y369570D01*
G01X1492955Y370292D02*
X1493929D01*
G01X1491981Y369570D02*
X1492955Y370292D01*
G01X1491493Y368848D02*
X1491981Y369570D01*
G01X1508546Y363074D02*
X1509520Y361630D01*
G01X1508058Y365239D02*
X1508546Y363074D01*
G01X1508058Y366683D02*
Y365239D01*
G01X1508546Y368848D02*
X1508058Y366683D01*
G01X1509520Y370292D02*
X1508546Y368848D01*
G01X1509004Y299906D02*
X1511169Y299185D01*
G01X1463127Y359465D02*
X1470345Y372457D01*
G01X1459777Y423028D02*
G03X1457601Y419507I1761J-3521D01*
G01X1463299Y424789D02*
G03X1465475Y428310I-1761J3521D01*
G01Y447066D02*
G03X1463299Y450587I-3937J0D01*
G01X1459777Y423028D02*
G03X1457601Y419507I1761J-3521D01*
G01X1463299Y424789D02*
G03X1465475Y428310I-1761J3521D01*
G01Y447066D02*
G03X1463299Y450587I-3937J0D01*
G01X1463383Y435365D02*
X1463467Y434873D01*
G01X1462964Y435283D02*
X1463048Y434873D01*
G01X1460032Y434463D02*
X1459949Y434873D01*
G01X1465475Y428310D02*
Y447066D01*
G01Y428310D02*
Y447066D01*
G01X1463467Y441763D02*
Y442255D01*
G01Y438974D02*
Y439466D01*
G01Y432331D02*
Y432741D01*
G01Y431018D02*
Y431428D01*
G01Y429706D02*
Y430116D01*
G01Y428640D02*
Y429050D01*
G01Y427327D02*
Y427737D01*
G01Y426015D02*
Y426425D01*
G01X1459613Y434381D02*
X1459530Y434873D01*
G01X1460786Y431592D02*
X1460870Y431346D01*
G01X1460786Y430280D02*
X1460870Y430034D01*
G01X1460786Y427902D02*
X1460870Y427655D01*
G01X1460786Y426589D02*
X1460870Y426343D01*
G01X1461205Y431592D02*
X1461121Y431757D01*
G01X1461205Y430280D02*
X1461121Y430444D01*
G01X1461205Y427902D02*
X1461121Y428066D01*
G01X1461205Y426589D02*
X1461121Y426753D01*
G01X1463132Y435776D02*
X1463383Y435365D01*
G01X1459865Y433971D02*
X1459613Y434381D01*
G01X1462797Y435529D02*
X1462964Y435283D01*
G01X1460200Y434217D02*
X1460032Y434463D01*
G01X1462880Y436022D02*
X1463132Y435776D01*
G01X1463048Y434873D02*
X1462964Y434463D01*
G01X1459949Y434873D02*
X1460032Y435283D01*
G01X1463467Y434873D02*
X1463383Y434381D01*
G01X1459530Y434873D02*
X1459613Y435365D01*
G01X1462126Y437006D02*
Y438318D01*
G01X1461791D02*
Y437006D01*
G01X1461624Y439466D02*
Y441763D01*
G01X1461121Y437006D02*
Y438318D01*
G01Y431757D02*
Y431921D01*
G01Y430444D02*
Y430690D01*
G01Y428066D02*
Y428230D01*
G01Y426753D02*
Y426999D01*
G01Y441763D02*
Y439466D01*
G01X1460786Y426917D02*
Y426589D01*
G01Y428230D02*
Y427902D01*
G01Y429050D02*
Y428640D01*
G01Y430608D02*
Y430280D01*
G01Y431921D02*
Y431592D01*
G01Y432741D02*
Y432331D01*
G01Y438318D02*
Y437006D01*
G01X1459530Y439466D02*
Y438974D01*
G01Y442255D02*
Y441763D01*
G01X1460116Y433725D02*
X1459865Y433971D01*
G01X1461289Y431510D02*
X1461205Y431592D01*
G01X1460870Y431346D02*
X1461121Y431100D01*
G01X1461289Y430198D02*
X1461205Y430280D01*
G01X1460870Y430034D02*
X1461038Y429870D01*
G01X1461289Y427819D02*
X1461205Y427902D01*
G01X1460870Y427655D02*
X1461121Y427409D01*
G01X1461289Y426507D02*
X1461205Y426589D01*
G01X1460870Y426343D02*
X1461038Y426179D01*
G01X1459777Y452348D02*
X1463298Y450587D01*
G01D02*
X1459777Y452348D01*
G01X1461121Y426999D02*
X1461205Y427163D01*
G01X1461121Y430690D02*
X1461205Y430854D01*
G01X1460870Y427163D02*
X1460786Y426917D01*
G01X1461121Y428230D02*
X1461205Y428476D01*
G01X1460870D02*
X1460786Y428230D01*
G01X1460870Y430854D02*
X1460786Y430608D01*
G01X1461121Y431921D02*
X1461205Y432167D01*
G01X1460870D02*
X1460786Y431921D01*
G01X1462294Y435858D02*
X1462797Y435529D01*
G01X1460702Y433889D02*
X1460200Y434217D01*
G01X1462545Y436186D02*
X1462880Y436022D01*
G01X1460451Y433561D02*
X1460116Y433725D01*
G01X1462964Y434463D02*
X1462797Y434217D01*
G01X1460032Y435283D02*
X1460200Y435529D01*
G01X1463383Y434381D02*
X1463132Y433971D01*
G01X1459613Y435365D02*
X1459865Y435776D01*
G01X1461456Y431428D02*
X1461289Y431510D01*
G01X1461456Y430116D02*
X1461289Y430198D01*
G01X1461456Y427737D02*
X1461289Y427819D01*
G01X1461456Y426425D02*
X1461289Y426507D01*
G01X1461038Y429870D02*
X1461456Y429706D01*
G01X1461038Y426179D02*
X1461456Y426015D01*
G01X1462294Y436268D02*
X1462545Y436186D01*
G01X1460702Y433479D02*
X1460451Y433561D01*
G01X1461205Y427163D02*
X1461289Y427245D01*
G01X1461121Y427409D02*
X1460870Y427163D01*
G01X1461205Y428476D02*
X1461373Y428640D01*
G01X1461038D02*
X1460870Y428476D01*
G01X1461205Y430854D02*
X1461289Y430936D01*
G01X1461121Y431100D02*
X1460870Y430854D01*
G01X1463132Y433971D02*
X1462880Y433725D01*
G01X1461205Y432167D02*
X1461373Y432331D01*
G01X1461038D02*
X1460870Y432167D01*
G01X1461875Y436350D02*
X1462294Y436268D01*
G01X1461121Y433397D02*
X1460702Y433479D01*
G01X1461791Y435940D02*
X1462294Y435858D01*
G01X1461205Y433807D02*
X1460702Y433889D01*
G01X1459865Y435776D02*
X1460116Y436022D01*
G01X1463467Y442255D02*
X1459530D01*
G01X1461624Y441763D02*
X1463467D01*
G01X1459530D02*
X1461121D01*
G01Y439466D02*
X1459530D01*
G01X1463467D02*
X1461624D01*
G01X1459530Y438974D02*
X1463467D01*
G01X1461121Y438318D02*
X1460786D01*
G01X1462126D02*
X1461791D01*
G01X1461289Y427245D02*
X1461456Y427327D01*
G01X1463298Y424789D02*
X1459777Y423028D01*
G01X1463298Y424789D02*
X1459777Y423028D01*
G01X1462797Y434217D02*
X1462294Y433889D01*
G01X1460200Y435529D02*
X1460702Y435858D01*
G01X1461791Y437006D02*
X1462126D01*
G01X1460786D02*
X1461121D01*
G01Y436350D02*
X1461875D01*
G01X1461205Y435940D02*
X1461791D01*
G01Y433807D02*
X1461205D01*
G01X1461875Y433397D02*
X1461121D01*
G01X1463467Y432741D02*
X1460786D01*
G01X1461373Y432331D02*
X1463467D01*
G01X1460786D02*
X1461038D01*
G01X1463467Y431428D02*
X1461456D01*
G01Y431018D02*
X1463467D01*
G01Y430116D02*
X1461456D01*
G01Y429706D02*
X1463467D01*
G01Y429050D02*
X1460786D01*
G01X1461373Y428640D02*
X1463467D01*
G01X1460786D02*
X1461038D01*
G01X1463467Y427737D02*
X1461456D01*
G01Y427327D02*
X1463467D01*
G01Y426425D02*
X1461456D01*
G01Y426015D02*
X1463467D01*
G01X1461289Y430936D02*
X1461456Y431018D01*
G01X1462880Y433725D02*
X1462545Y433561D01*
G01X1460116Y436022D02*
X1460451Y436186D01*
G01X1460702Y435858D02*
X1461205Y435940D01*
G01X1462294Y433889D02*
X1461791Y433807D01*
G01X1460702Y436268D02*
X1461121Y436350D01*
G01X1462294Y433479D02*
X1461875Y433397D01*
G01X1462545Y433561D02*
X1462294Y433479D01*
G01X1460451Y436186D02*
X1460702Y436268D01*
G01X1457601Y455869D02*
G03X1459777Y452348I3937J0D01*
G01X1457601Y455869D02*
G03X1459777Y452348I3937J0D01*
G01X1457601Y455869D02*
Y591232D01*
G01D02*
G03X1453664Y595169I-3937J0D01*
G01X1457601Y591232D02*
G03X1453664Y595169I-3937J0D01*
G01X1506957Y1006410D02*
Y989087D01*
G01X1516623Y203913D02*
X1517111Y203192D01*
G01X1516623D02*
Y203913D01*
G01X1517111Y203192D02*
X1516623D01*
G01X1531240Y203913D02*
X1530752Y204635D01*
G01X1532214Y203192D02*
X1531240Y203913D01*
G01X1533188Y203192D02*
X1532214D01*
G01X1534163Y203913D02*
X1533188Y203192D01*
G01X1534650Y204635D02*
X1534163Y203913D01*
G01X1535137Y206079D02*
X1534650Y204635D01*
G01Y207522D02*
X1535137Y206079D01*
G01X1534163Y208244D02*
X1534650Y207522D01*
G01X1533188Y208966D02*
X1534163Y208244D01*
G01X1532214Y208966D02*
X1533188D01*
G01X1531240Y208244D02*
X1532214Y208966D01*
G01X1531727Y211853D02*
X1531240Y208244D01*
G01X1534650Y211853D02*
X1531727D01*
G01X1527342Y206079D02*
Y205357D01*
G01X1526367Y207522D02*
X1527342Y206079D01*
G01X1579960Y204635D02*
X1578986Y203192D01*
G01X1580447Y206801D02*
X1579960Y204635D01*
G01X1580447Y208244D02*
Y206801D01*
G01X1579960Y210410D02*
X1580447Y208244D01*
G01X1578986Y211853D02*
X1579960Y210410D01*
G01X1550241Y203192D02*
Y211853D01*
G01X1546343D02*
X1550241Y203192D01*
G01X1546343D02*
Y211853D01*
G01X1556574Y207522D02*
X1554138D01*
G01X1557549Y208244D02*
X1556574Y207522D01*
G01X1558036Y208966D02*
X1557549Y208244D01*
G01X1558036Y210410D02*
Y208966D01*
G01X1557549Y211131D02*
X1558036Y210410D01*
G01X1556574Y211853D02*
X1557549Y211131D01*
G01X1554138Y211853D02*
X1556574D01*
G01X1554138Y203192D02*
Y211853D01*
G01X1540009Y204635D02*
X1540984Y203192D01*
G01X1539522Y206801D02*
X1540009Y204635D01*
G01X1539522Y208244D02*
Y206801D01*
G01X1540009Y210410D02*
X1539522Y208244D01*
G01X1540984Y211853D02*
X1540009Y210410D01*
G01X1523444Y203913D02*
X1522957Y204635D01*
G01X1524419Y203192D02*
X1523444Y203913D01*
G01X1525393Y203192D02*
X1524419D01*
G01X1526367Y203913D02*
X1525393Y203192D01*
G01X1527342Y205357D02*
X1526367Y203913D01*
G01X1525393Y208244D02*
X1526367Y207522D01*
G01Y208966D02*
X1525393Y208244D01*
G01X1526855Y209688D02*
X1526367Y208966D01*
G01X1526855Y210410D02*
Y209688D01*
G01X1526367Y211131D02*
X1526855Y210410D01*
G01X1525393Y211853D02*
X1526367Y211131D01*
G01X1524419Y211853D02*
X1525393D01*
G01X1523444Y211131D02*
X1524419Y211853D01*
G01X1573626D02*
Y203192D01*
G01X1569729Y211853D02*
Y203192D01*
G01X1563882Y211853D02*
Y203192D01*
G01X1561446Y211853D02*
X1566318D01*
G01X1524419Y208244D02*
X1525393D01*
G01X1569729Y207522D02*
X1573626D01*
G01X1531641Y267293D02*
X1532128Y266572D01*
G01X1531641D02*
Y267293D01*
G01X1532128Y266572D02*
X1531641D01*
G01X1527428Y291967D02*
X1527915Y291245D01*
G01X1527428D02*
Y291967D01*
G01X1527915Y291245D02*
X1527428D01*
G01X1518658Y291967D02*
X1518171Y292688D01*
G01X1519632Y291245D02*
X1518658Y291967D01*
G01X1520607Y291245D02*
X1519632D01*
G01X1521581Y291967D02*
X1520607Y291245D01*
G01X1522068Y292688D02*
X1521581Y291967D01*
G01X1522556Y294132D02*
X1522068Y292688D01*
G01Y295576D02*
X1522556Y294132D01*
G01X1521581Y296297D02*
X1522068Y295576D01*
G01X1520607Y297019D02*
X1521581Y296297D01*
G01X1519632Y297019D02*
X1520607D01*
G01X1518658Y296297D02*
X1519632Y297019D01*
G01X1519145Y299906D02*
X1518658Y296297D01*
G01X1527991Y244906D02*
X1527016Y244184D01*
G01X1528478Y245628D02*
X1527991Y244906D01*
G01X1528965Y247071D02*
X1528478Y245628D01*
G01X1528965Y249959D02*
Y247071D01*
G01X1528478Y251402D02*
X1528965Y249959D01*
G01X1527991Y252124D02*
X1528478Y251402D01*
G01X1527016Y252846D02*
X1527991Y252124D01*
G01X1526042D02*
X1527016Y252846D01*
G01X1525555Y251402D02*
X1526042Y252124D01*
G01X1525067Y249959D02*
X1525555Y251402D01*
G01X1525067Y247071D02*
Y249959D01*
G01X1525555Y245628D02*
X1525067Y247071D01*
G01X1526042Y244906D02*
X1525555Y245628D01*
G01X1527016Y244184D02*
X1526042Y244906D01*
G01X1548693Y267293D02*
X1547719Y266572D01*
G01X1549180Y268015D02*
X1548693Y267293D01*
G01X1549668Y269459D02*
X1549180Y268015D01*
G01X1549668Y272346D02*
Y269459D01*
G01X1549180Y273789D02*
X1549668Y272346D01*
G01X1548693Y274511D02*
X1549180Y273789D01*
G01X1547719Y275233D02*
X1548693Y274511D01*
G01X1546744D02*
X1547719Y275233D01*
G01X1546257Y273789D02*
X1546744Y274511D01*
G01X1545770Y272346D02*
X1546257Y273789D01*
G01X1545770Y269459D02*
Y272346D01*
G01X1546257Y268015D02*
X1545770Y269459D01*
G01X1546744Y267293D02*
X1546257Y268015D01*
G01X1547719Y266572D02*
X1546744Y267293D01*
G01X1544480Y291967D02*
X1543505Y291245D01*
G01X1544967Y292688D02*
X1544480Y291967D01*
G01X1545454Y294132D02*
X1544967Y292688D01*
G01X1545454Y297019D02*
Y294132D01*
G01X1544967Y298463D02*
X1545454Y297019D01*
G01X1544480Y299185D02*
X1544967Y298463D01*
G01X1543505Y299906D02*
X1544480Y299185D01*
G01X1542531D02*
X1543505Y299906D01*
G01X1542044Y298463D02*
X1542531Y299185D01*
G01X1541556Y297019D02*
X1542044Y298463D01*
G01X1541556Y294132D02*
Y297019D01*
G01X1542044Y292688D02*
X1541556Y294132D01*
G01X1542531Y291967D02*
X1542044Y292688D01*
G01X1543505Y291245D02*
X1542531Y291967D01*
G01X1521657Y247071D02*
Y246350D01*
G01X1520683Y248515D02*
X1521657Y247071D01*
G01X1542359Y269459D02*
Y268737D01*
G01X1541385Y270902D02*
X1542359Y269459D01*
G01X1582969Y292688D02*
X1581995Y291245D01*
G01X1583456Y294854D02*
X1582969Y292688D01*
G01X1583456Y296297D02*
Y294854D01*
G01X1582969Y298463D02*
X1583456Y296297D01*
G01X1581995Y299906D02*
X1582969Y298463D01*
G01X1512613Y293410D02*
X1511169Y291967D01*
G01X1513335Y295576D02*
X1512613Y293410D01*
G01Y297741D02*
X1513335Y295576D01*
G01X1511169Y299185D02*
X1512613Y297741D01*
G01X1559583Y295576D02*
X1557147D01*
G01X1560558Y296297D02*
X1559583Y295576D01*
G01X1561045Y297019D02*
X1560558Y296297D01*
G01X1561045Y298463D02*
Y297019D01*
G01X1560558Y299185D02*
X1561045Y298463D01*
G01X1559583Y299906D02*
X1560558Y299185D01*
G01X1557147Y291245D02*
Y299906D01*
G01X1536684Y299185D02*
X1537172Y298463D01*
G01X1535710Y299906D02*
X1536684Y299185D01*
G01X1534736D02*
X1535710Y299906D01*
G01X1534248Y298463D02*
X1534736Y299185D01*
G01X1533761Y297019D02*
X1534248Y298463D01*
G01X1533761Y294132D02*
Y297019D01*
G01X1534248Y292688D02*
X1533761Y294132D01*
G01X1534736Y291967D02*
X1534248Y292688D01*
G01X1535710Y291245D02*
X1534736Y291967D01*
G01X1536684D02*
X1535710Y291245D01*
G01X1537172Y292688D02*
X1536684Y291967D01*
G01X1537659Y294132D02*
X1537172Y292688D01*
G01Y295576D02*
X1537659Y294132D01*
G01X1535710Y296297D02*
X1537172Y295576D01*
G01X1534248D02*
X1535710Y296297D01*
G01X1533761Y294132D02*
X1534248Y295576D01*
G01X1550813Y292688D02*
X1551788Y291245D01*
G01X1550326Y294854D02*
X1550813Y292688D01*
G01X1550326Y296297D02*
Y294854D01*
G01X1550813Y298463D02*
X1550326Y296297D01*
G01X1551788Y299906D02*
X1550813Y298463D01*
G01X1517759Y244906D02*
X1517272Y245628D01*
G01X1518734Y244184D02*
X1517759Y244906D01*
G01X1519708Y244184D02*
X1518734D01*
G01X1520683Y244906D02*
X1519708Y244184D01*
G01X1521657Y246350D02*
X1520683Y244906D01*
G01X1538462Y267293D02*
X1537975Y268015D01*
G01X1539436Y266572D02*
X1538462Y267293D01*
G01X1540411Y266572D02*
X1539436D01*
G01X1541385Y267293D02*
X1540411Y266572D01*
G01X1542359Y268737D02*
X1541385Y267293D01*
G01X1540411Y271624D02*
X1541385Y270902D01*
G01Y272346D02*
X1540411Y271624D01*
G01X1541872Y273068D02*
X1541385Y272346D01*
G01X1541872Y273789D02*
Y273068D01*
G01X1541385Y274511D02*
X1541872Y273789D01*
G01X1540411Y275233D02*
X1541385Y274511D01*
G01X1539436Y275233D02*
X1540411D01*
G01X1538462Y274511D02*
X1539436Y275233D01*
G01X1519708Y249237D02*
X1520683Y248515D01*
G01Y249959D02*
X1519708Y249237D01*
G01X1521170Y250680D02*
X1520683Y249959D01*
G01X1521170Y251402D02*
Y250680D01*
G01X1520683Y252124D02*
X1521170Y251402D01*
G01X1519708Y252846D02*
X1520683Y252124D01*
G01X1518734Y252846D02*
X1519708D01*
G01X1517759Y252124D02*
X1518734Y252846D01*
G01X1576635Y299906D02*
Y291245D01*
G01X1572738Y299906D02*
Y291245D01*
G01X1566891Y299906D02*
Y291245D01*
G01X1524333Y275233D02*
Y266572D01*
G01X1572738Y295576D02*
X1576635D01*
G01X1539436Y271624D02*
X1540411D01*
G01X1515076Y270902D02*
X1517999D01*
G01X1518734Y249237D02*
X1519708D01*
G01X1522068Y299906D02*
X1519145D01*
G01X1569446Y370292D02*
X1573344D01*
G01X1569446Y361630D02*
Y370292D01*
G01X1573344Y361630D02*
X1569446D01*
G01X1527547Y365961D02*
X1527059Y363796D01*
G01Y368127D02*
X1527547Y365961D01*
G01X1526085Y369570D02*
X1527059Y368127D01*
G01X1518777Y361630D02*
Y370292D01*
G01X1514879D02*
X1518777Y361630D01*
G01X1514879D02*
Y370292D01*
G01X1525111D02*
X1526085Y369570D01*
G01X1524136Y370292D02*
X1525111D01*
G01X1523162Y369570D02*
X1524136Y370292D01*
G01X1522187Y368127D02*
X1523162Y369570D01*
G01Y362352D02*
X1522187Y363796D01*
G01X1524136Y361630D02*
X1523162Y362352D01*
G01X1525111Y361630D02*
X1524136D01*
G01X1526085Y362352D02*
X1525111Y361630D01*
G01X1527059Y363796D02*
X1526085Y362352D01*
G01X1521700Y365961D02*
X1522187Y368127D01*
G01Y363796D02*
X1521700Y365961D01*
G01X1557147Y299906D02*
X1559583D01*
G01X1548496Y365961D02*
X1546060D01*
G01X1549471Y366683D02*
X1548496Y365961D01*
G01X1549958Y367405D02*
X1549471Y366683D01*
G01X1549958Y368848D02*
Y367405D01*
G01X1549471Y369570D02*
X1549958Y368848D01*
G01X1548496Y370292D02*
X1549471Y369570D01*
G01X1546060Y370292D02*
X1548496D01*
G01X1546060Y361630D02*
Y370292D01*
G01X1555805D02*
X1558241Y361630D01*
G01X1553369D02*
X1555805Y370292D01*
G01X1584550Y361630D02*
X1586986Y370292D01*
G01X1565061Y369570D02*
X1565549Y368848D01*
G01X1564087Y370292D02*
X1565061Y369570D01*
G01X1563113Y370292D02*
X1564087D01*
G01X1562138Y369570D02*
X1563113Y370292D01*
G01X1561164Y368127D02*
X1562138Y369570D01*
G01Y362352D02*
X1561164Y363796D01*
G01X1563113Y361630D02*
X1562138Y362352D01*
G01X1564087Y361630D02*
X1563113D01*
G01X1565061Y362352D02*
X1564087Y361630D01*
G01X1565549Y363074D02*
X1565061Y362352D01*
G01X1560677Y365961D02*
X1561164Y368127D01*
G01Y363796D02*
X1560677Y365961D01*
G01X1548496D02*
X1549958Y361630D01*
G01X1540214Y370292D02*
Y361630D01*
G01X1537778Y370292D02*
X1542650D01*
G01X1569446Y365961D02*
X1571882D01*
G01X1585524Y364518D02*
X1588447D01*
G01X1554343D02*
X1557266D01*
G01X1564455Y299906D02*
X1569327D01*
G01X1616218Y361630D02*
X1620115D01*
G01X1616218Y370292D02*
Y361630D01*
G01X1624013D02*
X1627911D01*
G01X1624013Y370292D02*
Y361630D01*
G01X1639604D02*
X1643501D01*
G01X1639604Y370292D02*
Y361630D01*
G01X1586986Y370292D02*
X1589422Y361630D01*
G01X1610371Y370292D02*
X1612807Y361630D01*
G01X1607935D02*
X1610371Y370292D01*
G01X1649348D02*
X1651784Y361630D01*
G01X1646912D02*
X1649348Y370292D01*
G01X1657143Y365961D02*
Y361630D01*
G01X1655194Y370292D02*
X1657143Y365961D01*
G01D02*
X1659092Y370292D01*
G01X1594781D02*
Y361630D01*
G01X1592345Y370292D02*
X1597217D01*
G01X1647886Y364518D02*
X1650809D01*
G01X1608910D02*
X1611833D01*
G01X1719319Y-338472D02*
Y-82686D01*
G01X1725855Y989087D02*
Y-354220D01*
G01Y-174693D02*
X1743177D01*
G01X1725855Y61528D02*
X1743177D01*
G01X1725855Y297748D02*
X1743177D01*
G01X1662990Y370292D02*
X1666887D01*
G01X1662990Y361630D02*
Y370292D01*
G01X1666887Y361630D02*
X1662990D01*
G01X1679067Y362352D02*
X1678093Y363796D01*
G01X1680042Y361630D02*
X1679067Y362352D01*
G01X1681016Y361630D02*
X1680042D01*
G01X1681991Y362352D02*
X1681016Y361630D01*
G01X1682478Y363074D02*
X1681991Y362352D01*
G01X1682478Y364518D02*
Y363074D01*
G01X1681991Y365239D02*
X1682478Y364518D01*
G01X1679067Y367405D02*
X1681991Y365239D01*
G01X1673221Y365961D02*
X1670785D01*
G01X1674195Y366683D02*
X1673221Y365961D01*
G01X1674682Y367405D02*
X1674195Y366683D01*
G01X1674682Y368848D02*
Y367405D01*
G01X1674195Y369570D02*
X1674682Y368848D01*
G01X1673221Y370292D02*
X1674195Y369570D01*
G01X1670785Y370292D02*
X1673221D01*
G01X1670785Y361630D02*
Y370292D01*
G01X1678580Y368127D02*
X1679067Y367405D01*
G01X1678580Y368848D02*
Y368127D01*
G01X1679067Y369570D02*
X1678580Y368848D01*
G01X1680042Y370292D02*
X1679067Y369570D01*
G01X1681016Y370292D02*
X1680042D01*
G01X1681991Y369570D02*
X1681016Y370292D01*
G01X1682478Y368848D02*
X1681991Y369570D01*
G01X1688811Y363074D02*
X1687837Y361630D01*
G01X1689299Y365239D02*
X1688811Y363074D01*
G01X1689299Y366683D02*
Y365239D01*
G01X1688811Y368848D02*
X1689299Y366683D01*
G01X1687837Y370292D02*
X1688811Y368848D01*
G01X1673221Y365961D02*
X1674682Y361630D01*
G01X1662990Y365961D02*
X1665426D01*
G01X1725855Y533969D02*
X1743177D01*
G01X1725855Y770189D02*
X1743177D01*
G01Y1006410D02*
Y-371543D01*
M02*
